P  JOB   D:/<user>/9048_F0T_Management_Board_D_brd_V04_1213_1625.brd               
P  CODE  00                                                                     
P  UNITS CUST 0                                                                 
P  TITLE D:/<user>/9048_F0T_Management_Board_D_brd_V04_1213_1625.brd               
P  NUM   001                                                                    
P  REV   A                                                                      
P  VER IPC-D-356A                                                               
C                                                                               
C  IPC-D-356 Ouptut File from Allegro                                           
C  IPC File Date: Tue Dec 13 16:32:29 2022                                      
C                                                                               
C                                                                               
C  Board File:             9048_F0T_Management_Board_D_brd_V04_1213_1625.brd    
C  Design Rule Status:     UP TO DATE                                           
C  Unit of Measure:        mils                                                 
C  Decimal Place Accuracy: 2                                                    
C  Number of etch Layers:  12                                                   
C  Board Thickness(mils):  63.000000                                            
C  Drawing Extents(mils):  -2500000  -2500000  5500000  5500000                 
C                                                                               
C                                                                               
C  BOARD LAYER INFORMATION                                                      
C                                                                               
C     Layer      Layer            Layer             Film  Layer                 
C     Name       Material         Type              Type  Number                
C  ---------------------------------------------------------                    
C  TOP           COPPER           CONDUCTOR         POS     1                   
C  GND           COPPER           PLANE             NEG     2                   
C  IN1           COPPER           CONDUCTOR         POS     3                   
C  GND1          COPPER           PLANE             NEG     4                   
C  IN2           COPPER           CONDUCTOR         POS     5                   
C  VCC           COPPER           PLANE             NEG     6                   
C  VCC1          COPPER           PLANE             NEG     7                   
C  IN3           COPPER           CONDUCTOR         POS     8                   
C  GND2          COPPER           PLANE             NEG     9                   
C  IN4           COPPER           CONDUCTOR         POS    10                   
C  GND3          COPPER           PLANE             NEG    11                   
C  BOTTOM        COPPER           CONDUCTOR         POS    12                   
C                                                                               
C                                                                               
C  PADSTACK INFORMATION                                                         
C                                                                               
C     Padstack          First     Last                                          
C     Name              Layer     Layer     Width     Height                    
C  ---------------------------------------------------------                    
C  TP28B                BOTTOM    BOTTOM         7502      7500                 
C  SMD18X20             TOP       TOP            2200      2400                 
C  S48D32_T4_0          TOP       BOTTOM         6200      6200                 
C  C41D41N              TOP       BOTTOM         7100      7100                 
C  SMD85X156_CUT_NPM    TOP       TOP            8900     16000                 
C  SMD12X20_NPM         TOP       TOP            1600      2400                 
C  C48D32_T6_0          TOP       BOTTOM         6200      6200                 
C  S48D32_T6_0          TOP       BOTTOM         6200      6200                 
C  C131D91              TOP       BOTTOM        13500     13500                 
C  S44D28_T2            TOP       BOTTOM         5800      5800                 
C  C44D28_T2            TOP       BOTTOM         5800      5800                 
C  SMD32X32             TOP       TOP            3600      3600                 
C  C48D32_T4_0          TOP       BOTTOM         6200      6200                 
C  SMD26X54             TOP       TOP            3000      5800                 
C  SMD22X24             TOP       TOP            2600      2800                 
C  SMD18X52             TOP       TOP            2200      5600                 
C  TP20B                BOTTOM    BOTTOM         7502      7500                 
C  TP26T                TOP       TOP            7502      7500                 
C  C256D126             TOP       BOTTOM        26000     26000                 
C  C178D150B315I221_NPT TOP       BOTTOM        31900     31900                 
C  OB252X315D126X189B25 TOP       BOTTOM        25600     31900                 
C  SMD24X42_PM22X40     TOP       TOP            2800      4600                 
C  C36D36N              TOP       BOTTOM         6600      6600                 
C  C67D67N_T1-96        TOP       BOTTOM         9700      9700                 
C  C48D48N_T1-96        TOP       BOTTOM         7800      7800                 
C  SMD49X110            TOP       TOP            5300     11400                 
C  SMD11X63             TOP       TOP            1500      6700                 
C  SMD20X34             TOP       TOP            2400      3800                 
C  SMD16X34             TOP       TOP            2000      3800                 
C  SPD_C125                                     12500     12500                 
C  SMD13X46             TOP       TOP            1700      5000                 
C  VT18D10B18A26_BGA    TOP       BOTTOM         7502      7500                 
C  SMD46X69             TOP       TOP            5000      7300                 
C  SMD79X79             TOP       TOP            8300      8300                 
C  SMD59X79             TOP       TOP            6300      8300                 
C  SMD25X40             TOP       TOP            2900      4400                 
C  SMD24X28             TOP       TOP            2800      3200                 
C  SMD36X115_PM30X111_C TOP       TOP            4000     11900                 
C  SMD11X26             TOP       TOP            1500      3000                 
C  SMD24X38             TOP       TOP            2800      4200                 
C  SMD16X20             TOP       TOP            2000      2400                 
C  SMD11X28             TOP       TOP            1500      3200                 
C  SMD18X23_SM18X23     TOP       TOP            1800      2300                 
C  SMD18X27_SM18X27     TOP       TOP            1800      2700                 
C  SMD10X25_SM10X25     TOP       TOP            1000      2500                 
C  C61D41               TOP       BOTTOM         7100      7100                 
C  S61D41               TOP       BOTTOM         7100      7100                 
C  SMD17X24             TOP       TOP            2100      2800                 
C  TC785CC25_O          TOP       BOTTOM         8700      8700                 
C  TC395CC25_O          TOP       BOTTOM         4800      4800                 
C  C85D67_SM85_NPM      TOP       BOTTOM         9700      9700                 
C  SMD40X109            TOP       TOP            4400     11300                 
C  SMD28X40             TOP       TOP            3200      4400                 
C  SMD14X44             TOP       TOP            1800      4800                 
C  SMD20X59             TOP       TOP            2400      6300                 
C  SMD48X71             TOP       TOP            5200      7500                 
C  SMD24X61             TOP       TOP            2800      6500                 
C  OC20X4R              TOP       TOP            1640      1640                 
C  SMD17X67             TOP       TOP            2100      7100                 
C  SMD40X56             TOP       TOP            4400      6000                 
C  R40X15               TOP       TOP            4400      1900                 
C  SH10X28_CUT_R        TOP       TOP            1384      3156                 
C  SMD10X52             TOP       TOP            1400      5600                 
C  SMD10X36             TOP       TOP            1400      4000                 
C  SH10X28_CUT_L        TOP       TOP            1384      3156                 
C  SMDC14-5             TOP       TOP            1850      1850                 
C  VIA20D10             TOP       BOTTOM         3000      3000                 
C  SMD7X32              TOP       TOP            1100      3600                 
C  SMDC39M118           TOP       TOP           11800     11800                 
C  SMD130X130           TOP       TOP           13400     13400                 
C  C238D124_NPB         TOP       BOTTOM        24200     24200                 
C  C237D134_NPB         TOP       BOTTOM        24100     24100                 
C  SH32X124_SM32X124_CU TOP       TOP            3150     12402                 
C  SMD69X105            TOP       TOP            7300     10900                 
C  SMD28X40_PM24X36     TOP       TOP            3200      4400                 
C  SMD16X36_PM14X34     TOP       TOP            2000      4000                 
C  SMD22X32_PM18X28     TOP       TOP            2600      3600                 
C  SMD24X28_PM20X24     TOP       TOP            2800      3200                 
C  SMDC16               TOP       TOP            2000      2000                 
C  SMD24X24_PM20X20     TOP       TOP            2800      2800                 
C  SH0-3X0-9_CUT        TOP       TOP            3944      1582                 
C  SMD39X48             TOP       TOP            4300      5200                 
C  SMD24X65_PM20X60_IY2 TOP       TOP            2800      6900                 
C  SMD12X79             TOP       TOP            1600      8300                 
C  SMD14X59             TOP       TOP            1800      6300                 
C  SMD46X62             TOP       TOP            5000      6600                 
C  SMD14X49             TOP       TOP            1800      5300                 
C  SMD44X54             TOP       TOP            4800      5800                 
C  SMD34X46             TOP       TOP            3800      5000                 
C  GF15X68T             TOP       TOP            1900      7200                 
C  SMD40X48             TOP       TOP            4400      5200                 
C  SMD28X32             TOP       TOP            3200      3600                 
C  SMD17X70             TOP       TOP            2100      7400                 
C  GF15X84T             TOP       TOP            1900      8800                 
C  SMD10X59             TOP       TOP            1400      6300                 
C  SMD32X36             TOP       TOP            3600      4000                 
C  SMD14X36             TOP       TOP            1800      4000                 
C  SMD16X24             TOP       TOP            2000      2800                 
C  SMD40X71             TOP       TOP            4400      7500                 
C  SMD10X28             TOP       TOP            1400      3200                 
C  SMD11X36             TOP       TOP            1500      4000                 
C  SMD17X20             TOP       TOP            2100      2400                 
C  SMD22X32             TOP       TOP            2600      3600                 
C  SMD40X50             TOP       TOP            4400      5400                 
C  SMD12X32             TOP       TOP            1600      3600                 
C  TP30T                TOP       TOP            7502      7500                 
C  SMD56X231_PM35X231_I TOP       TOP            6000     23500                 
C  C125D125N_T2-0       TOP       BOTTOM        15500     15500                 
C  RE-R_0824-2          TOP       TOP            2384      2368                 
C  SMD84-8X130          TOP       TOP            8880     13400                 
C  GF15X68B             BOTTOM    BOTTOM         1900      7200                 
C  GF15X84B             BOTTOM    BOTTOM         1900      8800                 
C  RE-L_0824-2          TOP       TOP            2384      2368                 
C  VT18D10B26_ANT26_BGA TOP       BOTTOM         7502      7500                 
C  VIA18D10A26_BGA      TOP       BOTTOM         2600      2600                 
C  VT20D10B26           TOP       BOTTOM         7502      7500                 
C  VT20D10T30           TOP       BOTTOM         7502      7500                 
C  TP26B                BOTTOM    BOTTOM         7500      7500                 
C                                                                               
C                                                                               
C  ****************************************                                     
C     Name mapping for long Signal names                                        
C  ****************************************                                     
C                                                                               
P  NNAMEm0000 REAR_AC_PWR_BMC_BTN_N                                             
P  NNAMEm0001 AC_PWR_BMC_BTN_R_N                                                
P  NNAMEm0002 AC_PWR_BMC_BTN_N                                                  
P  NNAMEm0003 ID_LED_D_P3V3_AUX                                                 
P  NNAMEm0004 REAR_AC_PWR_BTN                                                   
P  NNAMEm0005 RST_SRST_PLD_BMC_R2_N                                             
P  NNAMEm0006 RST_SRST_PLD_BMC_R1_N                                             
P  NNAMEm0007 RMII_OCP_RCLKI_R_ISO                                              
P  NNAMEm0008 RMII_OCP_RCLKI_ISO                                                
P  NNAMEm0009 REAR_AC_PWR_BTN_N                                                 
P  NNAMEm0010 PWRGD_P1V0_AUX_DELAY_R                                            
P  NNAMEm0011 HDD_LED_P5V_AUX                                                   
P  NNAMEm0012 AC_PWR_BTN_R2_N                                                   
P  NNAMEm0013 AC_PWR_BTN_R1_N                                                   
P  NNAMEm0014 FM_INTRUDER_R_N                                                   
P  NNAMEm0015 FM_TPM_PRSNT_1_R_N                                                
P  NNAMEm0016 FM_TPM_PRSNT_0_R_N                                                
P  NNAMEm0017 BMC_CPLD_GPIO_2_R2                                                
P  NNAMEm0018 BMC_CPLD_GPIO_2_R1                                                
P  NNAMEm0019 SPI_BMC_HOLD0_N                                                   
P  NNAMEm0020 SMB_BMC_MM16_R5_SDA                                               
P  NNAMEm0021 SMB_BMC_MM16_R5_SCL                                               
P  NNAMEm0022 PWRGD_P3V3_RGM_R3                                                 
P  NNAMEm0023 PWRGD_P2V5_AUX_R3                                                 
P  NNAMEm0024 PWRGD_P1V8_AUX_R3                                                 
P  NNAMEm0025 PWRGD_P1V2_AUX_R2                                                 
P  NNAMEm0026 SMB_BMC_MM16_R1_SDA                                               
P  NNAMEm0027 SMB_BMC_MM16_R1_SCL                                               
P  NNAMEm0028 H_CPU_CATERR_LVC2_R2_N                                            
P  NNAMEm0029 FM_BOARD_BMC_REV_ID2                                              
P  NNAMEm0030 FM_BOARD_BMC_REV_ID1                                              
P  NNAMEm0031 FM_BOARD_BMC_REV_ID0                                              
P  NNAMEm0032 UART_SYS_DBG_TX_R                                                 
P  NNAMEm0033 UART_SYS_DBG_TX                                                   
P  NNAMEm0034 UART_SYS_DBG_RX_R                                                 
P  NNAMEm0035 UART_SYS_DBG_RX                                                   
P  NNAMEm0036 TP_BMC_SPICS0_N                                                   
P  NNAMEm0037 SYS_BMC_PWRBTN_R1_N                                               
P  NNAMEm0038 SPA_SOUT_SW_DBG_R                                                 
P  NNAMEm0039 SPA_SOUT_SW_BUF_R                                                 
P  NNAMEm0040 SPA_SIN_SW_DBG_R                                                  
P  NNAMEm0041 SPA_SIN_SW_BUF_R                                                  
P  NNAMEm0042 RST_PFR_OVR_RTC_R                                                 
P  NNAMEm0043 IRQ_SML0_ALERT_R_N                                                
P  NNAMEm0044 GPU_WP_HW_CTRL_R_N                                                
P  NNAMEm0045 GPU_NVS_PWR_BRAKE_R_N                                             
P  NNAMEm0046 FM_PFR_DSW_PWROK_N                                                
P  NNAMEm0047 FM_PCH_BEEP_LED                                                   
P  NNAMEm0048 CLK_GEN2_BMC_RC_OE_N                                              
P  NNAMEm0049 SPI_BMC_HOLD1_N                                                   
P  NNAMEm0050 SPI_BMC_IO1_FLASH_R                                               
P  NNAMEm0051 SPI_BMC_IO0_FLASH_R                                               
P  NNAMEm0052 SPI_BMC_CS1_FLASH_R_N                                             
P  NNAMEm0053 SPI_BMC_CS0_FLASH_R_N                                             
P  NNAMEm0054 SPI_BMC_CLK_FLASH_R                                               
P  NNAMEm0055 FLASH_LATCH_Q_N_R1                                                
P  NNAMEm0056 FLASH_LATCH_Q_N_R                                                 
P  NNAMEm0057 SPI_BMC_BT_WP1_N_R                                                
P  NNAMEm0058 SPI_BMC_BT_WP0_N_R                                                
P  NNAMEm0059 FM_FLASH_LATCH_N                                                  
P  NNAMEm0060 FLASH_WP_STATUS                                                   
P  NNAMEm0061 FLASH_R_WP_STATUS                                                 
P  NNAMEm0062 FLASH_LATCH_Q_N_R2                                                
P  NNAMEm0063 PWRGD_P3V3_RGM_R2                                                 
P  NNAMEm0064 PWRGD_P1V8_AUX_R2                                                 
P  NNAMEm0065 SMB_BMC_MM2_SCL_R1                                                
P  NNAMEm0066 SW_P3V3_AUX_BST_R                                                 
P  NNAMEm0067 PU_BMC_FWSPIABR_N_R                                               
P  NNAMEm0068 SMB_BMC_MM16_R4_SDA                                               
P  NNAMEm0069 SMB_BMC_MM16_R4_SCL                                               
P  NNAMEm0070 ESPI_HOST_LPC_BMC_LFRAME_N_R                                      
P  NNAMEm0071 ESPI_HOST_LPC_BMC_CLK_R                                           
P  NNAMEm0072 SMB_BMC_ALERT16_R_N                                               
P  NNAMEm0073 UART_BIC_GF_TXD                                                   
P  NNAMEm0074 UART_BIC_GF_RXD                                                   
P  NNAMEm0075 UART_BIC_DBG_TX_R                                                 
P  NNAMEm0076 UART_BIC_DBG_TX                                                   
P  NNAMEm0077 UART_BIC_DBG_RX_R                                                 
P  NNAMEm0078 UART_BIC_DBG_RX                                                   
P  NNAMEm0079 UART_6_BMC_TXD_R                                                  
P  NNAMEm0080 UART_6_BMC_RXD_R                                                  
P  NNAMEm0081 TP_BMC_SPICS2_N                                                   
P  NNAMEm0082 SPI_BMC_TPM_MOSI_R1                                               
P  NNAMEm0083 SPI_BMC_TPM_MOSI                                                  
P  NNAMEm0084 SPI_BMC_TPM_MISO                                                  
P  NNAMEm0085 SPI_BMC_TPM_CLK                                                   
P  NNAMEm0086 SMB_TMP421_BMC_MM2_SDA                                            
P  NNAMEm0087 SMB_TMP421_BMC_MM2_SCL                                            
P  NNAMEm0088 PWR_LED_P5V_AUX                                                   
P  NNAMEm0089 P2E_PCH_TX_C_DP                                                   
P  NNAMEm0090 P2E_PCH_TX_C_DN                                                   
P  NNAMEm0091 P2E_GPU_TX_C_DP                                                   
P  NNAMEm0092 P2E_GPU_TX_C_DN                                                   
P  NNAMEm0093 JTAG_SCM_PLD_R_JTAGEN                                             
P  NNAMEm0094 FM_UARTSW_MSB_R_N                                                 
P  NNAMEm0095 FM_UARTSW_MSB_R1_N                                                
P  NNAMEm0096 FM_UARTSW_MSB_N                                                   
P  NNAMEm0097 FM_UARTSW_LSB_R_N                                                 
P  NNAMEm0098 FM_UARTSW_LSB_R1_N                                                
P  NNAMEm0099 FM_UARTSW_LSB_N                                                   
P  NNAMEm0100 NC_FM_PFR_UPDATE_N                                                
P  NNAMEm0101 NC_FM_PFR_NO_SERVICE_ACT_N                                        
P  NNAMEm0102 FM_BMC_UARTSW_MSB_N                                               
P  NNAMEm0103 FM_BMC_UARTSW_LSB_N                                               
P  NNAMEm0104 FM_BIC_DEBUG_SW_N                                                 
P  NNAMEm0105 CLK_BUF1_GPU_FPGA_OE_R_N                                          
P  NNAMEm0106 CLK_100M_PCH_DP                                                   
P  NNAMEm0107 CLK_100M_PCH_DN                                                   
P  NNAMEm0108 CLK_100M_GPU_DP                                                   
P  NNAMEm0109 CLK_100M_GPU_DN                                                   
P  NNAMEm0110 BMC_ID_BEEP_SEL                                                   
P  NNAMEm0111 RST_SPI_FLASH_BUF_R3_N                                            
P  NNAMEm0112 IRQ_PCH_SCI_WHEA_N                                                
P  NNAMEm0113 IRQ_PCH_TPM_SPI_N                                                 
P  NNAMEm0114 UART_BMC_5_TXD_BUF1_R                                             
P  NNAMEm0115 UART_BMC_5_TXD_BUF1                                               
P  NNAMEm0116 UART_BMC_5_RXD_BUF1_SW                                            
P  NNAMEm0117 UART_BMC_5_RXD_BUF1_R                                             
P  NNAMEm0118 UART_BMC_5_RXD_BUF1                                               
P  NNAMEm0119 RST_SPI_FLASH_R_N                                                 
P  NNAMEm0120 SMB_DEBUG_AUX_LVC3_USB_R3_SDA                                     
P  NNAMEm0121 SMB_DEBUG_AUX_LVC3_USB_R3_SCL                                     
P  NNAMEm0122 RST_SPI_FLASH_BUF_N                                               
P  NNAMEm0123 FM_BMC_DEBUG_SW_R2_N                                              
P  NNAMEm0124 DP_BMC_HPD_3V3_BUF                                                
P  NNAMEm0125 TDR_SE_50_OHM_TOP                                                 
P  NNAMEm0126 TDR_SE_50_OHM_IN4                                                 
P  NNAMEm0127 TDR_SE_50_OHM_IN3                                                 
P  NNAMEm0128 TDR_SE_50_OHM_IN2                                                 
P  NNAMEm0129 TDR_SE_50_OHM_IN1                                                 
P  NNAMEm0130 TDR_SE_50_OHM_BOT                                                 
P  NNAMEm0131 TDR_DIFF_85_TOP_DP                                                
P  NNAMEm0132 TDR_DIFF_85_TOP_DN                                                
P  NNAMEm0133 TDR_DIFF_85_IN4_DP                                                
P  NNAMEm0134 TDR_DIFF_85_IN4_DN                                                
P  NNAMEm0135 TDR_DIFF_85_IN1_DP                                                
P  NNAMEm0136 TDR_DIFF_85_IN1_DN                                                
P  NNAMEm0137 TDR_DIFF_85_BOT_DP                                                
P  NNAMEm0138 TDR_DIFF_85_BOT_DN                                                
P  NNAMEm0139 TDR_DIFF_100_TOP_DP                                               
P  NNAMEm0140 TDR_DIFF_100_TOP_DN                                               
P  NNAMEm0141 TDR_DIFF_100_IN4_DP                                               
P  NNAMEm0142 TDR_DIFF_100_IN4_DN                                               
P  NNAMEm0143 TDR_DIFF_100_IN1_DP                                               
P  NNAMEm0144 TDR_DIFF_100_IN1_DN                                               
P  NNAMEm0145 TDR_DIFF_100_BOT_DP                                               
P  NNAMEm0146 TDR_DIFF_100_BOT_DN                                               
P  NNAMEm0147 SMB_DEBUG_AUX_LVC3_USB_R2_SDA                                     
P  NNAMEm0148 SMB_DEBUG_AUX_LVC3_USB_R2_SCL                                     
P  NNAMEm0149 RST_PLTRST_R2_N                                                   
P  NNAMEm0150 PWRGD_SYS_PWROK_R1                                                
P  NNAMEm0151 PWRGD_DSW_PWROK_R3                                                
P  NNAMEm0152 PWRGD_DSW_PWROK                                                   
P  NNAMEm0153 LED_POSTCODE_INT                                                  
P  NNAMEm0154 LED_POSTCODE_A2                                                   
P  NNAMEm0155 LED_POSTCODE_A1                                                   
P  NNAMEm0156 LED_POSTCODE_A0                                                   
P  NNAMEm0157 LED_POSTCODE_7_R1                                                 
P  NNAMEm0158 LED_POSTCODE_6_R1                                                 
P  NNAMEm0159 LED_POSTCODE_5_R1                                                 
P  NNAMEm0160 LED_POSTCODE_4_R1                                                 
P  NNAMEm0161 LED_POSTCODE_3_R1                                                 
P  NNAMEm0162 LED_POSTCODE_2_R1                                                 
P  NNAMEm0163 LED_POSTCODE_1_R1                                                 
P  NNAMEm0164 LED_POSTCODE_0_R1                                                 
P  NNAMEm0165 FM_UART_SWITCH_N                                                  
P  NNAMEm0166 FM_SOL_UART_CH_SEL_R3                                             
P  NNAMEm0167 FM_SOL_UART_CH_SEL                                                
P  NNAMEm0168 FM_SLPS3_GF_R2_N                                                  
P  NNAMEm0169 FM_SLPS3_GF_R1_N                                                  
P  NNAMEm0170 FM_DEBUG_RST_BTN_N                                                
P  NNAMEm0171 FM_DEBUG_PWR_BTN_N                                                
P  NNAMEm0172 FM_DEBUG_PORT_R_PRSNT_N                                           
P  NNAMEm0173 FM_DEBUG_PORT_PRSNT_N                                             
P  NNAMEm0174 FM_CPU_MSMI_CATERR_LVT3_R3_N                                      
P  NNAMEm0175 FM_BMC_CRASHLOG_TRIG_R2_N                                         
P  NNAMEm0176 IRQ_PCH_TPM_SPI_R2_N                                              
P  NNAMEm0177 USB3_01_MUX_FB_TXP                                                
P  NNAMEm0178 USB3_01_MUX_FB_TXN                                                
P  NNAMEm0179 USB3_01_MUX_FB_RXP                                                
P  NNAMEm0180 USB3_01_MUX_FB_RXN                                                
P  NNAMEm0181 SMB_BMC_MM15_R1_SDA                                               
P  NNAMEm0182 SMB_BMC_MM15_R1_SCL                                               
P  NNAMEm0183 DEBUG_PORT_PRSNT_R                                                
P  NNAMEm0184 DEBUG_PORT_PRSNT_BUF_R_EN                                         
P  NNAMEm0185 SMB_PCH_TPM_SDA                                                   
P  NNAMEm0186 SMB_PCH_TPM_SCL                                                   
P  NNAMEm0187 PD_CLK_125M_PHY_BMC_RGMII                                         
P  NNAMEm0188 FM_JTAG_BMC_MUX_SEL_R2                                            
P  NNAMEm0189 FM_JTAG_BMC_MUX_SEL_R1                                            
P  NNAMEm0190 FM_JTAG_BMC_MUX_SEL                                               
P  NNAMEm0191 FM_BMC_SUSACK_R2_N                                                
P  NNAMEm0192 FM_BMC_SUSACK_R1_N                                                
P  NNAMEm0193 RST_WDTRST_PLD_R2_N                                               
P  NNAMEm0194 RST_WDTRST_PLD_R1_N                                               
P  NNAMEm0195 RST_WDTRST_PLD_N                                                  
P  NNAMEm0196 RST_BMC_SELF_HW_R1                                                
P  NNAMEm0197 CRT_VCC5_2_FUSE                                                   
P  NNAMEm0198 UART_BMC_5_TXD_BUF_R                                              
P  NNAMEm0199 UART_BMC_5_TXD_BUF                                                
P  NNAMEm0200 UART_BMC_5_RXD_BUF_R                                              
P  NNAMEm0201 UART_BMC_5_RXD_BUF                                                
P  NNAMEm0202 TP_BIOS_MUX1_PIN14                                                
P  NNAMEm0203 TP_BIOS_MUX1_PIN13                                                
P  NNAMEm0204 TP_BIOS_MUX1_PIN12                                                
P  NNAMEm0205 SPI_PCH_SECURE_CS0_N                                              
P  NNAMEm0206 SPI_BMC_TPM_MOSI_R                                                
P  NNAMEm0207 SPI_BMC_TPM_MISO_R                                                
P  NNAMEm0208 SPI_BMC_TPM_CS2_R_N                                               
P  NNAMEm0209 SPI_BMC_TPM_CS2_N_R                                               
P  NNAMEm0210 SPI_BMC_TPM_CLK_R                                                 
P  NNAMEm0211 SPA_SOUT_SW_DBG                                                   
P  NNAMEm0212 SMB_DEBUG_AUX_LVC3_USB_SDA                                        
P  NNAMEm0213 SMB_DEBUG_AUX_LVC3_USB_SCL                                        
P  NNAMEm0214 SMB_DEBUG_AUX_LVC3_USB_R1_SDA                                     
P  NNAMEm0215 SMB_DEBUG_AUX_LVC3_USB_R1_SCL                                     
P  NNAMEm0216 SMB_BMC_TPM_MM16_SDA                                              
P  NNAMEm0217 SMB_BMC_TPM_MM16_SCL                                              
P  NNAMEm0218 SMB_BMC_MM16_R3_SDA                                               
P  NNAMEm0219 SMB_BMC_MM16_R3_SCL                                               
P  NNAMEm0220 SMB_BMC_MM14_SDA                                                  
P  NNAMEm0221 SMB_BMC_MM14_SCL                                                  
P  NNAMEm0222 SMB_BMC_MM14_R1_SDA                                               
P  NNAMEm0223 SMB_BMC_MM14_R1_SCL                                               
P  NNAMEm0224 SMB_BMC_MM13_SDA                                                  
P  NNAMEm0225 SMB_BMC_MM13_SCL                                                  
P  NNAMEm0226 SMB_BMC_ALERT9_R_N                                                
P  NNAMEm0227 SMB_BMC_ALERT9_R1_N                                               
P  NNAMEm0228 SMB_BMC_ALERT4_R_N                                                
P  NNAMEm0229 SMB_BMC_ALERT4_R1_N                                               
P  NNAMEm0230 SMB_BMC_ALERT3_R_N                                                
P  NNAMEm0231 SMB_BMC_ALERT3_R1_N                                               
P  NNAMEm0232 SMB_BMC_ALERT10_R_N                                               
P  NNAMEm0233 SMB_BMC_ALERT10_R1_N                                              
P  NNAMEm0234 RST_SRST_PLD_BMC_BUF_N                                            
P  NNAMEm0235 RST_SPI_PCH_FLASH_R1_N                                            
P  NNAMEm0236 RST_SPI_BMC_FLASH_R2_N                                            
P  NNAMEm0237 RST_SPI_BMC_FLASH_R1_N                                            
P  NNAMEm0238 RST_SGPIO_RESET_R_N                                               
P  NNAMEm0239 RST_BMC_SRST_BUF_R_N                                              
P  NNAMEm0240 RST_BMC_SRST_BUF_R1_N                                             
P  NNAMEm0241 RST_BMC_SELF_HW_R3                                                
P  NNAMEm0242 RST_BMC_SELF_HW_R2                                                
P  NNAMEm0243 BMC_EMMC_RST_R_N                                                  
P  NNAMEm0244 RST_BMC_SELF_HW_D_C                                               
P  NNAMEm0245 RST_BMC_SELF_HW_D                                                 
P  NNAMEm0246 RST_BMC_SELF_HW                                                   
P  NNAMEm0247 RST_BMC_EXTRST_R3_N                                               
P  NNAMEm0248 RST_BMC_EXTRST_R2_N                                               
P  NNAMEm0249 RST_BMC_EXTRST_R1_N                                               
P  NNAMEm0250 PWRGD_EN_P3V3_R                                                   
P  NNAMEm0251 PWRGD_P5V_AUX_R1                                                  
P  NNAMEm0252 PWRGD_P5V_AUX_R                                                   
P  NNAMEm0253 PWRGD_P3V3_RGM_R1                                                 
P  NNAMEm0254 PWRGD_P3V3_RGM_R                                                  
P  NNAMEm0255 PWRGD_P3V3_AUX_R2                                                 
P  NNAMEm0256 PWRGD_P3V3_AUX_R1                                                 
P  NNAMEm0257 PWRGD_P3V3_AUX_R                                                  
P  NNAMEm0258 PWRGD_P2V5_AUX_R1                                                 
P  NNAMEm0259 PWRGD_P2V5_AUX_R                                                  
P  NNAMEm0260 PWRGD_P1V8_AUX_R1                                                 
P  NNAMEm0261 PWRGD_P1V8_AUX_R                                                  
P  NNAMEm0262 PWRGD_P1V2_AUX_R1                                                 
P  NNAMEm0263 PWRGD_P1V2_AUX_R                                                  
P  NNAMEm0264 PWRGD_P1V0_AUX_R2                                                 
P  NNAMEm0265 PWRGD_P1V0_AUX_R1                                                 
P  NNAMEm0266 PWRGD_P1V0_AUX_R                                                  
P  NNAMEm0267 PWRGD_P1V0_AUX_DELAY_R1                                           
P  NNAMEm0268 PWRGD_P1V0_AUX_DELAY_BUF                                          
P  NNAMEm0269 PD_BIOS_MUX_EN_R_N                                                
P  NNAMEm0270 PD_BIOS_MUX_EN_N                                                  
P  NNAMEm0271 IRQ_BMC_TPM_SPI_R_N                                               
P  NNAMEm0272 FM_TPM_PRSNT_1_N                                                  
P  NNAMEm0273 FM_PECI_SEL_R_N                                                   
P  NNAMEm0274 FM_ESPI_PLD_R1_EN                                                 
P  NNAMEm0275 FM_CPU_MSMI_CATERR_LVT3_PLD_N                                     
P  NNAMEm0276 FM_BMC_READY_R_PLD_N                                              
P  NNAMEm0277 FM_BMC_READY_PLD_N                                                
P  NNAMEm0278 FM_BMC_BIOS_MUX_CS_SPI_R_SEL_0                                    
P  NNAMEm0279 FM_BIOS_DEBUG_EN_R_N                                              
P  NNAMEm0280 FM_BIOS_DEBUG_EN_N                                                
P  NNAMEm0281 DEBUG_PORT_UART_TX                                                
P  NNAMEm0282 DEBUG_PORT_UART_RX                                                
P  NNAMEm0283 DEBUG_PORT_PRSNT_BUF_EN                                           
P  NNAMEm0284 DEBUG_PORT_PRSNT                                                  
P  NNAMEm0285 BMC_CPLD_GPIO_8_R2                                                
P  NNAMEm0286 SPI_BMC_TPM_MISO_R1                                               
P  NNAMEm0287 BMC_CPLD_GPIO_8                                                   
P  NNAMEm0288 BMC_CPLD_GPIO_7_R2                                                
P  NNAMEm0289 SPI_BMC_TPM_CLK_R1                                                
P  NNAMEm0290 BMC_CPLD_GPIO_7                                                   
P  NNAMEm0291 BMC_ID_BEEP_SEL_R1                                                
P  NNAMEm0292 SPI_BMC_TPM_CS2_R1_N                                              
P  NNAMEm0293 FM_DEBUG_PORT_PRSNT_R1_N                                          
P  NNAMEm0294 FM_DEBUG_PORT_R2_PRSNT_N                                          
P  NNAMEm0295 PWRGD_DSW_PWROK_R2                                                
P  NNAMEm0296 PWRGD_DSW_PWROK_R1                                                
P  NNAMEm0297 FM_BMC_CRASHLOG_TRIG_N                                            
P  NNAMEm0298 FM_SOL_UART_CH_SEL_R2                                             
P  NNAMEm0299 FM_SOL_UART_CH_SEL_R1                                             
P  NNAMEm0300 FM_P12V_HSC_ENABLE_R2                                             
P  NNAMEm0301 FM_P12V_HSC_ENABLE_R1                                             
P  NNAMEm0302 FM_P12V_HSC_ENABLE                                                
P  NNAMEm0303 BMC_CPLD_GPIO_2                                                   
P  NNAMEm0304 RST_ROT_CPU_R1_N                                                  
P  NNAMEm0305 SMB_BMC_ALERT16_R2_N                                              
P  NNAMEm0306 BMC_CPLD_GPIO_13_R2                                               
P  NNAMEm0307 FLASH_WP_STATUS_R1                                                
P  NNAMEm0308 BMC_CPLD_GPIO_13                                                  
P  NNAMEm0309 BMC_CPLD_GPIO_12_R2                                               
P  NNAMEm0310 FM_FLASH_LATCH_N_R1                                               
P  NNAMEm0311 BMC_CPLD_GPIO_12                                                  
P  NNAMEm0312 H_CPU0_MEMTRIP_LVC1_N                                             
P  NNAMEm0313 FM_THERMTRIP_DLY_LVC1_R_N                                         
P  NNAMEm0314 FM_PCIE_M2_SSD0_PRSNT_N                                           
P  NNAMEm0315 FM_PMBUS_ALERT_EN                                                 
P  NNAMEm0316 H_CPU1_MEMTRIP_LVC1_N                                             
P  NNAMEm0317 FM_SPD_REMOTE_EN_R                                                
P  NNAMEm0318 FM_ADR_COMPLETE                                                   
P  NNAMEm0319 FM_ADR_TRIGGER_N                                                  
P  NNAMEm0320 ID_RST_BTN_BMC_R_N                                                
P  NNAMEm0321 IRQ_PCH_SCI_WHEA_R_N                                              
P  NNAMEm0322 SPI_SYS_MUX_WP_IO2                                                
P  NNAMEm0323 SPI_SYS_MUX_MOSI                                                  
P  NNAMEm0324 SPI_SYS_MUX_MISO                                                  
P  NNAMEm0325 SPI_SYS_MUX_HOLD_IO3                                              
P  NNAMEm0326 SPI_SYS_MUX_CLK                                                   
P  NNAMEm0327 FM_BIOS_POST_CMPLT_BMC_N                                          
P  NNAMEm0328 PWRGD_CPUPWRGD_LVC1                                               
P  NNAMEm0329 PWRGD_PCH_PWROK                                                   
P  NNAMEm0330 IRQ_CPU1_VRHOT_N                                                  
P  NNAMEm0331 IRQ_CPU0_VRHOT_N                                                  
P  NNAMEm0332 IRQ_OC_DETECT_EN_N                                                
P  NNAMEm0333 IRQ_UV_DETECT_N                                                   
P  NNAMEm0334 IRQ_OC_DETECT_N                                                   
P  NNAMEm0335 SMB_BMC_ALERT9_N                                                  
P  NNAMEm0336 SMB_BMC_ALERT16_N                                                 
P  NNAMEm0337 FM_BMC_EN_DET_R                                                   
P  NNAMEm0338 SMB_BMC_ALERT12_N                                                 
P  NNAMEm0339 SMB_BMC_ALERT10_N                                                 
P  NNAMEm0340 PWRGD_SYS_PWROK_PLD                                               
P  NNAMEm0341 PWRGD_SYS_PWROK_BMC                                               
P  NNAMEm0342 PWRGD_PSU_AC_PWROK_PLD                                            
P  NNAMEm0343 PWRGD_PSU_AC_PWROK_BMC                                            
P  NNAMEm0344 FM_ESPI_PLD_R_EN                                                  
P  NNAMEm0345 FM_VIRTUAL_RESEAT_BMC                                             
P  NNAMEm0346 RST_ROT_CPU_R_N                                                   
P  NNAMEm0347 FM_VIRTUAL_RESEAT                                                 
P  NNAMEm0348 85_10INCH_TOP_DP                                                  
P  NNAMEm0349 85_10INCH_TOP_DN                                                  
P  NNAMEm0350 85_10INCH_IN4_DP                                                  
P  NNAMEm0351 85_10INCH_IN4_DN                                                  
P  NNAMEm0352 85_10INCH_IN1_DP                                                  
P  NNAMEm0353 85_10INCH_IN1_DN                                                  
P  NNAMEm0354 85_10INCH_BOT_DP                                                  
P  NNAMEm0355 85_10INCH_BOT_DN                                                  
P  NNAMEm0356 PWR_LED_BUF_N_R                                                   
P  NNAMEm0357 REAR_ID_RST_BTN_N                                                 
P  NNAMEm0358 PU_FPGA_NSTATUS                                                   
P  NNAMEm0359 PU_FPGA_NCONFIG                                                   
P  NNAMEm0360 PU_FPGA_CONFIG_DONE                                               
P  NNAMEm0361 PU_25M_FPGA_CLK_EN                                                
P  NNAMEm0362 CLK_25M_OSC_FPGA_R                                                
P  NNAMEm0363 CLK_25M_OSC_FPGA                                                  
P  NNAMEm0364 USB_HOST_BMC_B_R_DP                                               
P  NNAMEm0365 USB_HOST_BMC_B_R_DN                                               
P  NNAMEm0366 USB_HOST_BMC_B_DP                                                 
P  NNAMEm0367 USB_HOST_BMC_B_DN                                                 
P  NNAMEm0368 USB_HOST_BMC_A_DP                                                 
P  NNAMEm0369 USB_HOST_BMC_A_DN                                                 
P  NNAMEm0370 UART_BMC_5_TXD_R                                                  
P  NNAMEm0371 UART_BMC_5_RXD_R                                                  
P  NNAMEm0372 UART_BMC_1_RXD_R                                                  
P  NNAMEm0373 UART_6_BMC_R_TXD                                                  
P  NNAMEm0374 UART_6_BMC_R_RXD                                                  
P  NNAMEm0375 FM_BMC_CRASHLOG_TRIG_R1_N                                         
P  NNAMEm0376 FM_BIC_DEBUG_SW_N_R                                               
P  NNAMEm0377 SPI_SYS_WP_R_IO2                                                  
P  NNAMEm0378 SPI_SYS_R1_MOSI                                                   
P  NNAMEm0379 SPI_SYS_R1_MISO                                                   
P  NNAMEm0380 SPI_SYS_HOLD_R_IO3                                                
P  NNAMEm0381 SPI_BMC_BOOT_CS1_R1_N                                             
P  NNAMEm0382 SPI_BMC_BOOT_CS0_R1_N                                             
P  NNAMEm0383 SPI_BMC_BIOS_SOURCE_CS0_N                                         
P  NNAMEm0384 SPI_BMC_BIOS_ROM_R_IO3                                            
P  NNAMEm0385 SPI_BMC_BIOS_ROM_R_IO2                                            
P  NNAMEm0386 SPI_BMC_BIOS_ROM_IO3                                              
P  NNAMEm0387 SPI_BMC_BIOS_ROM_IO2                                              
P  NNAMEm0388 SPI_BMC_BIOS_CS0_R1_N                                             
P  NNAMEm0389 SMB_BMC_MM16_SDA                                                  
P  NNAMEm0390 SMB_BMC_MM16_SCL                                                  
P  NNAMEm0391 SMB_BMC_MM16_R_SDA                                                
P  NNAMEm0392 SMB_BMC_MM16_R_SCL                                                
P  NNAMEm0393 SMB_BMC_MM15_SDA                                                  
P  NNAMEm0394 SMB_BMC_MM15_SCL                                                  
P  NNAMEm0395 SMB_BMC_MM15_R_SDA                                                
P  NNAMEm0396 SMB_BMC_MM15_R_SCL                                                
P  NNAMEm0397 SMB_BMC_MM12_SDA                                                  
P  NNAMEm0398 SMB_BMC_MM12_SCL                                                  
P  NNAMEm0399 SMB_BMC_ALERT15_N                                                 
P  NNAMEm0400 SMB_BMC_MM13_R_SDA                                                
P  NNAMEm0401 SMB_BMC_MM14_R_SCL                                                
P  NNAMEm0402 SMB_BMC_MM14_R_SDA                                                
P  NNAMEm0403 SMB_BMC_MM13_R_SCL                                                
P  NNAMEm0404 RST_SRST_PLD_BMC_R_N                                              
P  NNAMEm0405 RST_SGPIO_RESET_N                                                 
P  NNAMEm0406 RST_SGPIO_RESET_BMC_N                                             
P  NNAMEm0407 RST_PLTRST_R1_N                                                   
P  NNAMEm0408 RST_MB_STBY_R_N                                                   
P  NNAMEm0409 RST_BMC_LPC_ESPI_N                                                
P  NNAMEm0410 PWRGD_SYS_PWROK                                                   
P  NNAMEm0411 PWRGD_PSU_AC_PWROK                                                
P  NNAMEm0412 PWRGD_P1V0_AUX_DELAY                                              
P  NNAMEm0413 PWRGD_PSU_AC_PWROK_R                                              
P  NNAMEm0414 PU_BMC_FWSPIABR_N                                                 
P  NNAMEm0415 PGPPA_BMC_AUX_SENSOR                                              
P  NNAMEm0416 PGPPA_BMC_AUX_L                                                   
P  NNAMEm0417 LPC_ESPI_SEL_R1                                                   
P  NNAMEm0418 H_CPU1_PROCHOT_LVC1_R_N                                           
P  NNAMEm0419 IRQ_SGPIO_BMC_N                                                   
P  NNAMEm0420 IRQ_BMC_PCH_NMI_R_N                                               
P  NNAMEm0421 IRQ_BMC_PCH_NMI_N                                                 
P  NNAMEm0422 IRQ_BMC_LPC_SERIRQ_ESPI_GF                                        
P  NNAMEm0423 FM_THROTTLE_R_N                                                   
P  NNAMEm0424 FM_SLPS3_GF_R_N                                                   
P  NNAMEm0425 H_CPU0_PROCHOT_LVC1_R_N                                           
P  NNAMEm0426 H_CPU0_PROCHOT_LVC1_N                                             
P  NNAMEm0427 RST_PCA9548_SENSOR_R_N                                            
P  NNAMEm0428 FM_DBP_CPU_PREQ_GF_R_N                                            
P  NNAMEm0429 FM_DBP_BMC_PRDY_R_N                                               
P  NNAMEm0430 FM_DBP_BMC_PRDY_N                                                 
P  NNAMEm0431 FM_BMC_MUX_CS_SPI_SEL_0                                           
P  NNAMEm0432 FM_BMC_DBP_PRESENT_N                                              
P  NNAMEm0433 FM_BMC_CPU_FBRK_OUT_R_N                                           
P  NNAMEm0434 FM_BMC_CPU_FBRK_OUT_N                                             
P  NNAMEm0435 ESPI_LPC_LAD3_IO3                                                 
P  NNAMEm0436 ESPI_LPC_LAD2_IO2                                                 
P  NNAMEm0437 ESPI_LPC_LAD1_IO1                                                 
P  NNAMEm0438 ESPI_LPC_LAD0_IO0                                                 
P  NNAMEm0439 ESPI_HOST_LPC_BMC_LFRAME_N                                        
P  NNAMEm0440 ESPI_HOST_LPC_BMC_CLK                                             
P  NNAMEm0441 BATTERY_DETECT_R                                                  
P  NNAMEm0442 85_5INCH_TOP_DP                                                   
P  NNAMEm0443 85_5INCH_TOP_DN                                                   
P  NNAMEm0444 85_5INCH_IN4_DP                                                   
P  NNAMEm0445 85_5INCH_IN4_DN                                                   
P  NNAMEm0446 85_5INCH_IN1_DP                                                   
P  NNAMEm0447 85_5INCH_IN1_DN                                                   
P  NNAMEm0448 85_5INCH_BOT_DP                                                   
P  NNAMEm0449 85_5INCH_BOT_DN                                                   
P  NNAMEm0450 SYS_BMC_PWRBTN_R_N                                                
P  NNAMEm0451 SPI_BMC_BIOS_CS0_N                                                
P  NNAMEm0452 FM_BMC_ONCTL_R_N                                                  
P  NNAMEm0453 JTAG_1_BMC_TDO_R                                                  
P  NNAMEm0454 FM_BMC_SUSACK_N                                                   
P  NNAMEm0455 JTAG_SCM_PLD_R1_JTAGEN                                            
P  NNAMEm0456 JTAG_SCM_PLD_TMS                                                  
P  NNAMEm0457 JTAG_SCM_PLD_TDO                                                  
P  NNAMEm0458 JTAG_SCM_PLD_TDI                                                  
P  NNAMEm0459 JTAG_SCM_PLD_TCK                                                  
P  NNAMEm0460 MB_JTAG_PLD_R_JTAGEN                                              
P  NNAMEm0461 JTAG_SCM_PLD_JTAGEN                                               
P  NNAMEm0462 JTAG_SCM_CONN_TMS                                                 
P  NNAMEm0463 JTAG_SCM_CONN_TDO                                                 
P  NNAMEm0464 JTAG_SCM_CONN_TDI                                                 
P  NNAMEm0465 JTAG_SCM_CONN_TCK                                                 
P  NNAMEm0466 IRQ_PCH_TPM_SPI_R_N                                               
P  NNAMEm0467 FM_TPM_PRSNT_0_N                                                  
P  NNAMEm0468 V_BMC_LS_DDC_SDA_R                                                
P  NNAMEm0469 V_BMC_LS_DDC_SDA                                                  
P  NNAMEm0470 V_BMC_LS_DDC_SCL_R                                                
P  NNAMEm0471 V_BMC_LS_DDC_SCL                                                  
P  NNAMEm0472 V_BMC_DDC_LS_GATE                                                 
P  NNAMEm0473 USB_OC0_REAR_R_N                                                  
P  NNAMEm0474 TP_BIOS_MUX0_PIN14                                                
P  NNAMEm0475 TP_BIOS_MUX0_PIN13                                                
P  NNAMEm0476 TP_BIOS_MUX0_PIN12                                                
P  NNAMEm0477 SW_P3V3_AUX_FLT                                                   
P  NNAMEm0478 SW_P3V3_AUX_BST                                                   
P  NNAMEm0479 SW_P1V2_AUX_FLT                                                   
P  NNAMEm0480 SW_P1V2_AUX_BST                                                   
P  NNAMEm0481 SW_P1V0_AUX_FLT                                                   
P  NNAMEm0482 SW_P1V0_AUX_BST                                                   
P  NNAMEm0483 SPI_PCH_MUXED_IO3                                                 
P  NNAMEm0484 SPI_PCH_MUXED_IO2                                                 
P  NNAMEm0485 SPI_PCH_MUXED_IO1                                                 
P  NNAMEm0486 SPI_PCH_MUXED_IO0                                                 
P  NNAMEm0487 SPI_PCH_MUXED_CS0_N                                               
P  NNAMEm0488 SPI_PCH_MUXED_CLK                                                 
P  NNAMEm0489 SPI_PCH_IO3_FLASH_R1                                              
P  NNAMEm0490 SPI_PCH_IO2_FLASH_R1                                              
P  NNAMEm0491 SPI_PCH_IO1_FLASH_R1                                              
P  NNAMEm0492 SPI_PCH_IO0_FLASH_R1                                              
P  NNAMEm0493 SPI_PCH_CS0_FLASH_R1_N                                            
P  NNAMEm0494 SPI_PCH_CLK_FLASH_R1                                              
P  NNAMEm0495 RST_SPI_FLASH_N                                                   
P  NNAMEm0496 SPI_BMC_MOSI_IO0_R                                                
P  NNAMEm0497 SPI_BMC_MISO_IO1_R                                                
P  NNAMEm0498 SPI_BMC_BOOT_MOSI                                                 
P  NNAMEm0499 SPI_BMC_BOOT_MISO                                                 
P  NNAMEm0500 SPI_BMC_BOOT_CS1_R_N                                              
P  NNAMEm0501 SPI_BMC_BOOT_CS0_R_N                                              
P  NNAMEm0502 SPI_BMC_BOOT_CLK                                                  
P  NNAMEm0503 SPI_BMC_BIOS_ROM_R_MOSI                                           
P  NNAMEm0504 SPI_BMC_BIOS_ROM_R_MISO                                           
P  NNAMEm0505 SPI_BMC_BIOS_ROM_R_CLK                                            
P  NNAMEm0506 SPI_BMC_BIOS_ROM_MOSI                                             
P  NNAMEm0507 SPI_BMC_BIOS_ROM_MISO                                             
P  NNAMEm0508 SPI_BMC_BIOS_ROM_CLK                                              
P  NNAMEm0509 SPA_SOUT_SW_BUF                                                   
P  NNAMEm0510 UART_BMC_1_TXD_R                                                  
P  NNAMEm0511 SMB_BMC_MM16_R2_SDA                                               
P  NNAMEm0512 SMB_BMC_MM16_R2_SCL                                               
P  NNAMEm0513 SMB_BMC_MM9_SDA                                                   
P  NNAMEm0514 SMB_BMC_MM9_SCL                                                   
P  NNAMEm0515 SMB_BMC_MM9_R_SDA                                                 
P  NNAMEm0516 SMB_BMC_MM9_R_SCL                                                 
P  NNAMEm0517 SMB_BMC_MM8_SDA                                                   
P  NNAMEm0518 SMB_BMC_MM8_SCL                                                   
P  NNAMEm0519 SMB_BMC_MM8_R_SDA                                                 
P  NNAMEm0520 SMB_BMC_MM8_R_SCL                                                 
P  NNAMEm0521 SMB_BMC_MM7_SDA                                                   
P  NNAMEm0522 SMB_BMC_MM7_SCL                                                   
P  NNAMEm0523 SMB_BMC_MM7_R_SDA                                                 
P  NNAMEm0524 SMB_BMC_MM7_R_SCL                                                 
P  NNAMEm0525 SMB_BMC_MM6_SDA                                                   
P  NNAMEm0526 SMB_BMC_MM6_SCL                                                   
P  NNAMEm0527 SMB_BMC_MM6_R_SDA                                                 
P  NNAMEm0528 SMB_BMC_MM6_R_SCL                                                 
P  NNAMEm0529 SMB_BMC_MM5_SDA                                                   
P  NNAMEm0530 SMB_BMC_MM5_SCL                                                   
P  NNAMEm0531 SMB_BMC_MM5_R_SDA                                                 
P  NNAMEm0532 SMB_BMC_MM5_R_SCL                                                 
P  NNAMEm0533 SMB_BMC_MM4_SDA                                                   
P  NNAMEm0534 SMB_BMC_MM4_SCL                                                   
P  NNAMEm0535 SMB_BMC_MM4_R_SDA                                                 
P  NNAMEm0536 SMB_BMC_MM4_R_SCL                                                 
P  NNAMEm0537 SMB_BMC_MM3_SDA                                                   
P  NNAMEm0538 SMB_BMC_MM3_SCL                                                   
P  NNAMEm0539 SMB_BMC_MM3_R_SDA                                                 
P  NNAMEm0540 SMB_BMC_MM3_R_SCL                                                 
P  NNAMEm0541 SMB_BMC_MM2_SDA                                                   
P  NNAMEm0542 SMB_BMC_MM2_SCL                                                   
P  NNAMEm0543 SMB_BMC_MM2_R_SDA                                                 
P  NNAMEm0544 SMB_BMC_MM2_R_SCL                                                 
P  NNAMEm0545 SMB_BMC_MM1_SDA                                                   
P  NNAMEm0546 SMB_BMC_MM1_SCL                                                   
P  NNAMEm0547 SMB_BMC_MM1_R_SDA                                                 
P  NNAMEm0548 SMB_BMC_MM1_R_SCL                                                 
P  NNAMEm0549 SMB_BMC_MM12_R_SDA                                                
P  NNAMEm0550 SMB_BMC_MM12_R_SCL                                                
P  NNAMEm0551 SMB_BMC_MM10_SDA                                                  
P  NNAMEm0552 SMB_BMC_MM10_SCL                                                  
P  NNAMEm0553 SMB_BMC_MM10_R_SDA                                                
P  NNAMEm0554 SMB_BMC_MM10_R_SCL                                                
P  NNAMEm0555 SMB_BMC_ALERT4_N                                                  
P  NNAMEm0556 SMB_BMC_ALERT3_N                                                  
P  NNAMEm0557 VOL_SEN_ALERT_R                                                   
P  NNAMEm0558 SGPIO_CLK_PLD_0                                                   
P  NNAMEm0559 SGPIO_BMC_M1_LD                                                   
P  NNAMEm0560 SGPIO_BMC_M1_DO                                                   
P  NNAMEm0561 SGPIO_BMC_M1_DI                                                   
P  NNAMEm0562 SGPIO_BMC_M1_CLK                                                  
P  NNAMEm0563 RST_PLTRST_TPM_N                                                  
P  NNAMEm0564 RST_ESPI_LPC_BMC_N                                                
P  NNAMEm0565 ID_RST_BTN_BMC_N                                                  
P  NNAMEm0566 RST_BMC_RSTBTN_OUT_R_N                                            
P  NNAMEm0567 RST_BMC_RSTBTN_OUT_N                                              
P  NNAMEm0568 PVCCIO_PECI_BMC                                                   
P  NNAMEm0569 LED_POSTCODE_7_R                                                  
P  NNAMEm0570 LED_POSTCODE_6_R                                                  
P  NNAMEm0571 LED_POSTCODE_5_R                                                  
P  NNAMEm0572 LED_POSTCODE_4_R                                                  
P  NNAMEm0573 LED_POSTCODE_3_R                                                  
P  NNAMEm0574 LED_POSTCODE_2_R                                                  
P  NNAMEm0575 LED_POSTCODE_1_R                                                  
P  NNAMEm0576 LED_POSTCODE_0_R                                                  
P  NNAMEm0577 PU_25M_BMC_CLK_EN                                                 
P  NNAMEm0578 PD_M_BMC_DDR4_ZQ                                                  
P  NNAMEm0579 PD_M_BMC_DDR4_TEN                                                 
P  NNAMEm0580 PD_M_BMC_DDR4_PAR                                                 
P  NNAMEm0581 P3V3_STBY_PLLAHVDD                                                
P  NNAMEm0582 P3V3_STBY_DACAV33                                                 
P  NNAMEm0583 P3V3_P2V5_P1V8_RVDD                                               
P  NNAMEm0584 P3V3_P1V8_SD2VDD                                                  
P  NNAMEm0585 P3V3_P1V8_SD1VDD                                                  
P  NNAMEm0586 P3V3_P1V8_I2C_I3C                                                 
P  NNAMEm0587 P3V3_BMC_USB2AV33                                                 
P  NNAMEm0588 P1V8_STBY_RC_VCC18A                                               
P  NNAMEm0589 P1V8_STBY_PE_VCC18A                                               
P  NNAMEm0590 P1V8_STBY_DP_VCC18A                                               
P  NNAMEm0591 P1V8_STBY_AVDDPLL                                                 
P  NNAMEm0592 P1V8_BMC_USB2AV18                                                 
P  NNAMEm0593 P1V2_STBY_MVDD_CK                                                 
P  NNAMEm0594 P1V2_P1V0_I3C_VDDL2                                               
P  NNAMEm0595 P1V2_P1V0_I3C_VDDL1                                               
P  NNAMEm0596 P1V0_STBY_RC_VCC10A                                               
P  NNAMEm0597 P1V0_STBY_PLAVDD                                                  
P  NNAMEm0598 P1V0_STBY_PE_VCC10A                                               
P  NNAMEm0599 P1V0_STBY_DP_VCC10A                                               
P  NNAMEm0600 P0V6_DDR_VREF_AUX                                                 
P  NNAMEm0601 M_BMC_DDR4_RST_N                                                  
P  NNAMEm0602 M_BMC_DDR4_MWE_N                                                  
P  NNAMEm0603 M_BMC_DDR4_MRAS_N                                                 
P  NNAMEm0604 M_BMC_DDR4_MODT                                                   
P  NNAMEm0605 M_BMC_DDR4_MDM1                                                   
P  NNAMEm0606 M_BMC_DDR4_MDM0                                                   
P  NNAMEm0607 M_BMC_DDR4_MCS_N                                                  
P  NNAMEm0608 M_BMC_DDR4_MCLK_DP                                                
P  NNAMEm0609 M_BMC_DDR4_MCLK_DN                                                
P  NNAMEm0610 M_BMC_DDR4_MCLK_C                                                 
P  NNAMEm0611 M_BMC_DDR4_MCKE                                                   
P  NNAMEm0612 M_BMC_DDR4_MCAS_N                                                 
P  NNAMEm0613 M_BMC_DDR4_MBG1                                                   
P  NNAMEm0614 M_BMC_DDR4_MBG0                                                   
P  NNAMEm0615 M_BMC_DDR4_MBA1                                                   
P  NNAMEm0616 M_BMC_DDR4_MBA0                                                   
P  NNAMEm0617 M_BMC_DDR4_MACT_N                                                 
P  NNAMEm0618 M_BMC_DDR4_MA<9>                                                  
P  NNAMEm0619 M_BMC_DDR4_MA<8>                                                  
P  NNAMEm0620 M_BMC_DDR4_MA<7>                                                  
P  NNAMEm0621 M_BMC_DDR4_MA<6>                                                  
P  NNAMEm0622 M_BMC_DDR4_MA<5>                                                  
P  NNAMEm0623 M_BMC_DDR4_MA<4>                                                  
P  NNAMEm0624 M_BMC_DDR4_MA<3>                                                  
P  NNAMEm0625 M_BMC_DDR4_MA<2>                                                  
P  NNAMEm0626 M_BMC_DDR4_MA<1>                                                  
P  NNAMEm0627 M_BMC_DDR4_MA<13>                                                 
P  NNAMEm0628 M_BMC_DDR4_MA<12>                                                 
P  NNAMEm0629 M_BMC_DDR4_MA<11>                                                 
P  NNAMEm0630 M_BMC_DDR4_MA<10>                                                 
P  NNAMEm0631 M_BMC_DDR4_MA<0>                                                  
P  NNAMEm0632 M_BMC_DDR4_DQS1_P                                                 
P  NNAMEm0633 M_BMC_DDR4_DQS1_N                                                 
P  NNAMEm0634 M_BMC_DDR4_DQS0_P                                                 
P  NNAMEm0635 M_BMC_DDR4_DQS0_N                                                 
P  NNAMEm0636 M_BMC_DDR4_DQ<9>                                                  
P  NNAMEm0637 M_BMC_DDR4_DQ<8>                                                  
P  NNAMEm0638 M_BMC_DDR4_DQ<7>                                                  
P  NNAMEm0639 M_BMC_DDR4_DQ<6>                                                  
P  NNAMEm0640 M_BMC_DDR4_DQ<5>                                                  
P  NNAMEm0641 M_BMC_DDR4_DQ<4>                                                  
P  NNAMEm0642 M_BMC_DDR4_DQ<3>                                                  
P  NNAMEm0643 M_BMC_DDR4_DQ<2>                                                  
P  NNAMEm0644 M_BMC_DDR4_DQ<1>                                                  
P  NNAMEm0645 M_BMC_DDR4_DQ<15>                                                 
P  NNAMEm0646 M_BMC_DDR4_DQ<14>                                                 
P  NNAMEm0647 M_BMC_DDR4_DQ<13>                                                 
P  NNAMEm0648 M_BMC_DDR4_DQ<12>                                                 
P  NNAMEm0649 M_BMC_DDR4_DQ<11>                                                 
P  NNAMEm0650 M_BMC_DDR4_DQ<10>                                                 
P  NNAMEm0651 M_BMC_DDR4_DQ<0>                                                  
P  NNAMEm0652 M_BMC_DDR4_ALERT_N                                                
P  NNAMEm0653 ESPI_LPC_D3_IO3                                                   
P  NNAMEm0654 ESPI_LPC_D2_IO2                                                   
P  NNAMEm0655 ESPI_LPC_D1_IO1                                                   
P  NNAMEm0656 ESPI_LPC_D0_IO0                                                   
P  NNAMEm0657 JTAG_1_BMC_TRST_R                                                 
P  NNAMEm0658 JTAG_1_BMC_TMS_R                                                  
P  NNAMEm0659 JTAG_1_BMC_TDI_R                                                  
P  NNAMEm0660 JTAG_1_BMC_TCK_R                                                  
P  NNAMEm0661 H_CPU1_PROCHOT_LVC1_N                                             
P  NNAMEm0662 IRQ_SMI_ACTIVE_GF_N                                               
P  NNAMEm0663 IRQ_SMI_ACTIVE_BMC_N                                              
P  NNAMEm0664 IRQ_ESPI_LPC_SERIRQ_ALERT0_N                                      
P  NNAMEm0665 IRQ_BMC_CPU_NMI_R                                                 
P  NNAMEm0666 IRQ_BMC_CPU_NMI                                                   
P  NNAMEm0667 ID_LED_P3V3_AUX                                                   
P  NNAMEm0668 USB_HOST_BMC_A_R_DP                                               
P  NNAMEm0669 USB_HOST_BMC_A_R_DN                                               
P  NNAMEm0670 FM_PLT_BMC_THERMTRIP_N_R                                          
P  NNAMEm0671 FM_PCH_BMC_THERMTRIP_N                                            
P  NNAMEm0672 FM_JTAG_TCK_MUX_BMC_SEL_R1                                        
P  NNAMEm0673 FM_JTAG_TCK_MUX_BMC_SEL_R                                         
P  NNAMEm0674 FM_JTAG_TCK_MUX_BMC_SEL                                           
P  NNAMEm0675 RST_PCA9548_SENSOR_N                                              
P  NNAMEm0676 FM_CPU_RMCA_CATERR_LVT3_R_N                                       
P  NNAMEm0677 FM_CPU_MSMI_CATERR_LVT3_N                                         
P  NNAMEm0678 FM_BMC_SSPRST_N                                                   
P  NNAMEm0679 FM_BMC_DEBUG_SW_N                                                 
P  NNAMEm0680 FM_BMC_DBP_PRESENT_R_N                                            
P  NNAMEm0681 NC_DP_BMC_TX1_P                                                   
P  NNAMEm0682 NC_DP_BMC_TX1_N                                                   
P  NNAMEm0683 NC_DP_BMC_TX0_P                                                   
P  NNAMEm0684 NC_DP_BMC_TX0_N                                                   
P  NNAMEm0685 NC_DP_BMC_AUX_P                                                   
P  NNAMEm0686 NC_DP_BMC_AUX_N                                                   
P  NNAMEm0687 FM_DBP_CPU_PREQ_GF_N                                              
P  NNAMEm0688 BMC_HEARTBEAT_R_N                                                 
P  NNAMEm0689 BMC_HEARTBEAT_N                                                   
P  NNAMEm0690 BMC_DDC_BUF_PWR                                                   
P  NNAMEm0691 A_BMC_ADCVREFP1                                                   
P  NNAMEm0692 A_BMC_ADCVREFP0                                                   
P  NNAMEm0693 A_BMC_ADCVREFN1                                                   
P  NNAMEm0694 A_BMC_ADCVREFN0                                                   
C                                                                               
C  ****************************************                                     
C      SIGNAL PINS & VIAS ON THE BOARD                                          
C  ****************************************                                     
C                                                                               
327RST_BMC_HW_R1    VIA   -    M      A12X+013440Y+039460X0260Y         S2      
327RST_BMC_HW_R1    R282  -1          A12X+013000Y+039942X0198Y0197R270 S2      
327RST_BMC_HW_R1    U58   -2          A12X+013035Y+038702X0280Y0400R180 S2      
327RST_BMC_HW_OUT   D17   -1          A01X+010842Y+041520X0260Y0540R090 S1      
327RST_BMC_HW_OUT   U58   -4          A12X+013409Y+037758X0280Y0400R180 S2      
317RST_BMC_HW_OUT   VIA   -    MD0100PA00X+013270Y+040270X0200Y         S0      
327RST_BMC_HW_OUT   R633  -2          A01X+011592Y+041500X0198Y0197R180 S1      
317RST_BMC_HW_OUT   VIA   -    M      A01X+011280Y+041249X0200Y         S2      
017RST_BMC_HW_OUT   VIA   -    M      A12X+011280Y+041249X0260Y         S2      
017RST_BMC_HW_OUT         -    MD0100PA00X+011280Y+041249                       
327m0000            R882  -2   M      A12X+026842Y+005300X0198Y0197     S2      
327m0000            R883  -2          A12X+026842Y+005700X0198Y0197     S2      
327m0000            C335  -1   M      A12X+026842Y+004900X0198Y0197R180 S2      
317m0000            VIA   -    MD0100PA00X+026850Y+004550X0200Y         S0      
327m0000            U57   -2          A01X+026450Y+004500X0400Y0150     S1      
327NC_U57_P1        U57   -1          A01X+026450Y+004756X0400Y0150     S1      
327m0001            VIA   -    M      A12X+025911Y+006600X0260Y         S2      
327m0001            R884  -1          A12X+026142Y+005300X0198Y0197R180 S2      
317m0001            VIA   -    MD0100PA00X+026005Y+008703X0200Y         S0      
317m0001            VIA   -    MD0100PA00X+024130Y+015975X0180Y         S0      
327m0001            U5    -C6         A01X+023974Y+016130X0160Y    R180 S1      
317m0002            VIA   -    M      A01X+026794Y+004112X0200Y         S2      
017m0002            VIA   -    M      A12X+026794Y+004112X0260Y         S2      
017m0002                  -    MD0100PA00X+026794Y+004112                       
327m0002            U57   -4          A01X+027150Y+004244X0400Y0150     S1      
327m0002            R884  -2          A12X+026458Y+005300X0198Y0197R180 S2      
327m0002            R885  -2   M      A12X+026458Y+004900X0198Y0197R180 S2      
317LED_D22_R1       D22   -C    D0320PA00X+024772Y+002476X0480Y         S3      
327LED_D22_R1       Q13   -6          A01X+025324Y+004656X0170Y0200R090 S1      
317LED_D22_R        D22   -A    D0320PA00X+023772Y+002476X0480Y0480     S3      
327LED_D22_R        C27   -1          A01X+023300Y+004142X0198Y0197R090 S1      
327LED_D22_R        R80   -1   M      A01X+023700Y+004142X0198Y0197R090 S1      
317m0003            D13   -C    D0320PA00X+012705Y+002476X0480Y         S3      
327m0003            Q9    -6          A01X+013274Y+004446X0170Y0200R090 S1      
327m0004            SW8   -2          A01X+028681Y+002910X0590Y0790     S1      
327m0004            R882  -1          A12X+027158Y+005300X0198Y0197     S2      
317m0004            VIA   -    MD0100PA00X+027993Y+005169X0200Y         S0      
327m0004            R471  -1   M      A01X+028600Y+004142X0198Y0197R090 S1      
327m0004            R470  -1   M      A01X+028150Y+004142X0198Y0197R090 S1      
327m0004            C181  -1   M      A01X+029024Y+004143X0198Y0197R090 S1      
327m0004            D10   -A   M      A01X+029540Y+004188X0220Y0240R090 S1      
327NC_U16_P1        VIA   -           A01X+028029Y+006043X0300Y         S1      
327NC_U16_P1        U16   -1          A01X+028600Y+005706X0400Y0150     S1      
327m0005            R10   -1          A12X+002100Y+031942X0198Y0197R270 S2      
327m0005            U25   -F8         A01X+008606Y+036058X0160Y    R180 S1      
327m0005            VIA   -    M      A12X+002910Y+032700X0260Y         S2      
317m0005            VIA   -    MD0100PA00X+003270Y+039538X0200Y         S0      
317m0005            VIA   -    MD0100PA00X+008762Y+035902X0180Y         S0      
327m0006            R388  -2          A01X+001700Y+031692X0198Y0197R270 S1      
327m0006            R614  -1   M      A01X+002100Y+032008X0198Y0197R270 S1      
327m0006            U6    -3          A01X+002826Y+032244X0170Y0240R270 S1      
317m0007            VIA   -    MD0100PA00X+015280Y+011160X0200Y         S0      
327m0007            R392  -2          A01X+015530Y+010438X0198Y0197R090 S1      
317m0007            VIA   -    MD0100PA00X+017835Y+015975X0180Y         S0      
327m0007            U5    -C25        A01X+017990Y+016130X0160Y    R180 S1      
327m0008            R392  -1          A01X+015530Y+010122X0198Y0197R090 S1      
327m0008            U28   -2          A01X+016188Y+010340X0180Y0520R270 S1      
327m0009            VIA   -    M      A01X+028012Y+005520X0300Y         S1      
327m0009            U16   -2          A01X+028600Y+005450X0400Y0150     S1      
327m0009            C28   -1   M      A01X+028600Y+006242X0198Y0197R090 S1      
327m0009            R391  -2   M      A01X+029000Y+006242X0198Y0197R270 S1      
327m0009            R470  -2          A01X+028150Y+004458X0198Y0197R090 S1      
327m0010            R395  -1          A01X+017800Y+010422X0198Y0197R090 S1      
327m0010            U28   -4          A01X+017152Y+009966X0180Y0520R270 S1      
317m0011            D15   -A    D0320PA00X+009047Y+002476X0480Y0480     S3      
327m0011            R569  -1          A12X+008650Y+007208X0198Y0197R090 S2      
327m0011            C197  -1   M      A12X+009050Y+007192X0198Y0197R270 S2      
317LED_D21_R3       D21   -A    D0320PA00X+021114Y+002476X0480Y0480     S3      
327LED_D21_R3       R107  -1          A01X+021100Y+004092X0198Y0197R090 S1      
327LED_D21_R2       VIA   -    M      A01X+021287Y+004879X0300Y         S1      
327LED_D21_R2       R286  -1          A01X+021500Y+004408X0198Y0197R270 S1      
327LED_D21_R2       R107  -2          A01X+021100Y+004408X0198Y0197R090 S1      
327LED_D21_R1       R286  -2          A01X+021500Y+004092X0198Y0197R270 S1      
327LED_D21_R1       R389  -1          A01X+021900Y+004092X0198Y0197R090 S1      
327FM_ID_R_LED      VIA   -    M      A01X+012400Y+005010X0300Y         S1      
327FM_ID_R_LED      R390  -2          A01X+012742Y+005000X0198Y0197R180 S1      
327FM_ID_R_LED      U9    -2          A01X+010878Y+005150X0280Y0400R270 S1      
327m0012            R463  -2          A01X+005048Y+040135X0198Y0197     S1      
327m0012            U25   -N15        A01X+006401Y+038263X0160Y    R180 S1      
327m0013            U16   -4          A01X+029300Y+005194X0400Y0150     S1      
317m0013            VIA   -    M      A01X+029747Y+005152X0200Y         S2      
017m0013            VIA   -    M      A12X+029747Y+005152X0260Y         S2      
017m0013                  -    MD0100PA00X+029747Y+005152                       
317m0013            VIA   -    MD0100PA00X+020914Y+005366X0200Y         S0      
327m0013            R463  -1   M      A01X+004732Y+040135X0198Y0197     S1      
327m0013            R472  -2          A01X+005048Y+039785X0198Y0197     S1      
317m0013            VIA   -    MD0100PA00X+005241Y+019019X0200Y         S0      
317m0013            VIA   -    MD0100PA00X+006423Y+030321X0200Y         S0      
317m0013            VIA   -    MD0100PA00X+004433Y+040145X0200Y         S0      
317AC_PWR_BTN_N     VIA   -    MD0100PA00X+029914Y+024451X0200Y         S0      
317AC_PWR_BTN_N     VIA   -    M      A01X+028600Y+004700X0200Y         S2      
017AC_PWR_BTN_N     VIA   -    M      A12X+028600Y+004700X0260Y         S2      
017AC_PWR_BTN_N           -    MD0100PA00X+028600Y+004700                       
327AC_PWR_BTN_N     R471  -2          A01X+028600Y+004458X0198Y0197R090 S1      
317AC_PWR_BTN_N     VIA   -    MD0100PA00X+028748Y+039668X0200Y         S0      
317AC_PWR_BTN_N     VIA   -    MD0100PA00X+012593Y+043311X0200Y         S0      
327AC_PWR_BTN_N     GF1   -B42        A01X+013959Y+046638X0150Y0840R180 S1      
327m0014            VIA   -    M      A01X+015550Y+020050X0300Y         S1      
317m0014            VIA   -    MD0100PA00X+015250Y+019950X0200Y         S0      
327m0014            R853  -1          A01X+016050Y+020252X0198Y0197R090 S1      
327m0014            U5    -AB21       A01X+019250Y+022115X0160Y    R180 S1      
317m0014            VIA   -    MD0100PA00X+019409Y+021955X0180Y         S0      
327m0015            R123  -2          A01X+009800Y+033128X0198Y0197R090 S1      
327m0015            U25   -B5         A01X+009551Y+034798X0160Y    R180 S1      
327m0016            R767  -2          A12X+011937Y+034870X0198Y0197R090 S2      
327m0016            U25   -C4         A01X+009866Y+035113X0160Y    R180 S1      
327m0016            VIA   -    M      A12X+011937Y+034405X0260Y         S2      
317m0016            VIA   -    MD0100PA00X+010022Y+034957X0180Y         S0      
327BSM_PRSNT_R1_N   R459  -2          A12X+010595Y+034165X0198Y0197     S2      
327BSM_PRSNT_R1_N   U25   -A3         A01X+010181Y+034483X0160Y    R180 S1      
317BSM_PRSNT_R1_N   VIA   -    MD0100PA00X+010025Y+034639X0180Y         S2      
327m0017            R519  -2          A12X+011444Y+036262X0198Y0197     S2      
327m0017            U25   -E6         A01X+009236Y+035743X0160Y    R180 S1      
317m0017            VIA   -    MD0100PA00X+011146Y+036177X0200Y         S0      
317m0017            VIA   -    MD0100PA00X+009392Y+035587X0180Y         S0      
327m0018            R65   -1          A01X+014150Y+023842X0198Y0197R090 S1      
327m0018            U5    -T24        A01X+018305Y+020225X0160Y    R180 S1      
317m0018            VIA   -    MD0100PA00X+018150Y+020066X0180Y         S0      
317m0018            VIA   -    M      A01X+014270Y+022782X0200Y         S2      
017m0018            VIA   -    M      A12X+014270Y+022782X0260Y         S2      
017m0018                  -    MD0100PA00X+014270Y+022782                       
327m0019            R58   -2          A01X+010350Y+027258X0198Y0197R090 S1      
327m0019            J4    -28         A01X+009547Y+028882X0110Y0630     S1      
327BSM_PRSNT_R_N    R459  -1          A12X+010910Y+034165X0198Y0197     S2      
327BSM_PRSNT_R_N    VIA   -    M      A12X+011406Y+034064X0260Y         S2      
317BSM_PRSNT_R_N    VIA   -    MD0100PA00X+013860Y+029590X0200Y         S0      
317BSM_PRSNT_R_N    VIA   -    MD0100PA00X+009150Y+026700X0200Y         S0      
327BSM_PRSNT_R_N    R57   -1          A01X+009150Y+026942X0198Y0197R090 S1      
317BSM_PRSNT_R_N    VIA   -    MD0100PA00X+020669Y+022585X0180Y         S0      
327BSM_PRSNT_R_N    U5    -AC16       A01X+020825Y+022430X0160Y    R180 S1      
317BSM_PRSNT_R_N    VIA   -    MD0100PA00X+012980Y+032580X0200Y         S0      
317BSM_PRSNT_R_N    VIA   -    MD0100PA00X+011560Y+033790X0200Y         S0      
327BSM_PRSNT_N      R404  -2          A01X+009550Y+027258X0198Y0197R090 S1      
327BSM_PRSNT_N      R57   -2   M      A01X+009150Y+027258X0198Y0197R090 S1      
327BSM_PRSNT_N      J4    -16         A01X+008366Y+028882X0110Y0630     S1      
327U56_ADJ_1        R677  -1          A01X+029742Y+030700X0198Y0197     S1      
327U56_ADJ_1        U56   -4          A01X+029776Y+032038X0280Y0400R180 S1      
327U56_ADJ_1        R631  -2   M      A01X+029742Y+031150X0198Y0197R180 S1      
327P3V3_LDO         C227  -1          A01X+030492Y+031150X0198Y0197     S1      
317P3V3_LDO         VIA   -    MD0100PA00X+016910Y+011390X0200Y         S0      
327P3V3_LDO         U28   -5          A01X+017152Y+010714X0180Y0520R270 S1      
327P3V3_LDO         C180  -1   M      A01X+016638Y+011280X0198Y0197R180 S1      
317P3V3_LDO         VIA   -    MD0100PA00X+016620Y+010550X0200Y         S0      
317P3V3_LDO         VIA   -    M      A01X+030620Y+030880X0200Y         S2      
017P3V3_LDO         VIA   -    M      A12X+030620Y+030880X0260Y         S2      
017P3V3_LDO               -    MD0100PA00X+030620Y+030880                       
327P3V3_LDO         C301  -1   M      A12X+031122Y+026030X0198Y0197R180 S2      
327P3V3_LDO         U52   -5          A12X+031154Y+026651X0130Y0460R180 S2      
317P3V3_LDO         VIA   -    MD0100PA00X+030780Y+025920X0200Y         S0      
327P3V3_LDO         U56   -5          A01X+030524Y+032038X0280Y0400R180 S1      
327P3V3_LDO         R631  -1          A01X+030058Y+031150X0198Y0197R180 S1      
317P3V3_LDO         VIA   -    MD0100PA00X+030300Y+030920X0200Y         S0      
327P3V3_LDO         C298  -1   M      A01X+013358Y+025370X0198Y0197R180 S1      
327P3V3_LDO         U49   -5          A01X+013582Y+024774X0280Y0400R270 S1      
317P3V3_LDO         VIA   -    MD0100PA00X+013300Y+025610X0200Y         S0      
327P3V3_LDO         C297  -1   M      A01X+004668Y+024100X0198Y0197R180 S1      
327P3V3_LDO         U42   -5          A01X+004776Y+023552X0280Y0400     S1      
317P3V3_LDO         VIA   -    MD0100PA00X+005057Y+023863X0200Y         S0      
327P3V3_LDO         U53   -5          A01X+006456Y+014101X0130Y0460R180 S1      
327P3V3_LDO         C302  -1   M      A01X+006400Y+013328X0198Y0197R270 S1      
317P3V3_LDO         VIA   -    MD0100PA00X+006112Y+013307X0200Y    R180 S0      
317P3V3_LDO         VIA   -    M      A01X+005970Y+019620X0200Y         S2      
017P3V3_LDO         VIA   -    M      A12X+005970Y+019620X0260Y         S2      
017P3V3_LDO               -    MD0100PA00X+005970Y+019620                       
327P3V3_LDO         U18   -5          A01X+006226Y+019741X0130Y0460R180 S1      
327P3V3_LDO         C296  -1   M      A01X+006040Y+018998X0198Y0197R270 S1      
327m0020            R303  -2          A12X+007200Y+032792X0198Y0197R090 S2      
327m0020            R114  -2          A01X+007100Y+040608X0198Y0197R090 S1      
327m0020            R850  -1          A01X+011150Y+026792X0198Y0197R090 S1      
317m0020            VIA   -    M      A01X+006060Y+031800X0200Y         S2      
017m0020            VIA   -    M      A12X+006060Y+031800X0260Y         S2      
017m0020                  -    MD0100PA00X+006060Y+031800                       
327m0020            VIA   -    M      A12X+019450Y+010620X0260Y         S2      
317m0020            VIA   -    MD0100PA00X+034218Y+010690X0200Y         S0      
327m0020            R33   -1          A01X+028969Y+039160X0198Y0197     S1      
317m0020            VIA   -    MD0100PA00X+028763Y+038938X0200Y         S0      
317m0020            VIA   -    MD0100PA00X+006970Y+040880X0200Y         S0      
317m0020            VIA   -    MD0100PA00X+020150Y+006100X0200Y         S0      
327m0020            R880  -1          A12X+019600Y+011192X0198Y0197R270 S2      
327m0021            R272  -2          A12X+006800Y+031642X0198Y0197R090 S2      
327m0021            R105  -2          A01X+006700Y+040608X0198Y0197R090 S1      
327m0021            R879  -1          A12X+020000Y+011192X0198Y0197R270 S2      
327m0021            R849  -1          A01X+010740Y+027032X0198Y0197R090 S1      
317m0021            VIA   -    MD0100PA00X+034220Y+010050X0200Y         S0      
327m0021            R47   -2          A01X+028969Y+038750X0198Y0197R180 S1      
317m0021            VIA   -    MD0100PA00X+006061Y+031201X0200Y         S0      
317m0021            VIA   -    MD0100PA00X+028519Y+039084X0200Y         S0      
317m0021            VIA   -    MD0100PA00X+006700Y+040880X0200Y         S0      
327m0021            VIA   -    M      A12X+006540Y+031190X0260Y         S2      
317m0021            VIA   -    MD0100PA00X+020430Y+006060X0200Y         S0      
327m0022            R872  -2          A01X+028130Y+010832X0198Y0197R270 S1      
327m0022            R876  -1          A01X+030531Y+027710X0198Y0197     S1      
327m0022            VIA   -    M      A01X+031508Y+009598X0300Y         S1      
317m0022            VIA   -    MD0100PA00X+032050Y+010040X0200Y         S0      
317m0022            VIA   -    MD0100PA00X+029884Y+027964X0200Y         S0      
327m0023            R873  -1          A12X+031020Y+013018X0198Y0197R270 S2      
327m0023            R875  -1          A01X+012872Y+022776X0198Y0197R270 S1      
317m0023            VIA   -    M      A01X+026499Y+010173X0300Y         S1      
017m0023            VIA   -    M      A12X+026499Y+010173X0200Y         S1      
017m0023                  -    MD0100PA00X+026499Y+010173                       
317m0023            VIA   -    MD0100PA00X+012423Y+022519X0200Y         S0      
327m0024            R869  -1          A01X+027730Y+010582X0198Y0197R090 S1      
327m0024            R874  -1          A01X+014950Y+023258X0198Y0197R270 S1      
327m0024            VIA   -    M      A01X+034520Y+010584X0300Y         S1      
317m0024            VIA   -    MD0100PA00X+015104Y+023787X0200Y         S0      
317m0024            VIA   -    MD0100PA00X+031711Y+021914X0200Y         S0      
327m0025            R877  -2          A01X+033650Y+030338X0198Y0197R090 S1      
327m0025            R878  -1          A01X+006009Y+012308X0198Y0197R090 S1      
327m0025            VIA   -    M      A01X+029172Y+009561X0300Y         S1      
317m0025            VIA   -    MD0100PA00X+005994Y+012063X0200Y         S0      
317m0025            VIA   -    MD0100PA00X+028091Y+010288X0200Y         S0      
327EN_P3V3_R1       R868  -2          A01X+003372Y+021470X0198Y0197R180 S1      
327EN_P3V3_R1       R871  -1          A01X+004668Y+024490X0198Y0197R180 S1      
327EN_P3V3_R1       VIA   -    M      A12X+004780Y+024084X0260Y         S2      
317EN_P3V3_R1       VIA   -    MD0100PA00X+003570Y+021800X0200Y         S0      
317EN_P3V3_R1       VIA   -    MD0100PA00X+004970Y+024290X0200Y         S0      
327m0026            R850  -2          A01X+011150Y+027108X0198Y0197R090 S1      
327m0026            J4    -42         A01X+010925Y+028882X0110Y0630     S1      
327m0027            J4    -40         A01X+010728Y+028882X0110Y0630     S1      
327m0027            R849  -2          A01X+010740Y+027348X0198Y0197R090 S1      
317m0028            VIA   -    M      A01X+030893Y+040190X0200Y         S2      
017m0028            VIA   -    M      A12X+030893Y+040190X0260Y         S2      
017m0028                  -    MD0100PA00X+030893Y+040190                       
327m0028            GF1   -OB13       A01X+026953Y+046638X0150Y0840R180 S1      
317m0028            VIA   -    MD0100PA00X+026956Y+045604X0200Y         S0      
317m0028            VIA   -    MD0100PA00X+018779Y+016920X0180Y         S0      
327m0028            U5    -F22        A01X+018935Y+017075X0160Y    R180 S1      
327FM_INTRUDER_N    R853  -2          A01X+016050Y+020568X0198Y0197R090 S1      
317FM_INTRUDER_N    VIA   -    MD0100PA00X+016630Y+021230X0180Y         S0      
317FM_INTRUDER_N    VIA   -    MD0100PA00X+023540Y+030380X0200Y         S0      
317FM_INTRUDER_N    VIA   -    MD0100PA00X+023379Y+038449X0200Y         S0      
317FM_INTRUDER_N    VIA   -    MD0100PA00X+008155Y+040966X0200Y         S0      
327FM_INTRUDER_N    VIA   -    M      A12X+008400Y+042550X0260Y         S2      
327FM_INTRUDER_N    GF1   -A54        A12X+009427Y+046559X0150Y0680R180 S2      
317FM_INTRUDER_N    VIA   -    M      A01X+009603Y+040940X0200Y         S2      
017FM_INTRUDER_N    VIA   -    M      A12X+009603Y+040940X0260Y         S2      
017FM_INTRUDER_N          -    MD0100PA00X+009603Y+040940                       
317FM_INTRUDER_N    VIA   -    MD0100PA00X+011903Y+039333X0200Y         S0      
327m0029            R854  -2          A01X+028500Y+007908X0198Y0197R090 S1      
327m0029            R855  -1          A12X+028500Y+007908X0198Y0197R090 S2      
327m0029            U5    -F5         A01X+024289Y+017075X0160Y    R180 S1      
317m0029            VIA   -    MD0100PA00X+024445Y+016920X0180Y         S0      
317m0029            VIA   -    M      A01X+028250Y+008354X0200Y         S2      
017m0029            VIA   -    M      A12X+028250Y+008354X0260Y         S2      
017m0029                  -    MD0100PA00X+028250Y+008354                       
327m0030            R856  -2          A01X+028100Y+007908X0198Y0197R090 S1      
327m0030            R857  -1          A12X+028100Y+007908X0198Y0197R090 S2      
327m0030            U5    -E4         A01X+024604Y+016760X0160Y    R180 S1      
317m0030            VIA   -    MD0100PA00X+024760Y+016605X0180Y         S0      
317m0030            VIA   -    M      A01X+027750Y+008354X0200Y         S2      
017m0030            VIA   -    M      A12X+027750Y+008354X0260Y         S2      
017m0030                  -    MD0100PA00X+027750Y+008354                       
327m0031            R858  -2          A01X+027700Y+007908X0198Y0197R090 S1      
327m0031            R865  -1          A12X+027700Y+007908X0198Y0197R090 S2      
327m0031            U5    -D3         A01X+024919Y+016445X0160Y    R180 S1      
317m0031            VIA   -    MD0100PA00X+024764Y+016290X0180Y         S0      
317m0031            VIA   -    M      A01X+027250Y+008354X0200Y         S2      
017m0031            VIA   -    M      A12X+027250Y+008354X0260Y         S2      
017m0031                  -    MD0100PA00X+027250Y+008354                       
327EMMC_WP          R867  -2          A01X+011110Y+027928X0198Y0197R090 S1      
327EMMC_WP          J4    -46         A01X+011319Y+028882X0110Y0630     S1      
327m0032            R544  -2          A12X+011548Y+024990X0198Y0197R180 S2      
327m0032            VIA   -    M      A12X+011548Y+025490X0260Y         S2      
327m0032            U7    -3          A12X+011944Y+026156X0140Y0440     S2      
327m0033            R544  -1          A12X+011232Y+024990X0198Y0197R180 S2      
317m0033            VIA   -    MD0100PA00X+016866Y+027516X0200Y         S0      
317m0033            VIA   -    MD0100PA00X+027462Y+042472X0200Y         S0      
327m0033            GF1   -OB8        A01X+028134Y+046638X0150Y0840R180 S1      
327m0033            VIA   -    M      A01X+028420Y+043290X0300Y         S1      
327m0034            R618  -2          A12X+013562Y+025070X0198Y0197     S2      
327m0034            U20   -3          A12X+013194Y+026156X0140Y0440     S2      
327m0034            VIA   -    M      A12X+013706Y+025557X0260Y         S2      
327m0035            R618  -1          A12X+013878Y+025070X0198Y0197     S2      
317m0035            VIA   -    MD0100PA00X+027510Y+042768X0200Y         S0      
327m0035            VIA   -    M      A01X+027840Y+042640X0300Y         S1      
327m0035            GF1   -OB9        A01X+027898Y+046638X0150Y0840R180 S1      
317m0035            VIA   -    MD0100PA00X+016871Y+027226X0200Y         S0      
327TP_GF_B63        VIA   -           A01X+006394Y+042706X0300Y         S1      
327TP_GF_B63        GF1   -B63        A01X+007301Y+046559X0150Y0680R180 S1      
327TP_GF_B62        VIA   -           A01X+006919Y+042900X0300Y         S1      
327TP_GF_B62        GF1   -B62        A01X+007537Y+046559X0150Y0680R180 S1      
327TP_GF_A63        GF1   -A63        A12X+007301Y+046559X0150Y0680R180 S2      
327TP_GF_A62        GF1   -A62        A12X+007537Y+046559X0150Y0680R180 S2      
327TP_GF_A45        GF1   -A45        A12X+011553Y+046559X0150Y0680R180 S2      
327m0036            U5    -AD13       A01X+021770Y+022745X0160Y    R180 S1      
317m0036            VIA   -     D0100PA00X+021925Y+022900X0180Y    R180 S0      
327m0037            R462  -2          A12X+015993Y+023918X0198Y0197R270 S2      
327m0037            R804  -1          A12X+015767Y+024263X0198Y0197     S2      
327m0037            U5    -W24        A01X+018305Y+021170X0160Y    R180 S1      
317m0037            VIA   -    MD0100PA00X+018464Y+021325X0180Y         S0      
317m0037            VIA   -    MD0100PA00X+017530Y+024000X0200Y         S0      
317m0037            VIA   -    MD0100PA00X+015720Y+024000X0200Y         S0      
327m0038            R546  -2          A12X+012938Y+024970X0198Y0197R180 S2      
327m0038            VIA   -    M      A12X+012456Y+025550X0260Y         S2      
327m0038            U7    -1          A12X+012456Y+026156X0140Y0440     S2      
327m0039            R39   -1          A01X+010150Y+026108X0198Y0197R270 S1      
317m0039            VIA   -    MD0100PA00X+010680Y+026208X0200Y         S0      
327m0039            U7    -4   M      A12X+011944Y+026944X0140Y0440     S2      
327m0039            VIA   -           A12X+011316Y+027093X0260Y         S2      
327m0040            R628  -2          A12X+013018Y+028300X0198Y0197R180 S2      
327m0040            U20   -1          A12X+013706Y+026156X0140Y0440     S2      
327m0040            VIA   -    M      A12X+013479Y+028300X0260Y         S2      
327m0041            U20   -4          A12X+013194Y+026944X0140Y0440     S2      
327m0041            R726  -1          A12X+008060Y+025798X0198Y0197R090 S2      
317m0041            VIA   -    MD0100PA00X+008402Y+025823X0200Y    R090 S0      
317m0041            VIA   -    MD0100PA00X+011910Y+025151X0200Y         S0      
317m0041            VIA   -    MD0100PA00X+013242Y+027381X0200Y         S0      
317m0042            VIA   -    MD0100PA00X+017835Y+018810X0180Y         S0      
327m0042            U5    -M25        A01X+017990Y+018965X0160Y    R180 S1      
317m0042            VIA   -    M      A01X+015082Y+038732X0200Y         S2      
017m0042            VIA   -    M      A12X+015082Y+038732X0260Y         S2      
017m0042                  -    MD0100PA00X+015082Y+038732                       
327m0042            U25   -T7         A01X+008921Y+039208X0160Y    R180 S1      
317m0042            VIA   -    MD0100PA00X+008921Y+039418X0180Y         S0      
327PU_J13_P1        J13   -1          A01X+026491Y+005950X0400Y1090R090 S1      
327PU_J13_P1        R630  -2          A12X+025608Y+005150X0198Y0197R180 S2      
317PU_J13_P1        VIA   -    M      A01X+025600Y+005600X0200Y         S2      
017PU_J13_P1        VIA   -    M      A12X+025600Y+005600X0260Y         S2      
017PU_J13_P1              -    MD0100PA00X+025600Y+005600                       
327PCH_BEEP_R_LED   VIA   -    M      A12X+004530Y+042640X0260Y         S2      
327PCH_BEEP_R_LED   R811  -2          A12X+004040Y+042038X0198Y0197R270 S2      
327PCH_BEEP_R_LED   GF1   -B69        A01X+005884Y+046559X0150Y0680R180 S1      
317PCH_BEEP_R_LED   VIA   -    MD0100PA00X+005650Y+044760X0200Y         S0      
317m0043            VIA   -    M      A01X+017440Y+025194X0200Y         S2      
017m0043            VIA   -    M      A12X+017440Y+025194X0260Y         S2      
017m0043                  -    MD0100PA00X+017440Y+025194                       
317m0043            VIA   -    MD0100PA00X+009077Y+038418X0180Y         S0      
327m0043            U25   -N7         A01X+008921Y+038263X0160Y    R180 S1      
327m0043            U5    -F24        A01X+018305Y+017075X0160Y    R180 S1      
317m0043            VIA   -    MD0100PA00X+018150Y+016920X0180Y         S0      
327HDD_LED_R_N      VIA   -    M      A01X+005070Y+043910X0300Y         S1      
327HDD_LED_R_N      R564  -2          A01X+004860Y+043208X0198Y0197R090 S1      
327HDD_LED_R_N      GF1   -B68        A01X+006120Y+046559X0150Y0680R180 S1      
327m0044            U5    -AB26       A01X+017675Y+022115X0160Y    R180 S1      
317m0044            VIA   -    MD0100PA00X+017240Y+022070X0200Y         S0      
327m0044            U25   -P7         A01X+008921Y+038578X0160Y    R180 S1      
317m0044            VIA   -    MD0100PA00X+009077Y+038733X0180Y         S0      
317m0044            VIA   -    M      A01X+015820Y+038140X0200Y         S2      
017m0044            VIA   -    M      A12X+015820Y+038140X0260Y         S2      
017m0044                  -    MD0100PA00X+015820Y+038140                       
327m0045            U5    -Y24        A01X+018305Y+021485X0160Y    R180 S1      
317m0045            VIA   -    MD0100PA00X+018150Y+021640X0180Y         S0      
317m0045            VIA   -    MD0100PA00X+016550Y+023610X0200Y         S0      
317m0045            VIA   -    M      A01X+015250Y+038260X0200Y         S2      
017m0045            VIA   -    M      A12X+015250Y+038260X0260Y         S2      
017m0045                  -    MD0100PA00X+015250Y+038260                       
317m0045            VIA   -    MD0100PA00X+009077Y+039048X0180Y         S0      
327m0045            U25   -R7         A01X+008921Y+038892X0160Y    R180 S1      
327m0046            U5    -M24        A01X+018305Y+018965X0160Y    R180 S1      
317m0046            VIA   -    MD0100PA00X+018150Y+018810X0180Y         S2      
317m0046            VIA   -    M      A01X+016550Y+038280X0200Y         S2      
017m0046            VIA   -    M      A12X+016550Y+038280X0260Y         S2      
017m0046                  -    MD0100PA00X+016550Y+038280                       
317m0046            VIA   -    MD0100PA00X+008762Y+037788X0180Y         S0      
327m0046            U25   -L8         A01X+008606Y+037633X0160Y    R180 S1      
317m0047            VIA   -    MD0100PA00X+017184Y+019830X0180Y         S0      
327m0047            U5    -Y25        A01X+017990Y+021485X0160Y    R180 S1      
317m0047            VIA   -    M      A01X+015630Y+037630X0200Y         S2      
017m0047            VIA   -    M      A12X+015630Y+037630X0260Y         S2      
017m0047                  -    MD0100PA00X+015630Y+037630                       
317m0047            VIA   -    MD0100PA00X+009236Y+039418X0180Y         S0      
327m0047            U25   -T6         A01X+009236Y+039208X0160Y    R180 S1      
327m0047            R847  -2          A12X+004440Y+042038X0198Y0197R270 S2      
317m0047            VIA   -    MD0100PA00X+004610Y+042280X0200Y         S0      
317FM_HDD_LED_N     VIA   -    M      A01X+004510Y+043580X0200Y         S2      
017FM_HDD_LED_N     VIA   -    M      A12X+004510Y+043580X0260Y         S2      
017FM_HDD_LED_N           -    MD0100PA00X+004510Y+043580                       
317FM_HDD_LED_N     VIA   -    MD0100PA00X+009392Y+038733X0180Y         S0      
327FM_HDD_LED_N     U25   -P6         A01X+009236Y+038578X0160Y    R180 S1      
317FM_HDD_LED_N     VIA   -    MD0100PA00X+015210Y+037840X0200Y         S0      
327FM_HDD_LED_N     R838  -2          A01X+004470Y+043208X0198Y0197R090 S1      
317FM_HDD_LED_N     VIA   -    MD0100PA00X+017184Y+020066X0180Y         S0      
327FM_HDD_LED_N     U5    -Y26        A01X+017675Y+021485X0160Y    R180 S1      
327FM_DBG_SW_N      J13   -2          A01X+025409Y+006950X0400Y1090R090 S1      
327FM_DBG_SW_N      R629  -2          A12X+025300Y+007192X0198Y0197R090 S2      
327FM_DBG_SW_N      U7    -6          A12X+012456Y+026944X0140Y0440     S2      
327FM_DBG_SW_N      U20   -6   M      A12X+013706Y+026944X0140Y0440     S2      
327FM_DBG_SW_N      VIA   -    M      A12X+025290Y+008040X0260Y         S2      
317FM_DBG_SW_N      VIA   -    MD0100PA00X+021273Y+013215X0200Y         S0      
317FM_DBG_SW_N      VIA   -    MD0100PA00X+013720Y+027449X0200Y         S0      
317FM_DBG_SW_N      VIA   -    MD0100PA00X+024421Y+009730X0200Y         S0      
317FM_DBG_SW_N      VIA   -    MD0100PA00X+025000Y+007300X0200Y         S0      
317m0048            VIA   -    MD0100PA00X+020030Y+032880X0200Y         S0      
317m0048            VIA   -    M      A01X+016115Y+037670X0200Y         S2      
017m0048            VIA   -    M      A12X+016115Y+037670X0260Y         S2      
017m0048                  -    MD0100PA00X+016115Y+037670                       
317m0048            VIA   -    MD0100PA00X+009077Y+038103X0180Y         S0      
327m0048            U25   -M7         A01X+008921Y+037948X0160Y    R180 S1      
317m0048            VIA   -    MD0100PA00X+023044Y+032594X0200Y         S0      
317m0048            VIA   -    MD0100PA00X+022528Y+024600X0200Y         S0      
327m0048            U5    -AF10       A01X+022715Y+023374X0160Y    R180 S1      
327BMC_MONITER      U5    -T25        A01X+017990Y+020225X0160Y    R180 S1      
317BMC_MONITER      VIA   -    MD0100PA00X+017835Y+020380X0180Y         S0      
317BMC_MONITER      VIA   -    MD0100PA00X+009392Y+038103X0180Y         S0      
327BMC_MONITER      U25   -M6         A01X+009236Y+037948X0160Y    R180 S1      
317BMC_MONITER      VIA   -    MD0100PA00X+013870Y+037660X0200Y         S0      
327m0049            R543  -2          A01X+009950Y+027258X0198Y0197R090 S1      
327m0049            J4    -26         A01X+009350Y+028882X0110Y0630     S1      
327m0050            R552  -1          A01X+015522Y+029700X0198Y0197     S1      
327m0050            J4    -25         A01X+009252Y+031854X0110Y0630     S1      
327m0051            R550  -1          A01X+015522Y+030100X0198Y0197     S1      
327m0051            J4    -27         A01X+009449Y+031854X0110Y0630     S1      
327m0052            R558  -2   M      A01X+015522Y+030970X0198Y0197R180 S1      
327m0052            R547  -1          A12X+023538Y+030690X0198Y0197     S2      
327m0052            VIA   -    M      A01X+016600Y+030550X0300Y    R270 S1      
317m0052            VIA   -    MD0100PA00X+016210Y+029160X0200Y         S0      
327m0052            J4    -35         A01X+010236Y+031854X0110Y0630     S1      
317m0052            VIA   -    MD0100PA00X+022880Y+030550X0200Y         S0      
327m0053            R557  -2   M      A01X+015522Y+031356X0198Y0197R180 S1      
327m0053            R553  -1          A01X+016520Y+031742X0198Y0197R090 S1      
327m0053            VIA   -    M      A01X+016050Y+031850X0300Y    R270 S1      
327m0053            J4    -37         A01X+010433Y+031854X0110Y0630     S1      
327m0054            R549  -1          A01X+015522Y+030510X0198Y0197     S1      
327m0054            J4    -31         A01X+009842Y+031854X0110Y0630     S1      
327PU_J1_P1         R592  -2          A01X+018800Y+032098X0198Y0197R090 S1      
327PU_J1_P1         J1    -1          A01X+020841Y+032820X0400Y1090R090 S1      
327m0055            R555  -2          A01X+022608Y+030460X0198Y0197     S1      
327m0055            VIA   -    M      A01X+022608Y+030939X0300Y    R270 S1      
327m0055            R560  -1          A01X+022126Y+031028X0198Y0197R090 S1      
327m0056            R555  -1          A01X+022292Y+030460X0198Y0197     S1      
327m0056            VIA   -    M      A01X+021810Y+030560X0300Y    R180 S1      
327m0056            U54   -3          A01X+021099Y+030188X0160Y0340R090 S1      
327m0057            R556  -1          A01X+017592Y+032520X0198Y0197     S1      
317m0057            VIA   -    M      A01X+006120Y+028260X0200Y         S2      
017m0057            VIA   -    M      A12X+006120Y+028260X0260Y         S2      
017m0057                  -    MD0100PA00X+006120Y+028260                       
317m0057            VIA   -    MD0100PA00X+017056Y+030663X0200Y         S0      
327m0057            R664  -1          A01X+006120Y+027998X0198Y0197R270 S1      
327m0057            J4    -3          A01X+007087Y+031854X0110Y0630     S1      
327m0058            R559  -1          A01X+017592Y+032920X0198Y0197     S1      
327m0058            VIA   -    M      A01X+016750Y+031250X0300Y    R270 S1      
327m0058            J4    -5          A01X+007284Y+031854X0110Y0630     S1      
327m0058            R665  -1          A01X+006510Y+028008X0198Y0197R270 S1      
317m0058            VIA   -    MD0100PA00X+006510Y+028248X0200Y         S0      
317m0058            VIA   -    MD0100PA00X+016908Y+030868X0200Y         S0      
327RD_N             R548  -2          A01X+018648Y+030420X0198Y0197     S1      
327RD_N             VIA   -    M      A01X+019123Y+030550X0300Y    R270 S1      
327RD_N             U54   -6          A01X+019701Y+030188X0160Y0340R090 S1      
327NC_U55_P1        U55   -1          A01X+021079Y+031104X0130Y0460R090 S1      
327NC_U54_P1        U54   -5          A01X+019701Y+030464X0200Y0340R090 S1      
327NC_J1_P3         VIA   -           A01X+022410Y+035232X0300Y         S1      
327NC_J1_P3         J1    -3          A01X+020841Y+034820X0400Y1090R090 S1      
327m0059            R181  -2          A01X+018648Y+030020X0198Y0197     S1      
327m0059            U54   -7          A01X+019701Y+029932X0160Y0340R090 S1      
317m0059            VIA   -    M      A01X+019120Y+030020X0300Y    R180 S1      
017m0059            VIA   -    M      A12X+019120Y+030020X0200Y    R180 S1      
017m0059                  -    MD0100PA00X+019120Y+030020                       
317m0059            VIA   -    MD0100PA00X+020643Y+029878X0200Y         S0      
317m0059            VIA   -    MD0100PA00X+022283Y+026167X0200Y         S0      
327m0059            R465  -2          A01X+022204Y+025893X0198Y0197R180 S1      
327m0060            R551  -1          A01X+022060Y+031792X0198Y0197R090 S1      
327m0060            R466  -2          A01X+022230Y+028218X0198Y0197R090 S1      
327m0061            R554  -2          A01X+022060Y+032472X0198Y0197R270 S1      
327m0061            R551  -2   M      A01X+022060Y+032108X0198Y0197R090 S1      
327m0061            U55   -4          A01X+020321Y+031616X0130Y0460R090 S1      
327m0062            R559  -2   M      A01X+017908Y+032920X0198Y0197     S1      
327m0062            R556  -2          A01X+017908Y+032520X0198Y0197     S1      
327m0062            R560  -2   M      A01X+022126Y+031344X0198Y0197R090 S1      
327m0062            J1    -2   M      A01X+019759Y+033820X0400Y1090R090 S1      
327m0062            U55   -2          A01X+021079Y+031360X0130Y0460R090 S1      
327FLASH_LATCH_D    VIA   -    M      A01X+021767Y+030060X0300Y    R180 S1      
327FLASH_LATCH_D    U54   -2          A01X+021099Y+029932X0160Y0340R090 S1      
327FLASH_LATCH_D    R182  -2          A01X+022292Y+030060X0198Y0197R180 S1      
327FLASH_LATCH_CP   VIA   -    M      A01X+021740Y+029520X0300Y    R180 S1      
327FLASH_LATCH_CP   U54   -1          A01X+021099Y+029656X0200Y0340R090 S1      
327FLASH_LATCH_CP   R545  -2          A01X+022292Y+029660X0198Y0197R180 S1      
327BMC_RSTIND_N     R585  -1          A01X+028428Y+009326X0198Y0197R180 S1      
327BMC_RSTIND_N     R548  -1          A01X+018332Y+030420X0198Y0197     S1      
317BMC_RSTIND_N     VIA   -    MD0100PA00X+016830Y+030110X0200Y         S0      
317BMC_RSTIND_N     VIA   -    MD0100PA00X+010610Y+028290X0200Y         S0      
327BMC_RSTIND_N     VIA   -    M      A01X+028027Y+008847X0300Y         S1      
317BMC_RSTIND_N     VIA   -    MD0100PA00X+022289Y+010124X0200Y         S0      
327m0063            R530  -2          A01X+012250Y+025362X0198Y0197R270 S1      
327m0063            C310  -1   M      A01X+012650Y+025362X0198Y0197R090 S1      
327m0063            U49   -2          A01X+012638Y+024400X0280Y0400R270 S1      
327m0064            VIA   -    M      A01X+005498Y+021590X0300Y         S1      
327m0064            R529  -2          A01X+005498Y+022060X0198Y0197     S1      
327m0064            C305  -1   M      A01X+005472Y+021120X0198Y0197R180 S1      
327m0064            U18   -2          A01X+005970Y+020499X0130Y0460R180 S1      
327EN_P3V3_RGM      R380  -1          A01X+026590Y+010992X0198Y0197R090 S1      
327EN_P3V3_RGM      U18   -4          A01X+005714Y+019741X0130Y0460R180 S1      
317EN_P3V3_RGM      VIA   -    M      A01X+005241Y+018690X0200Y         S2      
017EN_P3V3_RGM      VIA   -    M      A12X+005241Y+018690X0260Y         S2      
017EN_P3V3_RGM            -    MD0100PA00X+005241Y+018690                       
317EN_P3V3_RGM      VIA   -    MD0100PA00X+027539Y+010271X0200Y         S0      
327EN_P3V3          VIA   -    M      A01X+005524Y+024370X0300Y         S1      
327EN_P3V3          U42   -4          A01X+005524Y+023552X0280Y0400     S1      
327EN_P3V3          R381  -1          A01X+004748Y+024880X0198Y0197R180 S1      
327EN_P1V8          VIA   -    M      A01X+013240Y+023240X0300Y         S1      
327EN_P1V8          R393  -1          A01X+013240Y+022777X0198Y0197R270 S1      
327EN_P1V8          U49   -4          A01X+013582Y+024026X0280Y0400R270 S1      
317EN_P1V2_AUX      VIA   -    MD0100PA00X+030288Y+027969X0200Y         S0      
327EN_P1V2_AUX      R708  -1          A01X+030531Y+028109X0198Y0197     S1      
327EN_P1V2_AUX      U52   -4          A12X+031666Y+026651X0130Y0460R180 S2      
327EN_P1V2_AUX      VIA   -    M      A12X+031628Y+025538X0260Y         S2      
317EN_P1V0_AUX      VIA   -    M      A01X+005994Y+011780X0200Y    R180 S2      
017EN_P1V0_AUX      VIA   -    M      A12X+005994Y+011780X0260Y    R180 S2      
017EN_P1V0_AUX            -    MD0100PA00X+005994Y+011780                       
327EN_P1V0_AUX      R399  -1          A01X+006392Y+012308X0198Y0197R090 S1      
327EN_P1V0_AUX      U53   -4          A01X+005944Y+014101X0130Y0460R180 S1      
317EN_P1V0_AUX      VIA   -    M      A01X+006080Y+013700X0200Y    R180 S2      
017EN_P1V0_AUX      VIA   -    M      A12X+006080Y+013700X0260Y    R180 S2      
017EN_P1V0_AUX            -    MD0100PA00X+006080Y+013700                       
327J7_P1            C215  -1          A01X+003452Y+041570X0198Y0197     S1      
327J7_P1            C217  -1          A01X+003452Y+041190X0198Y0197     S1      
327J7_P1            D20   -2          A01X+003219Y+042260X0460Y0690     S1      
317J7_P1            J7    -1    D0410PA00X+002382Y+040915X0610Y0610     S3      
317m0065            VIA   -    M      A01X+020615Y+041282X0200Y         S2      
017m0065            VIA   -    M      A12X+020615Y+041282X0260Y         S2      
017m0065                  -    MD0100PA00X+020615Y+041282                       
327m0065            R455  -2          A01X+016440Y+012308X0198Y0197R090 S1      
317m0065            VIA   -    MD0100PA00X+016880Y+012680X0200Y         S0      
327m0065            GF1   -A5         A12X+024041Y+046638X0150Y0840R180 S2      
317m0065            VIA   -    MD0100PA00X+024020Y+045065X0200Y         S0      
327m0066            R415  -1          A01X+003788Y+026450X0198Y0197R180 S1      
327m0066            PU1   -10         A01X+003070Y+025841X0100Y0360R180 S1      
327U41_ADJ          U41   -4          A01X+015047Y+022219X0110Y0360R090 S1      
327U41_ADJ          R832  -1          A01X+016003Y+021979X0198Y0197R270 S1      
327U41_ADJ          R831  -2   M      A01X+015603Y+021979X0198Y0197R090 S1      
327U39_ADJ          U39   -4          A01X+032338Y+013831X0110Y0360R180 S1      
327U39_ADJ          R830  -1          A01X+032605Y+014844X0198Y0197     S1      
327U39_ADJ          R829  -2   M      A01X+032605Y+014442X0198Y0197R180 S1      
317PU_FWSPIWP_N_R   VIA   -    M      A01X+022640Y+026634X0300Y         S1      
017PU_FWSPIWP_N_R   VIA   -    M      A12X+022640Y+026634X0200Y         S1      
017PU_FWSPIWP_N_R         -    MD0100PA00X+022640Y+026634                       
327PU_FWSPIWP_N_R   R402  -2          A12X+022340Y+026858X0198Y0197R270 S2      
327PU_FWSPIWP_N_R   U5    -AB12       A01X+022085Y+022115X0160Y    R180 S1      
317PU_FWSPIWP_N_R   VIA   -    MD0100PA00X+021929Y+022270X0180Y    R270 S0      
327m0067            R401  -2          A12X+022258Y+024580X0198Y0197R180 S2      
327m0067            U5    -AC12       A01X+022085Y+022430X0160Y    R180 S1      
317m0067            VIA   -    MD0100PA00X+021929Y+022585X0180Y    R270 S2      
327m0068            R114  -1          A01X+007100Y+040292X0198Y0197R090 S1      
327m0068            U25   -R14        A01X+006716Y+038892X0160Y    R180 S1      
327m0069            R105  -1          A01X+006700Y+040292X0198Y0197R090 S1      
327m0069            U25   -T15        A01X+006401Y+039208X0160Y    R180 S1      
327PU_PT20D         R297  -1          A01X+007650Y+033120X0198Y0197R270 S1      
327PU_PT20D         U25   -B10        A01X+007976Y+034798X0160Y    R180 S1      
327PU_PB25A         R288  -2          A01X+007500Y+040292X0198Y0197R270 S1      
327PU_PB25A         U25   -R12        A01X+007346Y+038892X0160Y    R180 S1      
317FM_JTAG_SEL      VIA   -    M      A01X+013530Y+017510X0200Y         S2      
017FM_JTAG_SEL      VIA   -    M      A12X+013530Y+017510X0260Y         S2      
017FM_JTAG_SEL            -    MD0100PA00X+013530Y+017510                       
327FM_JTAG_SEL      U5    -G23        A01X+018620Y+017390X0160Y    R180 S1      
317FM_JTAG_SEL      VIA   -    MD0100PA00X+018464Y+017235X0180Y         S0      
327FM_JTAG_SEL      GF1   -A43        A12X+012026Y+046638X0150Y0840R180 S2      
317FM_JTAG_SEL      VIA   -    MD0100PA00X+012317Y+043320X0200Y         S0      
327m0070            VIA   -    M      A01X+025790Y+041670X0300Y         S1      
317m0070            VIA   -    MD0100PA00X+025436Y+030058X0200Y         S0      
317m0070            VIA   -    MD0100PA00X+025235Y+041285X0200Y         S0      
327m0070            R311  -2          A01X+025790Y+042362X0198Y0197R270 S1      
327m0070            U5    -AF7        A01X+023659Y+023374X0160Y    R180 S1      
327m0071            R310  -2          A01X+026190Y+042362X0198Y0197R270 S1      
317m0071            VIA   -    M      A01X+024123Y+040728X0300Y         S1      
017m0071            VIA   -    M      A12X+024123Y+040728X0200Y         S1      
017m0071                  -    MD0100PA00X+024123Y+040728                       
317m0071            VIA   -    MD0100PA00X+024890Y+030490X0200Y         S0      
327m0071            U5    -AE7        A01X+023659Y+023060X0160Y    R180 S1      
317m0071            VIA   -    MD0100PA00X+023504Y+022904X0180Y         S0      
317m0071            VIA   -    MD0100PA00X+024930Y+023760X0200Y         S0      
327m0072            R54   -1          A12X+008250Y+006892X0198Y0197R270 S2      
317m0072            J14   -6    D0410PA00X+008571Y+005224X0610Y         S3      
327TMC75_A2         VIA   -    M      A12X+010572Y+005972X0260Y         S2      
327TMC75_A2         R419  -1          A12X+009450Y+007258X0198Y0197R090 S2      
327TMC75_A2         R418  -2   M      A12X+009850Y+007258X0198Y0197R270 S2      
317TMC75_A2         J14   -7    D0410PA00X+009571Y+004224X0610Y         S3      
317TMC75_A1         J14   -5    D0410PA00X+008571Y+004224X0610Y         S3      
327TMC75_A1         R53   -1   M      A12X+007650Y+007208X0198Y0197R090 S2      
327TMC75_A1         R52   -2          A12X+008108Y+007600X0198Y0197R180 S2      
327TMC75_A0         R417  -1          A12X+007208Y+007650X0198Y0197     S2      
327TMC75_A0         R416  -2   M      A12X+006850Y+007208X0198Y0197R270 S2      
317TMC75_A0         J14   -3    D0410PA00X+007571Y+004224X0610Y         S3      
327VCCIO5           R301  -2          A12X+010400Y+036092X0198Y0197R090 S2      
327VCCIO5           C160  -1   M      A12X+010342Y+035750X0164Y0164R180 S2      
327VCCIO5           C218  -1          A12X+010181Y+035428X0164Y0164R180 S2      
317VCCIO5           VIA   -    MD0100PA00X+010022Y+035587X0180Y         S0      
327VCCIO5           U25   -E4         A01X+009866Y+035743X0160Y    R180 S1      
327VCCIO4           C195  -1          A12X+009442Y+037100X0164Y0164R180 S2      
327VCCIO4           C220  -1          A12X+009442Y+036750X0164Y0164R180 S2      
327VCCIO4           R307  -2          A12X+009692Y+036400X0198Y0197     S2      
317VCCIO4           VIA   -    MD0100PA00X+009077Y+036532X0180Y         S0      
327VCCIO4           U25   -H7         A01X+008921Y+036688X0160Y    R180 S1      
327VCCIO4           C162  -1          A12X+009076Y+036853X0164Y0164     S2      
317VCCIO4           VIA   -    MD0100PA00X+009077Y+037158X0180Y         S0      
327VCCIO4           U25   -J7         A01X+008921Y+037003X0160Y    R180 S1      
327VCCIO3           VIA   -           A12X+010590Y+037690X0260Y         S2      
327VCCIO3           R308  -2          A12X+010120Y+037488X0198Y0197R270 S2      
317VCCIO3           VIA   -    MD0100PA00X+010022Y+038103X0180Y         S0      
327VCCIO3           U25   -M4         A01X+009866Y+037948X0160Y    R180 S1      
327VCCIO3           C216  -1          A12X+010054Y+037830X0164Y0164     S2      
327VCCIO3           C152  -1          A12X+010380Y+038142X0198Y0197R270 S2      
327VCCIO2           R297  -2          A01X+007650Y+032806X0198Y0197R270 S1      
327VCCIO2           R288  -1          A01X+007500Y+040608X0198Y0197R270 S1      
317VCCIO2           VIA   -    M      A01X+007398Y+040866X0200Y         S2      
017VCCIO2           VIA   -    M      A12X+007398Y+040866X0260Y         S2      
017VCCIO2                 -    MD0100PA00X+007398Y+040866                       
317VCCIO2           VIA   -    MD0100PA00X+007650Y+032550X0200Y         S0      
327VCCIO2           C260  -1          A12X+009866Y+038262X0164Y0164R270 S2      
327VCCIO2           C188  -1          A12X+009551Y+038263X0164Y0164     S2      
317VCCIO2           VIA   -    MD0100PA00X+009707Y+038418X0180Y         S0      
327VCCIO2           U25   -N5         A01X+009551Y+038263X0160Y    R180 S1      
327VCCIO2           R304  -2          A12X+007500Y+038692X0198Y0197R090 S2      
327VCCIO2           C165  -1          A12X+007348Y+038263X0164Y0164R090 S2      
317VCCIO2           VIA   -    MD0100PA00X+007191Y+038418X0180Y         S0      
327VCCIO2           U25   -N12        A01X+007346Y+038263X0160Y    R180 S1      
327VCCIO2           C285  -1          A12X+008921Y+037633X0164Y0164R090 S2      
327VCCIO2           C187  -1   M      A12X+008606Y+037633X0164Y0164R090 S2      
317VCCIO2           VIA   -    MD0100PA00X+008762Y+037473X0180Y         S0      
327VCCIO2           U25   -K8         A01X+008606Y+037318X0160Y    R180 S1      
327VCCIO2           U25   -K9         A01X+008291Y+037318X0160Y    R180 S1      
317VCCIO2           VIA   -    MD0100PA00X+008136Y+037473X0180Y         S0      
327VCCIO2           C245  -1   M      A12X+008291Y+037633X0164Y0164R090 S2      
327VCCIO1           VIA   -           A12X+006500Y+037750X0260Y         S2      
317VCCIO1           VIA   -    MD0100PA00X+007187Y+038103X0180Y         S0      
327VCCIO1           U25   -M13        A01X+007031Y+037948X0160Y    R180 S1      
327VCCIO1           C254  -1          A12X+007033Y+037946X0164Y0164R270 S2      
327VCCIO1           C281  -1          A12X+007031Y+037633X0164Y0164R180 S2      
327VCCIO1           C141  -1          A12X+007031Y+037318X0164Y0164R180 S2      
327VCCIO1           R525  -2          A12X+006900Y+038692X0198Y0197R090 S2      
317VCCIO1           VIA   -    MD0100PA00X+007191Y+038733X0180Y         S0      
327VCCIO1           C243  -1          A12X+007659Y+037000X0164Y0164R180 S2      
317VCCIO1           VIA   -    MD0100PA00X+007821Y+037158X0180Y         S0      
327VCCIO1           U25   -J10        A01X+007976Y+037003X0160Y    R180 S1      
327VCCIO1           U25   -H10        A01X+007976Y+036688X0160Y    R180 S1      
327VCCIO1           C164  -1          A12X+007661Y+036373X0164Y0164R270 S2      
317VCCIO1           VIA   -    MD0100PA00X+007821Y+036532X0180Y         S0      
327VCCIO1           C167  -1          A12X+007031Y+035743X0164Y0164R180 S2      
317VCCIO1           VIA   -    MD0100PA00X+006876Y+035587X0180Y         S0      
327VCCIO1           U25   -E13        A01X+007031Y+035743X0160Y    R180 S1      
327VCCIO0           C189  -1          A12X+008390Y+035928X0164Y0164R090 S2      
327VCCIO0           R305  -2          A12X+009692Y+036000X0198Y0197     S2      
327VCCIO0           C166  -1   M      A12X+008921Y+036058X0164Y0164R090 S2      
317VCCIO0           VIA   -    MD0100PA00X+008762Y+036217X0180Y         S0      
327VCCIO0           U25   -G8         A01X+008606Y+036373X0160Y    R180 S1      
327VCCIO0           C242  -1   M      A12X+008386Y+036232X0164Y0164R270 S2      
317VCCIO0           VIA   -    MD0100PA00X+008136Y+036217X0180Y         S0      
327VCCIO0           U25   -G9         A01X+008291Y+036373X0160Y    R180 S1      
327VCCIO0           C261  -1          A12X+009866Y+035113X0164Y0164R180 S2      
317VCCIO0           VIA   -    MD0100PA00X+009707Y+035272X0180Y         S0      
327VCCIO0           U25   -D5         A01X+009551Y+035428X0160Y    R180 S1      
327VCCIO0           C283  -1          A12X+007031Y+035113X0164Y0164R180 S2      
327VCCIO0           C247  -1          A12X+007031Y+035428X0164Y0164R180 S2      
317VCCIO0           VIA   -    MD0100PA00X+007191Y+035272X0180Y         S0      
327VCCIO0           U25   -D12        A01X+007346Y+035428X0160Y    R180 S1      
327m0073            U51   -4          A01X+006586Y+024924X0140Y0440     S1      
317m0073            VIA   -    MD0100PA00X+006880Y+025330X0200Y    R090 S0      
317m0073            VIA   -    MD0100PA00X+029170Y+045082X0200Y         S0      
327m0073            GF1   -OB5        A01X+028842Y+046638X0150Y0840R180 S1      
317m0073            VIA   -    M      A01X+023450Y+029350X0300Y         S1      
017m0073            VIA   -    M      A12X+023450Y+029350X0200Y         S1      
017m0073                  -    MD0100PA00X+023450Y+029350                       
327m0074            U50   -4          A01X+009006Y+024924X0140Y0440     S1      
327m0074            VIA   -    M      A12X+028076Y+043156X0260Y         S2      
317m0074            VIA   -    MD0100PA00X+018970Y+014040X0200Y         S0      
317m0074            VIA   -    MD0100PA00X+029162Y+044775X0200Y         S0      
327m0074            GF1   -OB6        A01X+028606Y+046638X0150Y0840R180 S1      
317m0074            VIA   -    MD0100PA00X+028750Y+041610X0200Y         S0      
317m0074            VIA   -    MD0100PA00X+009594Y+014969X0200Y         S0      
317m0074            VIA   -    MD0100PA00X+009530Y+024710X0200Y    R090 S0      
327m0074            R396  -2          A01X+009308Y+025550X0198Y0197     S1      
327m0075            R900  -2          A01X+007340Y+022278X0198Y0197R090 S1      
327m0075            U50   -1          A01X+008494Y+024136X0140Y0440     S1      
327m0075            VIA   -    M      A01X+008494Y+023210X0300Y    R090 S1      
327m0076            R900  -1          A01X+007340Y+021962X0198Y0197R090 S1      
327m0076            VIA   -    M      A01X+008100Y+021233X0300Y    R090 S1      
327m0076            U2    -1          A01X+009535Y+023998X0110Y0280     S1      
327m0077            R902  -2          A01X+006122Y+022888X0198Y0197R090 S1      
327m0077            U51   -1          A01X+006074Y+024136X0140Y0440     S1      
327m0077            VIA   -    M      A01X+006252Y+023360X0300Y    R090 S1      
327m0078            R902  -1          A01X+006122Y+022572X0198Y0197R090 S1      
327m0078            VIA   -    M      A01X+007029Y+022752X0300Y    R090 S1      
327m0078            U3    -1          A01X+007345Y+024008X0110Y0280     S1      
327m0079            R903  -2          A01X+006522Y+022888X0198Y0197R090 S1      
327m0079            U51   -3          A01X+006586Y+024136X0140Y0440     S1      
327m0079            VIA   -    M      A01X+006770Y+023538X0300Y    R090 S1      
327UART_6_BMC_TXD   R903  -1          A01X+006522Y+022572X0198Y0197R090 S1      
327UART_6_BMC_TXD   R761  -1          A12X+015532Y+011920X0198Y0197R180 S2      
317UART_6_BMC_TXD   VIA   -    MD0100PA00X+015180Y+011650X0200Y         S0      
317UART_6_BMC_TXD   VIA   -    M      A01X+007112Y+017856X0200Y         S2      
017UART_6_BMC_TXD   VIA   -    M      A12X+007112Y+017856X0260Y         S2      
017UART_6_BMC_TXD         -    MD0100PA00X+007112Y+017856                       
317UART_6_BMC_TXD   VIA   -    MD0100PA00X+006770Y+022972X0200Y    R090 S0      
327m0080            R901  -2          A01X+007750Y+022278X0198Y0197R090 S1      
327m0080            U50   -3          A01X+009006Y+024136X0140Y0440     S1      
327m0080            VIA   -    M      A01X+008579Y+022707X0300Y    R090 S1      
327m0080            R538  -2   M      A01X+008150Y+022278X0198Y0197R090 S1      
327UART_6_BMC_RXD   R901  -1          A01X+007750Y+021962X0198Y0197R090 S1      
327UART_6_BMC_RXD   R762  -1          A01X+017600Y+013472X0198Y0197R090 S1      
317UART_6_BMC_RXD   VIA   -    MD0100PA00X+017444Y+013239X0200Y         S0      
317UART_6_BMC_RXD   VIA   -    MD0100PA00X+007405Y+018649X0200Y         S0      
317UART_6_BMC_RXD   VIA   -    M      A01X+007458Y+021731X0200Y         S2      
017UART_6_BMC_RXD   VIA   -    M      A12X+007458Y+021731X0260Y         S2      
017UART_6_BMC_RXD         -    MD0100PA00X+007458Y+021731                       
317TP_PLD_CONN_P5   J7    -5    D0410PA00X+002382Y+036915X0610Y         S3      
317TP_PLD_19D       VIA   -     D0100PA00X+007506Y+035587X0180Y         S0      
327TP_PLD_19D       U25   -E11        A01X+007661Y+035743X0160Y    R180 S1      
327TP_GF1_B44       VIA   -           A01X+011020Y+043160X0300Y         S1      
327TP_GF1_B44       GF1   -B44        A01X+011789Y+046559X0150Y0680R180 S1      
317m0081            VIA   -     D0100PA00X+021299Y+022589X0180Y    R270 S0      
327m0081            U5    -AC13       A01X+021770Y+022430X0160Y    R180 S1      
327TP4              U35   -5          A01X+012653Y+012644X0100Y0250R270 S1      
317m0082            VIA   -    MD0100PA00X+022244Y+022585X0180Y         S0      
327m0082            U5    -AC11       A01X+022400Y+022430X0160Y    R180 S1      
317m0082            VIA   -    M      A01X+026210Y+028070X0300Y         S1      
017m0082            VIA   -    M      A12X+026210Y+028070X0200Y         S1      
017m0082                  -    MD0100PA00X+026210Y+028070                       
327m0082            R309  -1          A12X+026180Y+028372X0198Y0197R270 S2      
317m0083            VIA   -    MD0100PA00X+026150Y+029044X0200Y         S0      
327m0083            R309  -2          A12X+026180Y+028688X0198Y0197R270 S2      
317m0083            VIA   -    MD0100PA00X+024479Y+037591X0200Y         S0      
317m0083            VIA   -    M      A01X+028397Y+038255X0200Y         S2      
017m0083            VIA   -    M      A12X+028397Y+038255X0260Y         S2      
017m0083                  -    MD0100PA00X+028397Y+038255                       
327m0083            Q7    -S   M      A12X+029790Y+038390X0320Y0360R180 S2      
317m0083            VIA   -    MD0100PA00X+033571Y+037201X0200Y         S0      
327m0083            R97   -2          A01X+033308Y+037200X0198Y0197     S1      
317m0084            VIA   -    M      A01X+033550Y+038000X0200Y         S2      
017m0084            VIA   -    M      A12X+033550Y+038000X0260Y         S2      
017m0084                  -    MD0100PA00X+033550Y+038000                       
327m0084            R98   -2          A01X+033308Y+037650X0198Y0197     S1      
327m0084            R414  -2   M      A01X+033308Y+038100X0198Y0197     S1      
317m0084            VIA   -    MD0100PA00X+025332Y+032333X0200Y         S0      
317m0084            VIA   -    MD0100PA00X+024747Y+026999X0200Y         S0      
327m0084            R469  -2          A12X+024269Y+026085X0198Y0197R270 S2      
327m0085            R468  -2          A01X+026148Y+025990X0198Y0197     S1      
317m0085            VIA   -    MD0100PA00X+033548Y+035850X0200Y         S0      
327m0085            R109  -2          A01X+033308Y+036300X0198Y0197     S1      
327m0085            R408  -2   M      A01X+033308Y+035850X0198Y0197     S1      
317m0085            VIA   -    MD0100PA00X+026270Y+026510X0200Y         S0      
317m0085            VIA   -    M      A01X+025790Y+031210X0300Y         S1      
017m0085            VIA   -    M      A12X+025790Y+031210X0200Y         S1      
017m0085                  -    MD0100PA00X+025790Y+031210                       
327m0086            R409  -1          A12X+006450Y+006892X0198Y0197R270 S2      
317m0086            J14   -2    D0410PA00X+006571Y+005224X0610Y         S3      
327m0087            R410  -1          A12X+007250Y+007208X0198Y0197R090 S2      
317m0087            J14   -4    D0410PA00X+007571Y+005224X0610Y         S3      
317m0088            D14   -A    D0320PA00X+006390Y+002476X0480Y0480     S3      
327m0088            VIA   -    M      A12X+004018Y+002971X0260Y         S2      
327m0088            R568  -1   M      A12X+005550Y+006992X0198Y0197R270 S2      
327m0088            C321  -1          A12X+005950Y+006992X0198Y0197R270 S2      
327PCH_BEEP_LED     VIA   -    M      A12X+007878Y+006464X0260Y         S2      
317PCH_BEEP_LED     VIA   -    MD0100PA00X+005420Y+002540X0200Y         S0      
327PCH_BEEP_LED     R811  -1   M      A12X+004040Y+041722X0198Y0197R270 S2      
327PCH_BEEP_LED     R847  -1          A12X+004440Y+041722X0198Y0197R270 S2      
317PCH_BEEP_LED     VIA   -    MD0100PA00X+005410Y+044860X0200Y         S0      
327PCH_BEEP_LED     U8    -2          A12X+005600Y+009126X0170Y0240     S2      
327m0089            GF1   -A20        A12X+020498Y+046559X0150Y0680R180 S2      
327m0089            C24   -2          A12X+024643Y+024561X0198Y0197R270 S2      
327m0090            GF1   -A21        A12X+020262Y+046559X0150Y0680R180 S2      
327m0090            C25   -2          A12X+024243Y+024561X0198Y0197R270 S2      
327P2E_PCH_RX_DP    GF1   -A17        A12X+021207Y+046559X0150Y0680R180 S2      
317P2E_PCH_RX_DP    VIA   -    MD0100PA00X+021672Y+044222X0200Y         S0      
327P2E_PCH_RX_DP    U5    -AF5        A01X+024289Y+023374X0160Y    R180 S1      
317P2E_PCH_RX_DP    VIA   -    MD0100PA00X+024287Y+023760X0180Y         S0      
327P2E_PCH_RX_DN    GF1   -A18        A12X+020970Y+046559X0150Y0680R180 S2      
317P2E_PCH_RX_DN    VIA   -    MD0100PA00X+021322Y+044222X0200Y         S0      
327P2E_PCH_RX_DN    U5    -AF6        A01X+023974Y+023374X0160Y    R180 S1      
317P2E_PCH_RX_DN    VIA   -    MD0100PA00X+023987Y+023760X0180Y         S0      
327P2E_GPU_TX_DN    U5    -AF2        A01X+025234Y+023374X0160Y    R180 S1      
317P2E_GPU_TX_DN    VIA   -    MD0100PA00X+025390Y+023530X0180Y    R180 S0      
327P2E_GPU_TX_DN    C271  -1          A01X+005250Y+042892X0198Y0197R090 S1      
317P2E_GPU_TX_DN    VIA   -    MD0100PA00X+005275Y+042420X0200Y         S0      
327P2E_GPU_TX_DP    U5    -AF3        A01X+024919Y+023374X0160Y    R180 S1      
317P2E_GPU_TX_DP    VIA   -    MD0100PA00X+025075Y+023530X0180Y    R180 S0      
327P2E_GPU_TX_DP    C272  -1          A01X+005650Y+042892X0198Y0197R090 S1      
317P2E_GPU_TX_DP    VIA   -    MD0100PA00X+005625Y+042420X0200Y         S0      
327m0091            C272  -2          A01X+005650Y+043208X0198Y0197R090 S1      
327m0091            GF1   -B65        A01X+006829Y+046559X0150Y0680R180 S1      
327m0092            C271  -2          A01X+005250Y+043208X0198Y0197R090 S1      
327m0092            GF1   -B66        A01X+006592Y+046559X0150Y0680R180 S1      
327P2E_GPU_RX_DP    GF1   -A65        A12X+006829Y+046559X0150Y0680R180 S2      
317P2E_GPU_RX_DP    VIA   -    MD0100PA00X+006357Y+045334X0200Y         S0      
327P2E_GPU_RX_DP    U5    -AD2        A01X+025234Y+022745X0160Y    R180 S1      
317P2E_GPU_RX_DP    VIA   -    MD0100PA00X+025390Y+022900X0180Y    R180 S0      
317P2E_GPU_RX_DN    VIA   -    MD0100PA00X+006357Y+045684X0200Y         S0      
327P2E_GPU_RX_DN    GF1   -A66        A12X+006592Y+046559X0150Y0680R180 S2      
317P2E_GPU_RX_DN    VIA   -    MD0100PA00X+025075Y+022900X0180Y    R180 S0      
327P2E_GPU_RX_DN    U5    -AD3        A01X+024919Y+022745X0160Y    R180 S1      
327m0093            R397  -1          A12X+006810Y+033108X0198Y0197R090 S2      
317m0093            VIA   -    MD0100PA00X+007821Y+034957X0180Y         S2      
327m0093            U25   -C10        A01X+007976Y+035113X0160Y    R180 S1      
327JTAG_1_BMC_TDO   VIA   -    M      A12X+014169Y+019620X0260Y         S2      
327JTAG_1_BMC_TDO   R398  -1          A12X+013718Y+019560X0198Y0197     S2      
317JTAG_1_BMC_TDO   VIA   -    MD0100PA00X+014428Y+019513X0200Y         S0      
327JTAG_1_BMC_TDO   U5    -C16        A01X+020825Y+016130X0160Y    R180 S1      
317JTAG_1_BMC_TDO   VIA   -    MD0100PA00X+020669Y+015975X0180Y         S0      
327ID_LED_BUF       Q9    -2          A01X+012526Y+004190X0170Y0200R090 S1      
327ID_LED_BUF       U9    -4          A01X+011822Y+004776X0280Y0400R270 S1      
327HDD_LED_N        R838  -1   M      A01X+004470Y+042892X0198Y0197R090 S1      
327HDD_LED_N        R564  -1          A01X+004860Y+042892X0198Y0197R090 S1      
317HDD_LED_N        VIA   -    MD0100PA00X+003100Y+034250X0200Y         S0      
317HDD_LED_N        VIA   -    MD0100PA00X+005924Y+006724X0200Y         S0      
327HDD_LED_N        R619  -1   M      A01X+005250Y+006292X0198Y0197R090 S1      
327HDD_LED_N        Q12   -5          A01X+004450Y+006476X0170Y0200     S1      
327GPU_FPGA_RST_N   VIA   -    M      A12X+005510Y+022550X0260Y         S2      
317GPU_FPGA_RST_N   VIA   -    MD0100PA00X+008762Y+038733X0180Y         S0      
327GPU_FPGA_RST_N   U25   -P8         A01X+008606Y+038578X0160Y    R180 S1      
317GPU_FPGA_RST_N   VIA   -    MD0100PA00X+001400Y+040420X0200Y         S0      
327GPU_FPGA_RST_N   U5    -F23        A01X+018620Y+017075X0160Y    R180 S1      
317GPU_FPGA_RST_N   VIA   -    MD0100PA00X+018464Y+016920X0180Y         S0      
317GPU_FPGA_RST_N   VIA   -    MD0100PA00X+006749Y+018898X0200Y         S0      
327m0094            R899  -1          A12X+006050Y+042058X0198Y0197R090 S2      
327m0094            VIA   -    M      A12X+006372Y+041238X0260Y         S2      
317m0094            VIA   -    MD0100PA00X+007821Y+037788X0180Y         S0      
327m0094            U25   -L10        A01X+007976Y+037633X0160Y    R180 S1      
327m0095            R284  -2          A01X+030292Y+007950X0198Y0197R180 S1      
327m0095            VIA   -    M      A01X+030209Y+007455X0300Y         S1      
327m0095            D19   -C          A01X+030313Y+008400X0240Y0280R180 S1      
327m0096            R899  -2          A12X+006050Y+041742X0198Y0197R090 S2      
317m0096            VIA   -    M      A01X+029377Y+007353X0300Y         S1      
017m0096            VIA   -    M      A12X+029377Y+007353X0200Y         S1      
017m0096                  -    MD0100PA00X+029377Y+007353                       
327m0096            R284  -1          A01X+030608Y+007950X0198Y0197R180 S1      
317m0096            VIA   -    MD0100PA00X+010712Y+007100X0200Y         S0      
327m0096            U2    -6          A01X+009928Y+025062X0110Y0280     S1      
327m0096            R220  -2   M      A12X+005650Y+041742X0198Y0197R090 S2      
317m0096            VIA   -    MD0100PA00X+005233Y+041335X0200Y         S0      
317m0096            VIA   -    MD0100PA00X+007738Y+025377X0200Y         S0      
327m0096            U3    -6          A01X+007738Y+025072X0110Y0280     S1      
327m0097            R898  -1          A12X+005250Y+042058X0198Y0197R090 S2      
327m0097            VIA   -    M      A12X+005800Y+041260X0260Y         S2      
317m0097            VIA   -    MD0100PA00X+008136Y+038103X0180Y         S0      
327m0097            U25   -M9         A01X+008291Y+037948X0160Y    R180 S1      
327m0098            R283  -2          A01X+029442Y+007950X0198Y0197R180 S1      
327m0098            VIA   -    M      A01X+028974Y+007861X0300Y         S1      
327m0098            D18   -C          A01X+029363Y+008400X0240Y0280R180 S1      
327m0099            R898  -2          A12X+005250Y+041742X0198Y0197R090 S2      
317m0099            VIA   -    M      A01X+029758Y+007374X0200Y         S2      
017m0099            VIA   -    M      A12X+029758Y+007374X0260Y         S2      
017m0099                  -    MD0100PA00X+029758Y+007374                       
327m0099            R283  -1          A01X+029758Y+007950X0198Y0197R180 S1      
317m0099            VIA   -    MD0100PA00X+010912Y+006950X0200Y         S0      
317m0099            VIA   -    MD0100PA00X+008027Y+024783X0200Y         S0      
327m0099            U2    -5          A01X+010125Y+025062X0110Y0280     S1      
327m0099            U3    -5          A01X+007935Y+025072X0110Y0280     S1      
317m0099            VIA   -    MD0100PA00X+004434Y+040648X0200Y         S0      
327m0099            R134  -2   M      A12X+004850Y+041742X0198Y0197R090 S2      
317m0100            VIA   -           A01X+022990Y+006100X0300Y         S1      
017m0100            VIA   -           A12X+022990Y+006100X0200Y         S1      
017m0100                  -     D0100PA00X+022990Y+006100                       
317m0100            VIA   -    MD0100PA00X+008762Y+039048X0180Y         S0      
327m0100            U25   -R8         A01X+008606Y+038892X0160Y    R180 S1      
317m0100            VIA   -    MD0100PA00X+001400Y+040670X0200Y         S0      
317m0101            VIA   -           A01X+021140Y+005924X0300Y         S1      
017m0101            VIA   -           A12X+021140Y+005924X0200Y         S1      
017m0101                  -     D0100PA00X+021140Y+005924                       
317m0101            VIA   -    MD0100PA00X+001400Y+040170X0200Y         S0      
317m0101            VIA   -    MD0100PA00X+009077Y+037788X0180Y         S0      
327m0101            U25   -L7         A01X+008921Y+037633X0160Y    R180 S1      
327m0102            VIA   -    M      A12X+007397Y+042920X0260Y         S2      
327m0102            GF1   -A52        A12X+009900Y+046638X0150Y0840R180 S2      
317m0102            VIA   -    MD0100PA00X+008970Y+043790X0200Y         S0      
327m0102            R220  -1          A12X+005650Y+042058X0198Y0197R090 S2      
317m0102            VIA   -    MD0100PA00X+007960Y+042640X0200Y         S0      
327m0103            GF1   -A55        A12X+009191Y+046638X0150Y0840R180 S2      
327m0103            VIA   -    M      A12X+006246Y+042687X0260Y         S2      
327m0103            R134  -1          A12X+004850Y+042058X0198Y0197R090 S2      
327m0104            U51   -6   M      A01X+006074Y+024924X0140Y0440     S1      
327m0104            U50   -6          A01X+008494Y+024924X0140Y0440     S1      
327m0104            VIA   -    M      A12X+007110Y+022974X0260Y         S2      
317m0104            VIA   -    MD0100PA00X+007110Y+023358X0200Y         S0      
317m0104            VIA   -    MD0100PA00X+008920Y+013880X0200Y         S0      
327m0104            R122  -1          A01X+015582Y+015830X0198Y0197     S1      
317m0105            VIA   -    MD0100PA00X+008762Y+038418X0180Y         S0      
327m0105            U25   -N8         A01X+008606Y+038263X0160Y    R180 S1      
327m0105            VIA   -    M      A12X+003530Y+032390X0260Y         S2      
327m0105            U5    -F26        A01X+017675Y+017075X0160Y    R180 S1      
317m0105            VIA   -    MD0100PA00X+017300Y+017020X0180Y         S0      
317m0105            VIA   -    MD0100PA00X+006739Y+019194X0200Y         S0      
317m0105            VIA   -    MD0100PA00X+003210Y+043280X0200Y         S0      
317m0105            VIA   -    MD0100PA00X+007760Y+043140X0200Y         S0      
327m0106            GF1   -A14        A12X+021915Y+046559X0150Y0680R180 S2      
317m0106            VIA   -    MD0100PA00X+022122Y+041015X0200Y         S0      
327m0106            U5    -AD5        A01X+024289Y+022745X0160Y    R180 S1      
317m0106            VIA   -    MD0100PA00X+024134Y+022589X0180Y         S0      
327m0107            GF1   -A15        A12X+021679Y+046559X0150Y0680R180 S2      
317m0107            VIA   -    MD0100PA00X+021772Y+041015X0200Y         S0      
327m0107            U5    -AD6        A01X+023974Y+022745X0160Y    R180 S1      
317m0107            VIA   -    MD0100PA00X+024130Y+022900X0180Y    R180 S0      
317m0108            VIA   -    MD0100PA00X+025705Y+023215X0180Y    R180 S0      
327m0108            U5    -AE1        A01X+025549Y+023060X0160Y    R180 S1      
317m0108            VIA   -    MD0100PA00X+005648Y+045334X0200Y         S0      
327m0108            GF1   -A68        A12X+006120Y+046559X0150Y0680R180 S2      
317m0109            VIA   -    MD0100PA00X+005648Y+045684X0200Y         S0      
327m0109            GF1   -A69        A12X+005884Y+046559X0150Y0680R180 S2      
317m0109            VIA   -    MD0100PA00X+025390Y+023215X0180Y    R180 S0      
327m0109            U5    -AE2        A01X+025234Y+023060X0160Y    R180 S1      
317m0110            VIA   -    MD0100PA00X+010600Y+009190X0200Y         S0      
317m0110            VIA   -    M      A01X+009230Y+028210X0200Y         S2      
017m0110            VIA   -    M      A12X+009230Y+028210X0260Y         S2      
017m0110                  -    MD0100PA00X+009230Y+028210                       
317m0110            VIA   -    MD0100PA00X+017055Y+030405X0200Y         S0      
317m0110            VIA   -    MD0100PA00X+018500Y+027070X0200Y         S0      
327m0110            R461  -1          A01X+018755Y+026282X0198Y0197R270 S1      
327m0110            R319  -2   M      A01X+018692Y+026700X0198Y0197R180 S1      
327m0110            U8    -1          A12X+005856Y+009126X0170Y0240     S2      
317BEEP_LED         VIA   -    MD0100PA00X+009015Y+006898X0200Y         S0      
327BEEP_LED         U9    -1          A01X+010878Y+005524X0280Y0400R270 S1      
317BEEP_LED         VIA   -    M      A01X+011260Y+005280X0200Y         S2      
017BEEP_LED         VIA   -    M      A12X+011260Y+005280X0260Y         S2      
017BEEP_LED               -    MD0100PA00X+011260Y+005280                       
317BEEP_LED         VIA   -    MD0100PA00X+004500Y+009514X0200Y         S0      
327BEEP_LED         R306  -1          A12X+004800Y+009442X0198Y0197R270 S2      
327BEEP_LED         U8    -4          A12X+005344Y+009874X0170Y0240     S2      
327m0111            VIA   -    M      A01X+007600Y+017510X0300Y         S1      
327m0111            R827  -1          A01X+006920Y+018072X0198Y0197R090 S1      
327m0111            U44   -4          A01X+007137Y+017254X0160Y0360     S1      
327m0112            U25   -B9         A01X+008291Y+034798X0160Y    R180 S1      
317m0112            VIA   -    MD0100PA00X+008136Y+034642X0180Y         S2      
317m0112            VIA   -    MD0100PA00X+014100Y+035850X0200Y         S0      
317m0112            VIA   -    MD0100PA00X+016950Y+018020X0200Y         S0      
327m0112            R816  -2          A12X+020780Y+012308X0198Y0197R270 S2      
317m0112            VIA   -    MD0100PA00X+020850Y+012606X0200Y         S0      
327m0112            R826  -2          A12X+021080Y+013479X0198Y0197R090 S2      
327m0113            R746  -1          A01X+008850Y+040608X0198Y0197R270 S1      
317m0113            VIA   -    MD0100PA00X+017040Y+021470X0200Y         S0      
327m0113            U5    -AA25       A01X+017990Y+021800X0160Y    R180 S1      
317m0113            VIA   -    M      A01X+022922Y+028325X0300Y         S1      
017m0113            VIA   -    M      A12X+022922Y+028325X0200Y         S1      
017m0113                  -    MD0100PA00X+022922Y+028325                       
317m0113            VIA   -    MD0100PA00X+023029Y+037310X0200Y         S0      
327m0113            VIA   -    M      A01X+023537Y+040350X0300Y         S1      
317m0113            VIA   -    MD0100PA00X+004805Y+043635X0200Y         S0      
317m0113            VIA   -    MD0100PA00X+008648Y+040787X0200Y         S0      
317m0113            VIA   -    MD0100PA00X+024144Y+044578X0200Y         S0      
327m0113            R505  -1   M      A01X+022665Y+037624X0198Y0197R090 S1      
327m0113            R497  -2   M      A01X+022280Y+037620X0198Y0197R270 S1      
327FM_ID_LED        R390  -1          A01X+013058Y+005000X0198Y0197R180 S1      
317FM_ID_LED        VIA   -    M      A01X+012580Y+004733X0200Y         S2      
017FM_ID_LED        VIA   -    M      A12X+012580Y+004733X0260Y         S2      
017FM_ID_LED              -    MD0100PA00X+012580Y+004733                       
317FM_ID_LED        VIA   -    MD0100PA00X+005340Y+010279X0200Y         S0      
327FM_ID_LED        U5    -G26        A01X+017675Y+017390X0160Y    R180 S1      
317FM_ID_LED        VIA   -    MD0100PA00X+017520Y+017235X0180Y         S0      
327m0114            U24   -1          A12X+003514Y+011176X0170Y0240R090 S2      
327m0114            VIA   -    M      A12X+005150Y+011400X0260Y         S2      
317m0114            VIA   -    MD0100PA00X+007528Y+018080X0200Y         S0      
327m0114            R715  -2   M      A01X+010680Y+025968X0198Y0197R090 S1      
327m0114            R67   -2          A01X+011080Y+026028X0198Y0197R090 S1      
327m0114            U2    -2   M      A01X+009732Y+023998X0110Y0280     S1      
327m0115            VIA   -           A01X+010800Y+023720X0260Y         S1      
327m0115            U47   -6   M      A01X+011024Y+024954X0170Y0240     S1      
327m0115            R715  -1          A01X+010680Y+025652X0198Y0197R090 S1      
327m0116            VIA   -    M      A01X+008020Y+023410X0300Y    R090 S1      
327m0116            U3    -2          A01X+007542Y+024008X0110Y0280     S1      
327m0116            R766  -2          A01X+007540Y+023298X0198Y0197R090 S1      
327m0117            VIA   -    M      A01X+011960Y+026150X0300Y    R090 S1      
327m0117            U47   -4          A01X+011536Y+024954X0170Y0240     S1      
327m0117            R757  -1          A01X+012450Y+026112X0198Y0197R090 S1      
327m0118            R766  -1          A01X+007540Y+022982X0198Y0197R090 S1      
317m0118            VIA   -    MD0100PA00X+007045Y+022290X0200Y    R090 S0      
327m0118            R104  -2          A12X+004848Y+010230X0198Y0197R180 S2      
317m0118            VIA   -    M      A01X+011290Y+023920X0200Y    R090 S2      
017m0118            VIA   -    M      A12X+011290Y+023920X0260Y    R090 S2      
017m0118                  -    MD0100PA00X+011290Y+023920                       
327m0118            U47   -3   M      A01X+011536Y+024206X0170Y0240     S1      
327m0118            R72   -2          A01X+012033Y+023992X0198Y0197R270 S1      
327m0119            R752  -2          A01X+008150Y+016732X0198Y0197R270 S1      
327m0119            U44   -2          A01X+006881Y+016388X0160Y0360     S1      
317TP_PLD_L3        VIA   -     D0100PA00X+007191Y+035902X0180Y         S0      
327TP_PLD_L3        U25   -F12        A01X+007346Y+036058X0160Y    R180 S1      
327m0120            VIA   -    M      A12X+021055Y+037529X0260Y         S2      
327m0120            R95   -2          A12X+020332Y+037075X0198Y0197R180 S2      
327m0120            U40   -23         A12X+021542Y+036475X0140Y0590R090 S2      
327m0121            VIA   -    M      A12X+020835Y+036975X0260Y         S2      
327m0121            R632  -2          A12X+020332Y+036725X0198Y0197R180 S2      
327m0121            U40   -22         A12X+021542Y+036219X0140Y0590R090 S2      
327m0122            R562  -2          A01X+008750Y+026942X0198Y0197R270 S1      
327m0122            R561  -2   M      A01X+008350Y+026942X0198Y0197R270 S1      
317m0122            VIA   -    MD0100PA00X+008350Y+026690X0200Y         S0      
317m0122            VIA   -    M      A01X+010660Y+025369X0200Y    R090 S2      
017m0122            VIA   -    M      A12X+010660Y+025369X0260Y    R090 S2      
017m0122                  -    MD0100PA00X+010660Y+025369                       
327m0122            R563  -2   M      A01X+007280Y+018072X0198Y0197R270 S1      
327m0122            R827  -2          A01X+006920Y+018388X0198Y0197R090 S1      
327m0123            R750  -2          A12X+008650Y+039992X0198Y0197R090 S2      
327m0123            VIA   -    M      A12X+009420Y+039100X0260Y         S2      
327m0123            U25   -N6         A01X+009236Y+038263X0160Y    R180 S1      
317m0123            VIA   -    MD0100PA00X+009392Y+038418X0180Y         S0      
317m0124            VIA   -    MD0100PA00X+025135Y+015288X0200Y         S0      
327m0124            R387  -2          A12X+025352Y+015875X0198Y0197     S2      
327m0124            U5    -C7         A01X+023659Y+016130X0160Y    R180 S1      
317m0124            VIA   -    MD0100PA00X+023815Y+015975X0180Y         S0      
317T_GND            DB1   -1   MD0670PA00X-003100Y+043200X0850Y    R180 S3      
317T_GND            DB2   -1   MD0670PA00X-005600Y+039600X0850Y    R180 S3      
317T_GND            DB4   -1   MD0670PA00X-003010Y+026350X0850Y    R180 S3      
317T_GND            DB3   -1   MD0670PA00X-005610Y+026350X0850Y    R180 S3      
317T_GND            DB6   -1   MD0670PA00X-003000Y+004300X0850Y         S3      
317T_GND            DB5   -1   MD0670PA00X-005671Y+004301X0850Y         S3      
317m0125            DB1   -3    D0670PA00X-002600Y+041882X0850Y    R180 S3      
317m0125            DB1   -2    D0670PA00X-003600Y+041882X0850Y    R180 S3      
317m0126            DB5   -3    D0670PA00X-005171Y+005619X0850Y         S3      
317m0126            DB5   -2    D0670PA00X-006171Y+005619X0850Y         S3      
317m0127            DB4   -3    D0670PA00X-003510Y+025032X0850Y    R180 S3      
317m0127            DB4   -2    D0670PA00X-002510Y+025032X0850Y    R180 S3      
317m0128            DB3   -2    D0670PA00X-006110Y+025032X0850Y    R180 S3      
317m0128            DB3   -3    D0670PA00X-005110Y+025032X0850Y    R180 S3      
317m0129            DB2   -2    D0670PA00X-006100Y+038282X0850Y    R180 S3      
317m0129            DB2   -3    D0670PA00X-005100Y+038282X0850Y    R180 S3      
317m0130            DB6   -3    D0670PA00X-002500Y+005618X0850Y         S3      
317m0130            DB6   -2    D0670PA00X-003500Y+005618X0850Y         S3      
317m0131            X7    -4    D0098PA00X+044100Y+042000X0395Y    R270 S3      
317m0131            X1    -1    D0098PA00X+044100Y+033600X0395Y    R090 S3      
317m0132            X7    -1    D0098PA00X+045100Y+042000X0395Y    R270 S3      
317m0132            X1    -4    D0098PA00X+045100Y+033600X0395Y    R090 S3      
317m0133            X11   -4    D0098PA00X+044100Y+012600X0395Y    R270 S3      
317m0133            X5    -1    D0098PA00X+044100Y+020000X0395Y    R090 S3      
317m0134            X11   -1    D0098PA00X+045100Y+012600X0395Y    R270 S3      
317m0134            X5    -4    D0098PA00X+045100Y+020000X0395Y    R090 S3      
317m0135            X2    -1    D0098PA00X+044100Y+023000X0395Y    R090 S3      
317m0135            X8    -4    D0098PA00X+044100Y+030400X0395Y    R270 S3      
317m0136            X2    -4    D0098PA00X+045100Y+023000X0395Y    R090 S3      
317m0136            X8    -1    D0098PA00X+045100Y+030400X0395Y    R270 S3      
317m0137            X12   -4    D0098PA00X+045100Y+009600X0395Y    R090 S3      
317m0137            X6    -1    D0098PA00X+045100Y+001200X0395Y    R270 S3      
317m0138            X12   -1    D0098PA00X+044100Y+009600X0395Y    R090 S3      
317m0138            X6    -4    D0098PA00X+044100Y+001200X0395Y    R270 S3      
317m0139            X13   -1    D0098PA00X+044100Y-010700X0395Y    R090 S3      
317m0139            X19   -4    D0098PA00X+044100Y-001800X0395Y    R270 S3      
317m0140            X13   -4    D0098PA00X+045100Y-010700X0395Y    R090 S3      
317m0140            X19   -1    D0098PA00X+045100Y-001800X0395Y    R270 S3      
317m0141            X23   -4    D0098PA00X+044100Y-032340X0395Y    R270 S3      
317m0141            X17   -1    D0098PA00X+044100Y-024500X0395Y    R090 S3      
317m0142            X23   -1    D0098PA00X+045100Y-032340X0395Y    R270 S3      
317m0142            X17   -4    D0098PA00X+045100Y-024500X0395Y    R090 S3      
317m0143            X14   -1    D0098PA00X+044100Y-021500X0395Y    R090 S3      
317m0143            X20   -4    D0098PA00X+044100Y-013660X0395Y    R270 S3      
317m0144            X14   -4    D0098PA00X+045100Y-021500X0395Y    R090 S3      
317m0144            X20   -1    D0098PA00X+045100Y-013660X0395Y    R270 S3      
317m0145            X18   -1    D0098PA00X+044100Y-035500X0395Y    R090 S3      
317m0145            X24   -4    D0098PA00X+044100Y-044400X0395Y    R270 S3      
317m0146            X18   -4    D0098PA00X+045100Y-035500X0395Y    R090 S3      
317m0146            X24   -1    D0098PA00X+045100Y-044400X0395Y    R270 S3      
327m0147            VIA   -    M      A12X+014849Y+037426X0260Y         S2      
327m0147            R731  -2          A12X+014636Y+038276X0198Y0197R180 S2      
327m0147            U22   -13         A12X+015819Y+036850X0110Y0260     S2      
327m0148            VIA   -    M      A12X+015021Y+036925X0260Y         S2      
327m0148            R732  -2          A12X+014636Y+037876X0198Y0197R180 S2      
327m0148            U22   -12         A12X+015622Y+036850X0110Y0260     S2      
327m0149            VIA   -    M      A12X+020832Y+034324X0260Y         S2      
327m0149            R702  -2          A12X+020382Y+034225X0198Y0197R180 S2      
327m0149            U40   -16         A12X+021542Y+034683X0140Y0590R090 S2      
327m0150            VIA   -    M      A12X+020830Y+033820X0260Y         S2      
327m0150            R701  -2          A12X+020382Y+033875X0198Y0197R180 S2      
327m0150            U40   -15         A12X+021542Y+034427X0140Y0590R090 S2      
327m0151            VIA   -    M      A12X+020832Y+034829X0260Y         S2      
327m0151            R719  -2          A12X+020332Y+034575X0198Y0197R180 S2      
327m0151            R703  -2   M      A12X+020332Y+034925X0198Y0197R180 S2      
327m0151            U40   -17         A12X+021542Y+034939X0140Y0590R090 S2      
327m0152            R578  -1          A01X+010850Y+040608X0198Y0197R270 S1      
327m0152            R643  -1          A01X+025613Y+025325X0198Y0197R270 S1      
317m0152            VIA   -    MD0100PA00X+019973Y+031456X0200Y         S0      
317m0152            VIA   -    MD0100PA00X+025848Y+025487X0200Y         S0      
317m0152            VIA   -    MD0100PA00X+026426Y+031582X0200Y         S0      
327m0152            R703  -1          A12X+020018Y+034925X0198Y0197R180 S2      
317m0152            VIA   -    MD0100PA00X+019771Y+034925X0200Y         S0      
317m0152            VIA   -    MD0100PA00X+010850Y+040868X0200Y         S0      
327m0152            R627  -2          A12X+010250Y+040308X0198Y0197R270 S2      
317m0152            VIA   -    M      A01X+019580Y+039678X0200Y         S2      
017m0152            VIA   -    M      A12X+019580Y+039678X0260Y         S2      
017m0152                  -    MD0100PA00X+019580Y+039678                       
327m0153            VIA   -    M      A12X+024543Y+036730X0260Y         S2      
327m0153            R667  -2          A12X+025030Y+036772X0198Y0197R090 S2      
327m0153            U40   -1          A12X+023842Y+036730X0140Y0590R090 S2      
327m0154            VIA   -    M      A12X+024540Y+035580X0260Y         S2      
327m0154            R740  -2   M      A12X+025022Y+035520X0198Y0197     S2      
327m0154            R745  -1          A12X+025022Y+035120X0198Y0197R180 S2      
327m0154            U40   -3          A12X+023842Y+036219X0140Y0590R090 S2      
327m0155            VIA   -    M      A12X+024530Y+036110X0260Y         S2      
327m0155            R739  -2          A12X+025022Y+035910X0198Y0197     S2      
327m0155            R744  -1   M      A12X+025022Y+036310X0198Y0197R180 S2      
327m0155            U40   -2          A12X+023842Y+036475X0140Y0590R090 S2      
327m0156            R738  -2   M      A12X+022392Y+037664X0198Y0197R270 S2      
327m0156            VIA   -    M      A12X+022868Y+037664X0260Y         S2      
327m0156            R743  -1          A12X+023382Y+037410X0198Y0197R180 S2      
327m0156            U40   -21         A12X+021542Y+035963X0140Y0590R090 S2      
327m0157            VIA   -    M      A12X+029608Y+012200X0260Y         S2      
327m0157            U40   -11         A12X+023842Y+034171X0140Y0590R090 S2      
327m0157            R669  -2          A12X+029608Y+012650X0198Y0197R180 S2      
317m0157            VIA   -    MD0100PA00X+023350Y+034391X0200Y         S0      
317m0157            VIA   -    MD0100PA00X+029508Y+011910X0200Y         S0      
327LED_POSTCODE_7   R669  -1          A12X+029292Y+012650X0198Y0197R180 S2      
317LED_POSTCODE_7   VIA   -    MD0100PA00X+017080Y+019310X0200Y         S0      
327LED_POSTCODE_7   U5    -M26        A01X+017675Y+018965X0160Y    R180 S1      
317LED_POSTCODE_7   VIA   -    M      A01X+028828Y+012621X0200Y         S2      
017LED_POSTCODE_7   VIA   -    M      A12X+028828Y+012621X0260Y         S2      
017LED_POSTCODE_7         -    MD0100PA00X+028828Y+012621                       
327LED_POSTCODE_7   R597  -1          A01X+028530Y+012346X0198Y0197R270 S1      
327m0158            R674  -2          A12X+029628Y+013170X0198Y0197R180 S2      
317m0158            VIA   -    M      A01X+030050Y+012500X0200Y         S2      
017m0158            VIA   -    M      A12X+030050Y+012500X0260Y         S2      
017m0158                  -    MD0100PA00X+030050Y+012500                       
327m0158            U40   -10         A12X+023842Y+034427X0140Y0590R090 S2      
317m0158            VIA   -    MD0100PA00X+023350Y+034691X0200Y         S0      
327LED_POSTCODE_6   U5    -N26        A01X+017675Y+019280X0160Y    R180 S1      
327LED_POSTCODE_6   R674  -1          A12X+029312Y+013170X0198Y0197R180 S2      
327LED_POSTCODE_6   R598  -1          A01X+028530Y+012839X0198Y0197R090 S1      
317LED_POSTCODE_6   VIA   -    MD0100PA00X+029020Y+012950X0200Y         S0      
317LED_POSTCODE_6   VIA   -    MD0100PA00X+017434Y+019280X0180Y    R180 S0      
327m0159            R676  -2          A12X+030500Y+012092X0198Y0197R090 S2      
317m0159            VIA   -    M      A01X+025612Y+033636X0200Y         S2      
017m0159            VIA   -    M      A12X+025612Y+033636X0260Y         S2      
017m0159                  -    MD0100PA00X+025612Y+033636                       
317m0159            VIA   -    MD0100PA00X+030100Y+012102X0200Y         S0      
327m0159            U40   -9          A12X+023842Y+034683X0140Y0590R090 S2      
327LED_POSTCODE_5   R676  -1          A12X+030500Y+012408X0198Y0197R090 S2      
327LED_POSTCODE_5   R599  -1          A01X+031670Y+012298X0198Y0197R270 S1      
317LED_POSTCODE_5   VIA   -    MD0100PA00X+030740Y+012230X0200Y         S0      
317LED_POSTCODE_5   VIA   -    MD0100PA00X+018464Y+018810X0180Y         S0      
327LED_POSTCODE_5   U5    -M23        A01X+018620Y+018965X0160Y    R180 S1      
327m0160            R695  -2          A12X+030342Y+013129X0198Y0197     S2      
317m0160            VIA   -    M      A01X+026130Y+033410X0200Y         S2      
017m0160            VIA   -    M      A12X+026130Y+033410X0260Y         S2      
017m0160                  -    MD0100PA00X+026130Y+033410                       
327m0160            U40   -8          A12X+023842Y+034939X0140Y0590R090 S2      
317m0160            VIA   -    MD0100PA00X+030100Y+012990X0200Y         S0      
317LED_POSTCODE_4   VIA   -    MD0100PA00X+017520Y+019751X0180Y         S0      
327LED_POSTCODE_4   U5    -P26        A01X+017675Y+019595X0160Y    R180 S1      
327LED_POSTCODE_4   VIA   -    M      A01X+030360Y+013220X0300Y         S1      
327LED_POSTCODE_4   R695  -1          A12X+030658Y+013129X0198Y0197     S2      
327LED_POSTCODE_4   R600  -1          A01X+030822Y+013430X0198Y0197     S1      
317LED_POSTCODE_4   VIA   -    MD0100PA00X+030756Y+012850X0200Y         S0      
327m0161            R696  -2          A12X+029858Y+009760X0198Y0197R180 S2      
317m0161            VIA   -    M      A01X+029858Y+010190X0300Y         S1      
017m0161            VIA   -    M      A12X+029858Y+010190X0200Y         S1      
017m0161                  -    MD0100PA00X+029858Y+010190                       
327m0161            U40   -7          A12X+023842Y+035195X0140Y0590R090 S2      
317m0161            VIA   -    MD0100PA00X+023380Y+035430X0200Y         S0      
327LED_POSTCODE_3   U5    -N24        A01X+018305Y+019280X0160Y    R180 S1      
327LED_POSTCODE_3   VIA   -    M      A12X+029084Y+009635X0260Y         S2      
327LED_POSTCODE_3   R696  -1          A12X+029542Y+009760X0198Y0197R180 S2      
327LED_POSTCODE_3   R601  -1          A01X+029208Y+010040X0198Y0197R180 S1      
317LED_POSTCODE_3   VIA   -    MD0100PA00X+029460Y+010690X0200Y         S0      
317LED_POSTCODE_3   VIA   -    MD0100PA00X+018150Y+019124X0180Y    R180 S0      
327m0162            VIA   -    M      A12X+025632Y+034149X0260Y         S2      
327m0162            R697  -2          A12X+029898Y+011630X0198Y0197R180 S2      
317m0162            VIA   -    MD0100PA00X+029898Y+011890X0200Y         S0      
327m0162            U40   -6          A12X+023842Y+035451X0140Y0590R090 S2      
317m0162            VIA   -    MD0100PA00X+025942Y+034063X0200Y         S0      
327LED_POSTCODE_2   U5    -N25        A01X+017990Y+019280X0160Y    R180 S1      
327LED_POSTCODE_2   VIA   -    M      A12X+029136Y+011639X0260Y         S2      
327LED_POSTCODE_2   R697  -1          A12X+029582Y+011630X0198Y0197R180 S2      
327LED_POSTCODE_2   R602  -1          A01X+028530Y+011081X0198Y0197R090 S1      
317LED_POSTCODE_2   VIA   -    MD0100PA00X+029480Y+011180X0200Y         S0      
317LED_POSTCODE_2   VIA   -    MD0100PA00X+017835Y+019124X0180Y    R180 S0      
327m0163            R698  -2          A12X+031050Y+011858X0198Y0197R270 S2      
317m0163            VIA   -    M      A01X+031510Y+011640X0200Y         S2      
017m0163            VIA   -    M      A12X+031510Y+011640X0260Y         S2      
017m0163                  -    MD0100PA00X+031510Y+011640                       
317m0163            VIA   -    MD0100PA00X+023365Y+035963X0200Y         S0      
327m0163            U40   -5          A12X+023842Y+035707X0140Y0590R090 S2      
327LED_POSTCODE_1   R698  -1          A12X+031050Y+011542X0198Y0197R270 S2      
317LED_POSTCODE_1   VIA   -    M      A01X+030400Y+011650X0200Y         S2      
017LED_POSTCODE_1   VIA   -    M      A12X+030400Y+011650X0260Y         S2      
017LED_POSTCODE_1         -    MD0100PA00X+030400Y+011650                       
327LED_POSTCODE_1   R603  -1          A01X+031607Y+010589X0198Y0197R270 S1      
327LED_POSTCODE_1   U5    -N23        A01X+018620Y+019280X0160Y    R180 S1      
317LED_POSTCODE_1   VIA   -    MD0100PA00X+018464Y+019124X0180Y    R180 S0      
327m0164            VIA   -    M      A12X+025434Y+034632X0260Y         S2      
327m0164            R700  -2          A12X+031282Y+012200X0198Y0197     S2      
317m0164            VIA   -    MD0100PA00X+031380Y+012430X0200Y         S0      
327m0164            U40   -4          A12X+023842Y+035963X0140Y0590R090 S2      
317m0164            VIA   -    MD0100PA00X+025942Y+034323X0200Y         S0      
327LED_POSTCODE_0   U5    -P25        A01X+017990Y+019595X0160Y    R180 S1      
327LED_POSTCODE_0   VIA   -    M      A01X+032078Y+011103X0300Y         S1      
327LED_POSTCODE_0   R700  -1          A12X+031598Y+012200X0198Y0197     S2      
327LED_POSTCODE_0   R604  -1          A01X+031607Y+011081X0198Y0197R090 S1      
317LED_POSTCODE_0   VIA   -    MD0100PA00X+031800Y+011720X0200Y         S0      
317LED_POSTCODE_0   VIA   -    MD0100PA00X+017835Y+019751X0180Y         S0      
327m0165            VIA   -    M      A12X+020812Y+036341X0260Y         S2      
327m0165            R735  -2   M      A12X+020332Y+035975X0198Y0197R180 S2      
327m0165            R83   -2          A12X+020332Y+036325X0198Y0197R180 S2      
327m0165            U40   -20         A12X+021542Y+035707X0140Y0590R090 S2      
327FM_UART_SEL_N    VIA   -    M      A12X+020224Y+037898X0260Y         S2      
327FM_UART_SEL_N    Q8    -G          A12X+023006Y+038626X0320Y0360R270 S2      
327FM_UART_SEL_N    R83   -1          A12X+020018Y+036325X0198Y0197R180 S2      
327m0166            VIA   -    M      A12X+024325Y+038593X0260Y         S2      
327m0166            Q8    -D          A12X+023794Y+039000X0320Y0360R270 S2      
327m0166            R736  -2   M      A12X+024325Y+039268X0198Y0197R090 S2      
327m0166            R626  -2          A12X+024246Y+037822X0198Y0197R180 S2      
327m0167            R577  -1          A01X+011250Y+040608X0198Y0197R270 S1      
327m0167            GF1   -OB14       A01X+026716Y+046638X0150Y0840R180 S1      
317m0167            VIA   -    MD0100PA00X+026110Y+044350X0200Y         S0      
317m0167            VIA   -    MD0100PA00X+016550Y+038600X0200Y         S0      
317m0167            VIA   -    MD0100PA00X+017380Y+022540X0200Y         S0      
327m0167            R489  -1          A12X+017730Y+021988X0198Y0197R090 S2      
327m0167            VIA   -    M      A12X+023482Y+037990X0260Y         S2      
327m0167            R626  -1          A12X+023930Y+037822X0198Y0197R180 S2      
317m0167            VIA   -    MD0100PA00X+023360Y+037730X0200Y         S0      
327m0168            VIA   -    M      A12X+020835Y+035837X0260Y         S2      
327m0168            R721  -2          A12X+020332Y+035625X0198Y0197R180 S2      
327m0168            U40   -19         A12X+021542Y+035451X0140Y0590R090 S2      
327m0169            U5    -AB15       A01X+021140Y+022115X0160Y    R180 S1      
327m0169            R722  -1          A12X+021210Y+024722X0198Y0197R270 S2      
317m0169            VIA   -    MD0100PA00X+020984Y+022270X0180Y    R180 S0      
317m0169            VIA   -           A01X+005295Y+020070X0200Y         S2      
017m0169            VIA   -           A12X+005295Y+020070X0260Y         S2      
017m0169                  -     D0100PA00X+005295Y+020070                       
327m0170            VIA   -    M      A12X+025705Y+033138X0260Y         S2      
317m0170            VIA   -    MD0100PA00X+033990Y+006600X0200Y         S0      
327m0170            R733  -2          A01X+033738Y+006600X0198Y0197     S1      
327m0170            U40   -13         A12X+021542Y+033916X0140Y0590R090 S2      
317m0170            VIA   -    MD0100PA00X+034710Y+031370X0200Y         S0      
317m0170            VIA   -    MD0100PA00X+027757Y+035120X0200Y         S0      
317m0171            VIA   -    M      A01X+011280Y+006040X0200Y         S2      
017m0171            VIA   -    M      A12X+011280Y+006040X0260Y         S2      
017m0171                  -    MD0100PA00X+011280Y+006040                       
327m0171            R734  -2          A01X+005379Y+003487X0198Y0197     S1      
317m0171            VIA   -    MD0100PA00X+005635Y+003621X0200Y         S0      
317m0171            VIA   -    MD0100PA00X+011869Y+013730X0200Y         S0      
317m0171            VIA   -    MD0100PA00X+014950Y+035670X0200Y         S0      
317m0171            VIA   -    MD0100PA00X+022100Y+035200X0200Y         S0      
327m0171            U40   -14         A12X+021542Y+034171X0140Y0590R090 S2      
327m0172            VIA   -    M      A12X+022600Y+006800X0260Y         S2      
327m0172            Q6    -D          A12X+023125Y+006549X0320Y0360     S2      
327m0172            R730  -2   M      A12X+023092Y+007100X0198Y0197     S2      
327m0172            R707  -1          A12X+022150Y+006758X0198Y0197R090 S2      
327m0173            R579  -1          A01X+009250Y+040608X0198Y0197R270 S1      
317m0173            VIA   -    M      A01X+022823Y+034004X0300Y         S1      
017m0173            VIA   -    M      A12X+022823Y+034004X0200Y         S1      
017m0173                  -    MD0100PA00X+022823Y+034004                       
327m0173            R458  -2          A12X+023125Y+025052X0198Y0197R270 S2      
317m0173            VIA   -    MD0100PA00X+023000Y+025570X0200Y         S0      
317m0173            VIA   -    MD0100PA00X+004450Y+035160X0200Y         S0      
327m0173            VIA   -    M      A01X+008856Y+043304X0300Y         S1      
317m0173            VIA   -    MD0100PA00X+009250Y+040863X0200Y         S0      
317m0173            VIA   -    MD0100PA00X+004550Y+009250X0200Y         S0      
317m0173            VIA   -    MD0100PA00X+010390Y+044764X0200Y         S0      
317m0173            VIA   -    MD0100PA00X+008856Y+042654X0200Y         S0      
327m0173            R707  -2          A12X+022150Y+006442X0198Y0197R090 S2      
317m0173            VIA   -    MD0100PA00X+018740Y+010150X0200Y         S0      
327m0174            VIA   -    M      A12X+020834Y+035336X0260Y         S2      
327m0174            R720  -2          A12X+020332Y+035275X0198Y0197R180 S2      
327m0174            U40   -18         A12X+021542Y+035195X0140Y0590R090 S2      
327m0175            R747  -2          A01X+008450Y+040292X0198Y0197R270 S1      
327m0175            U25   -R6         A01X+009236Y+038892X0160Y    R180 S1      
327m0176            R746  -2          A01X+008850Y+040292X0198Y0197R270 S1      
327m0176            U25   -T5         A01X+009551Y+039208X0160Y    R180 S1      
317PVCCIO_AUX_PLD   VIA   -    M      A01X+012494Y+032490X0200Y         S2      
017PVCCIO_AUX_PLD   VIA   -    M      A12X+012494Y+032490X0260Y         S2      
017PVCCIO_AUX_PLD         -    MD0100PA00X+012494Y+032490                       
317PVCCIO_AUX_PLD   VIA   -    M      A01X+012430Y+034880X0200Y    R090 S2      
017PVCCIO_AUX_PLD   VIA   -    M      A12X+012430Y+034880X0260Y    R090 S2      
017PVCCIO_AUX_PLD         -    MD0100PA00X+012430Y+034880                       
327PVCCIO_AUX_PLD   R809  -2          A01X+012188Y+035030X0198Y0197     S1      
327PVCCIO_AUX_PLD   R810  -2          A01X+006100Y+032792X0198Y0197R270 S1      
317PVCCIO_AUX_PLD   VIA   -    MD0100PA00X+005282Y+032520X0200Y         S0      
327PVCCIO_AUX_PLD   R808  -2          A12X+005610Y+032792X0198Y0197R090 S2      
327PVCCIO_AUX_PLD   C257  -1   M      A12X+012742Y+035350X0198Y0197R180 S2      
327PVCCIO_AUX_PLD   R183  -2          A12X+012742Y+036150X0198Y0197     S2      
327PVCCIO_AUX_PLD   C256  -1   M      A12X+012742Y+035750X0198Y0197R180 S2      
327USB3_MUX_PD      VIA   -    M      A12X+017280Y+035465X0260Y         S2      
327USB3_MUX_PD      U22   -2          A12X+017000Y+035984X0110Y0260     S2      
327USB3_MUX_PD      R712  -2          A12X+017670Y+034998X0198Y0197R270 S2      
327USB3_MUX_PD      R694  -1   M      A12X+017280Y+034998X0198Y0197R090 S2      
327USB3_FPNL_TXP    C238  -1          A12X+018250Y+038278X0198Y0197R090 S2      
327USB3_FPNL_TXP    R671  -2   M      A12X+018250Y+038278X0198Y0197R270 S2      
317USB3_FPNL_TXP    VIA   -    MD0100PA00X+007565Y+042420X0200Y         S0      
327USB3_FPNL_TXP    GF1   -B59        A01X+008246Y+046559X0150Y0680R180 S1      
317USB3_FPNL_TXP    VIA   -    MD0100PA00X+018235Y+038563X0200Y         S0      
327USB3_FPNL_TXN    C239  -1          A12X+017850Y+038278X0198Y0197R090 S2      
327USB3_FPNL_TXN    R672  -2   M      A12X+017850Y+038278X0198Y0197R270 S2      
317USB3_FPNL_TXN    VIA   -    MD0100PA00X+007215Y+042420X0200Y         S0      
327USB3_FPNL_TXN    GF1   -B60        A01X+008010Y+046559X0150Y0680R180 S1      
317USB3_FPNL_TXN    VIA   -    MD0100PA00X+017885Y+038563X0200Y         S0      
317USB3_FPNL_RXP    VIA   -    MD0100PA00X+016255Y+038733X0200Y         S0      
327USB3_FPNL_RXP    U22   -17         A12X+016606Y+036850X0110Y0260     S2      
317USB3_FPNL_RXP    VIA   -    MD0100PA00X+006412Y+043127X0200Y         S0      
327USB3_FPNL_RXP    GF1   -A59        A12X+008246Y+046559X0150Y0680R180 S2      
317USB3_FPNL_RXN    VIA   -    MD0100PA00X+015905Y+038733X0200Y         S0      
327USB3_FPNL_RXN    U22   -16         A12X+016409Y+036850X0110Y0260     S2      
317USB3_FPNL_RXN    VIA   -    MD0100PA00X+006062Y+043127X0200Y         S0      
327USB3_FPNL_RXN    GF1   -A60        A12X+008010Y+046559X0150Y0680R180 S2      
327USB3_01_TXP_C    C238  -2          A12X+018250Y+037962X0198Y0197R090 S2      
327USB3_01_TXP_C    R671  -1   M      A12X+018250Y+037962X0198Y0197R270 S2      
327USB3_01_TXP_C    U22   -19         A12X+017000Y+036850X0110Y0260     S2      
327USB3_01_TXN_C    C239  -2          A12X+017850Y+037962X0198Y0197R090 S2      
327USB3_01_TXN_C    R672  -1   M      A12X+017850Y+037962X0198Y0197R270 S2      
327USB3_01_TXN_C    U22   -18         A12X+016803Y+036850X0110Y0260     S2      
327m0177            U22   -3          A12X+016803Y+035984X0110Y0260     S2      
327m0177            R673  -1   M      A01X+015967Y+008880X0198Y0197R270 S1      
317m0177            VIA   -    MD0100PA00X+015992Y+009628X0200Y         S0      
327m0177            L21   -1   M      A01X+015999Y+009059X0140Y0360     S1      
327m0178            U22   -4          A12X+016606Y+035984X0110Y0260     S2      
327m0178            R666  -1   M      A01X+016367Y+008880X0198Y0197R270 S1      
317m0178            VIA   -    MD0100PA00X+016342Y+009628X0200Y         S0      
327m0178            L21   -4   M      A01X+016333Y+009059X0140Y0360     S1      
327m0179            R675  -1   M      A01X+016910Y+008880X0198Y0197R270 S1      
317m0179            VIA   -    MD0100PA00X+016935Y+009628X0200Y         S0      
327m0179            L22   -1   M      A01X+016941Y+009059X0140Y0360     S1      
327m0179            U22   -7          A12X+016016Y+035984X0110Y0260     S2      
327m0180            R668  -1   M      A01X+017310Y+008880X0198Y0197R270 S1      
317m0180            VIA   -    MD0100PA00X+017285Y+009628X0200Y         S0      
327m0180            L22   -4   M      A01X+017276Y+009059X0140Y0360     S1      
327m0180            U22   -8          A12X+015819Y+035984X0110Y0260     S2      
317USB3_01_FB_TXP   J2    -9    D0280PA00X+015324Y+005858X0440Y    R090 S3      
327USB3_01_FB_TXP   R673  -2          A01X+015967Y+008566X0198Y0197R270 S1      
327USB3_01_FB_TXP   L21   -2   M      A01X+015999Y+008390X0140Y0360     S1      
327USB3_01_FB_TXP   U27   -10  M      A01X+016278Y+007313X0100Y0250R180 S1      
327USB3_01_FB_TXP   U27   -1   M      A01X+016278Y+007007X0100Y0250R180 S1      
317USB3_01_FB_TXN   J2    -8    D0280PA00X+016111Y+005858X0440Y    R090 S3      
327USB3_01_FB_TXN   R666  -2          A01X+016367Y+008566X0198Y0197R270 S1      
327USB3_01_FB_TXN   L21   -3   M      A01X+016333Y+008390X0140Y0360     S1      
327USB3_01_FB_TXN   U27   -9   M      A01X+016475Y+007313X0100Y0250R180 S1      
327USB3_01_FB_TXN   U27   -2   M      A01X+016475Y+007007X0100Y0250R180 S1      
317USB3_01_FB_RXP   J2    -6    D0280PA00X+017686Y+005858X0440Y    R090 S3      
327USB3_01_FB_RXP   R675  -2          A01X+016910Y+008566X0198Y0197R270 S1      
327USB3_01_FB_RXP   L22   -2   M      A01X+016941Y+008390X0140Y0360     S1      
327USB3_01_FB_RXP   U27   -7   M      A01X+016869Y+007313X0100Y0250R180 S1      
327USB3_01_FB_RXP   U27   -4   M      A01X+016869Y+007007X0100Y0250R180 S1      
317USB3_01_FB_RXN   J2    -5    D0280PA00X+018473Y+005858X0440Y    R090 S3      
327USB3_01_FB_RXN   R668  -2          A01X+017310Y+008566X0198Y0197R270 S1      
327USB3_01_FB_RXN   L22   -3   M      A01X+017276Y+008390X0140Y0360     S1      
327USB3_01_FB_RXN   U27   -6   M      A01X+017066Y+007313X0100Y0250R180 S1      
327USB3_01_FB_RXN   U27   -5   M      A01X+017066Y+007007X0100Y0250R180 S1      
327m0181            VIA   -    M      A12X+005950Y+024050X0260Y         S2      
327m0181            U37   -3          A12X+006422Y+024770X0140Y0590     S2      
327m0181            R294  -2          A12X+006122Y+023288X0198Y0197R270 S2      
327m0182            VIA   -    M      A12X+006450Y+024040X0260Y         S2      
327m0182            U37   -2          A12X+006678Y+024770X0140Y0590     S2      
327m0182            R135  -2          A12X+006522Y+023288X0198Y0197R270 S2      
327m0183            VIA   -    M      A12X+016898Y+007100X0260Y         S2      
327m0183            R693  -2          A12X+017300Y+007492X0198Y0197R090 S2      
317m0183            J2    -7    D0280PA00X+016898Y+005858X0440Y    R090 S3      
327m0183            R205  -1   M      A12X+016900Y+007492X0198Y0197R270 S2      
327m0184            VIA   -    M      A12X+019460Y+008990X0260Y         S2      
327m0184            R295  -2          A12X+018196Y+009338X0198Y0197R090 S2      
327m0184            R296  -1   M      A12X+018898Y+009338X0198Y0197R270 S2      
327m0184            R670  -1   M      A12X+018547Y+009338X0198Y0197R270 S2      
327m0184            U23   -4          A12X+018780Y+008745X0220Y0320R270 S2      
317TP_PLD_C13       VIA   -     D0100PA00X+009707Y+038733X0180Y         S0      
327TP_PLD_C13       U25   -P5         A01X+009551Y+038578X0160Y    R180 S1      
327m0185            R126  -1          A01X+026992Y+039950X0198Y0197     S1      
327m0185            VIA   -    M      A01X+026030Y+040337X0300Y         S1      
327m0185            J5    -6          A01X+025516Y+038329X0240Y0650R270 S1      
327m0186            J5    -10         A01X+023855Y+037739X0240Y0650R090 S1      
327m0186            R136  -2          A01X+022670Y+038326X0198Y0197     S1      
327m0187            VIA   -    M      A01X+024190Y+011430X0300Y         S1      
317m0187            VIA   -    MD0100PA00X+023921Y+011230X0200Y         S0      
327m0187            R273  -1          A01X+024370Y+010918X0198Y0197R270 S1      
327m0187            U5    -A10        A01X+022715Y+015500X0160Y    R180 S1      
317m0187            VIA   -    MD0100PA00X+022566Y+015337X0180Y         S0      
327m0188            R634  -2          A01X+009080Y+033340X0198Y0197R090 S1      
327m0188            U25   -B6         A01X+009236Y+034798X0160Y    R180 S1      
327m0189            R644  -2          A12X+015200Y+025272X0198Y0197R090 S2      
327m0189            VIA   -    M      A12X+015230Y+024820X0260Y         S2      
327m0189            U5    -AD24       A01X+018305Y+022745X0160Y    R180 S1      
317m0189            VIA   -    MD0100PA00X+018150Y+022900X0180Y         S0      
327m0190            R634  -1          A01X+009080Y+033024X0198Y0197R090 S1      
327m0190            VIA   -    M      A12X+016164Y+027650X0260Y         S2      
327m0190            R642  -2   M      A12X+015200Y+025992X0198Y0197R090 S2      
327m0190            R644  -1          A12X+015200Y+025588X0198Y0197R090 S2      
327m0190            R640  -2   M      A12X+016942Y+026700X0198Y0197     S2      
317m0190            VIA   -    MD0100PA00X+011056Y+029633X0200Y         S0      
317m0190            VIA   -    MD0100PA00X+009329Y+033029X0200Y         S0      
327m0191            R445  -2          A01X+010050Y+040292X0198Y0197R270 S1      
327m0191            U25   -R4         A01X+009866Y+038892X0160Y    R180 S1      
327m0192            R407  -1          A12X+020400Y+026418X0198Y0197R090 S2      
327m0192            U5    -AD15       A01X+021140Y+022745X0160Y    R180 S1      
317m0192            VIA   -    M      A01X+020590Y+026613X0300Y         S1      
017m0192            VIA   -    M      A12X+020590Y+026613X0200Y         S1      
017m0192                  -    MD0100PA00X+020590Y+026613                       
317m0192            VIA   -    MD0100PA00X+020984Y+022900X0180Y    R180 S0      
327m0193            R635  -2          A01X+010450Y+040292X0198Y0197R270 S1      
327m0193            U25   -T3         A01X+010181Y+039208X0160Y    R180 S1      
327m0194            U5    -AD12       A01X+022085Y+022745X0160Y    R180 S1      
317m0194            VIA   -    MD0100PA00X+022240Y+022900X0180Y    R180 S2      
327m0194            R637  -1          A12X+021880Y+025048X0198Y0197R270 S2      
317m0194            VIA   -    MD0100PA00X+021551Y+025331X0200Y         S0      
327m0195            R635  -1          A01X+010450Y+040608X0198Y0197R270 S1      
327m0195            R452  -2          A12X+021410Y+025562X0198Y0197R090 S2      
317m0195            VIA   -    MD0100PA00X+012310Y+039060X0200Y         S0      
317m0195            VIA   -    MD0100PA00X+021680Y+025555X0200Y         S0      
317m0195            VIA   -    MD0100PA00X+023247Y+038228X0200Y         S0      
327m0195            R637  -2          A12X+021880Y+025364X0198Y0197R270 S2      
317m0195            VIA   -    M      A01X+010834Y+041155X0200Y         S2      
017m0195            VIA   -    M      A12X+010834Y+041155X0260Y         S2      
017m0195                  -    MD0100PA00X+010834Y+041155                       
327m0196            R494  -1          A01X+022180Y+024902X0198Y0197R090 S1      
327m0196            U5    -AF11       A01X+022400Y+023374X0160Y    R180 S1      
327RST_BMC_HW_R     R638  -1          A01X+005008Y+038000X0198Y0197R180 S1      
327RST_BMC_HW_R     U25   -J15        A01X+006401Y+037003X0160Y    R180 S1      
327RST_BMC_HW       R887  -2          A01X+004050Y+038108X0198Y0197R090 S1      
317RST_BMC_HW       VIA   -    M      A01X+012250Y+041968X0200Y         S2      
017RST_BMC_HW       VIA   -    M      A12X+012250Y+041968X0260Y         S2      
017RST_BMC_HW             -    MD0100PA00X+012250Y+041968                       
327RST_BMC_HW       R282  -2          A12X+013000Y+040258X0198Y0197R270 S2      
317RST_BMC_HW       VIA   -    MD0100PA00X+004450Y+038000X0200Y         S0      
327RST_BMC_HW       R638  -2          A01X+004692Y+038000X0198Y0197R180 S1      
327m0197            FS1   -2          A12X+012510Y+007509X0400Y0710R090 S2      
327m0197            J8    -13         A01X+013632Y+007724X0240Y0610R270 S1      
317m0197            VIA   -    MD0100PA00X+013050Y+007470X0200Y         S0      
327m0197            VIA   -           A12X+012580Y+006900X0260Y         S2      
327CRT_VCC5_2_D     FS1   -1          A12X+012510Y+008651X0400Y0710R090 S2      
327CRT_VCC5_2_D     D16   -2   M      A12X+011650Y+008371X0250Y0400R270 S2      
327CRT_VCC5_2_D     VIA   -           A12X+011300Y+008850X0260Y    R180 S2      
327m0198            VIA   -    M      A01X+002560Y+010630X0300Y         S1      
327m0198            J6    -1          A01X+004528Y+008900X0400Y1090R090 S1      
317m0198            VIA   -    MD0100PA00X+001250Y+010200X0200Y         S0      
327m0198            R765  -2          A12X+001672Y+011620X0198Y0197     S2      
327m0198            R102  -2          A12X+001680Y+011248X0198Y0197R270 S2      
327m0199            VIA   -    M      A12X+002200Y+011140X0260Y         S2      
327m0199            R102  -1          A12X+001680Y+010932X0198Y0197R270 S2      
327m0199            U24   -6          A12X+002766Y+011176X0170Y0240R090 S2      
327m0200            VIA   -    M      A12X+004000Y+010420X0260Y         S2      
327m0200            R104  -1          A12X+004532Y+010230X0198Y0197R180 S2      
327m0200            U24   -4          A12X+002766Y+010664X0170Y0240R090 S2      
317m0201            VIA   -    M      A01X+004094Y+011256X0200Y    R180 S2      
017m0201            VIA   -    M      A12X+004094Y+011256X0260Y    R180 S2      
017m0201                  -    MD0100PA00X+004094Y+011256                       
327m0201            J6    -3          A01X+004528Y+010900X0400Y1090R090 S1      
327m0201            U24   -3          A12X+003514Y+010664X0170Y0240R090 S2      
327m0201            R741  -2   M      A12X+004532Y+010620X0198Y0197     S2      
327TP_J40_6         J40   -6          A01X+016301Y+036657X0200Y0590     S1      
327TP_J40_6         U17   -6          A01X+016301Y+036520X0170Y0670     S1      
327TP_J40_5         J40   -5          A01X+015801Y+036657X0200Y0590     S1      
327TP_J40_5         U17   -5          A01X+015801Y+036520X0170Y0670     S1      
327TP_J40_4         J40   -4          A01X+015301Y+036657X0200Y0590     S1      
327TP_J40_4         U17   -4          A01X+015301Y+036520X0170Y0670     S1      
327TP_J40_14        J40   -14         A01X+014801Y+040437X0200Y0590     S1      
327TP_J40_14        U17   -14         A01X+014801Y+040575X0170Y0670     S1      
327TP_J40_13        J40   -13         A01X+015301Y+040437X0200Y0590     S1      
327TP_J40_13        U17   -13         A01X+015301Y+040575X0170Y0670     S1      
327TP_J40_12        J40   -12         A01X+015801Y+040437X0200Y0590     S1      
327TP_J40_12        U17   -12  M      A01X+015801Y+040575X0170Y0670     S1      
327TP_J40_12        VIA   -           A01X+016112Y+042459X0300Y         S1      
327TP_J40_11        J40   -11         A01X+016301Y+040437X0200Y0590     S1      
327TP_J40_11        U17   -11  M      A01X+016301Y+040575X0170Y0670     S1      
327TP_J40_11        VIA   -           A01X+016645Y+042481X0300Y         S1      
327m0202            U21   -14         A12X+016130Y+040424X0140Y0590R090 S2      
327m0202            VIA   -           A12X+018824Y+041765X0260Y         S2      
327m0203            U21   -13         A12X+016130Y+040168X0140Y0590R090 S2      
327m0203            VIA   -           A12X+019247Y+041485X0260Y         S2      
327m0204            U21   -12         A12X+016130Y+039912X0140Y0590R090 S2      
327m0204            VIA   -           A12X+019460Y+041966X0260Y         S2      
327m0205            R864  -2          A01X+021960Y+042912X0198Y0197R270 S1      
327m0205            U21   -11         A12X+016130Y+039657X0140Y0590R090 S2      
317m0205            VIA   -    MD0100PA00X+014251Y+039369X0200Y    R090 S0      
327m0205            VIA   -    M      A12X+015464Y+039657X0260Y         S2      
327m0206            R97   -1          A01X+032992Y+037200X0198Y0197     S1      
317m0206            VIA   -    M      A01X+032620Y+037068X0200Y         S2      
017m0206            VIA   -    M      A12X+032620Y+037068X0260Y         S2      
017m0206                  -    MD0100PA00X+032620Y+037068                       
327m0206            J10   -3          A01X+032013Y+037148X0240Y0650R270 S1      
327m0207            R98   -1          A01X+032992Y+037650X0198Y0197     S1      
317m0207            VIA   -    M      A01X+032610Y+037572X0200Y         S2      
017m0207            VIA   -    M      A12X+032610Y+037572X0260Y         S2      
017m0207                  -    MD0100PA00X+032610Y+037572                       
327m0207            J10   -4          A01X+032013Y+037542X0240Y0650R270 S1      
327m0208            R100  -2          A01X+033308Y+038550X0198Y0197     S1      
327m0208            VIA   -    M      A12X+026050Y+030050X0260Y         S2      
317m0208            VIA   -    MD0100PA00X+027240Y+039240X0200Y         S0      
317m0208            VIA   -    MD0100PA00X+023840Y+030420X0200Y         S0      
317m0208            VIA   -    MD0100PA00X+026620Y+029480X0200Y         S0      
327m0208            R238  -2   M      A01X+026940Y+028142X0198Y0197R270 S1      
327m0208            R460  -1          A01X+027325Y+027558X0198Y0197R270 S1      
327m0209            R100  -1          A01X+032992Y+038550X0198Y0197     S1      
317m0209            VIA   -    M      A01X+032638Y+038072X0200Y         S2      
017m0209            VIA   -    M      A12X+032638Y+038072X0260Y         S2      
017m0209                  -    MD0100PA00X+032638Y+038072                       
327m0209            J10   -5          A01X+032013Y+037936X0240Y0650R270 S1      
327m0210            R109  -1          A01X+032992Y+036300X0198Y0197     S1      
327m0210            J10   -1          A01X+032013Y+036361X0240Y0650R270 S1      
327m0211            R546  -1          A12X+012622Y+024970X0198Y0197R180 S2      
317m0211            VIA   -    M      A01X+022776Y+008252X0300Y         S1      
017m0211            VIA   -    M      A12X+022776Y+008252X0200Y         S1      
017m0211                  -    MD0100PA00X+022776Y+008252                       
327m0211            U29   -2          A12X+023050Y+007946X0160Y0240R180 S2      
317m0211            VIA   -    MD0100PA00X+011614Y+023079X0200Y         S0      
327SPA_SIN_SW_DBG   R628  -1          A12X+012702Y+028300X0198Y0197R180 S2      
317SPA_SIN_SW_DBG   VIA   -    M      A01X+010358Y+023740X0200Y    R090 S2      
017SPA_SIN_SW_DBG   VIA   -    M      A12X+010358Y+023740X0260Y    R090 S2      
017SPA_SIN_SW_DBG         -    MD0100PA00X+010358Y+023740                       
317SPA_SIN_SW_DBG   VIA   -    MD0100PA00X+023215Y+008248X0200Y         S0      
327SPA_SIN_SW_DBG   R193  -2          A12X+024170Y+009392X0198Y0197R090 S2      
327SPA_SIN_SW_DBG   U36   -4   M      A12X+024205Y+008654X0240Y0240R270 S2      
317SPA_SIN_SW_DBG   VIA   -    MD0100PA00X+005101Y+023357X0200Y         S0      
317SPA_SIN_SW_DBG   VIA   -    MD0100PA00X+004034Y+010071X0200Y         S0      
317m0212            VIA   -    MD0100PA00X+010855Y+029424X0200Y         S0      
327m0212            R731  -1          A12X+014320Y+038276X0198Y0197R180 S2      
327m0212            R95   -1          A12X+020018Y+037075X0198Y0197R180 S2      
317m0212            VIA   -    MD0100PA00X+013920Y+037251X0200Y         S0      
317m0212            VIA   -    MD0100PA00X+019740Y+037025X0200Y         S0      
327m0212            R302  -2          A12X+006600Y+028808X0198Y0197R270 S2      
317m0212            VIA   -    MD0100PA00X+005890Y+028808X0200Y         S0      
327m0213            R732  -1          A12X+014320Y+037876X0198Y0197R180 S2      
317m0213            VIA   -    M      A01X+014570Y+037070X0200Y         S2      
017m0213            VIA   -    M      A12X+014570Y+037070X0260Y         S2      
017m0213                  -    MD0100PA00X+014570Y+037070                       
317m0213            VIA   -    MD0100PA00X+019740Y+036760X0200Y         S0      
327m0213            R632  -1          A12X+020018Y+036725X0198Y0197R180 S2      
317m0213            VIA   -    MD0100PA00X+012634Y+038270X0200Y         S0      
317m0213            VIA   -    MD0100PA00X+007596Y+028405X0200Y         S0      
327m0213            R300  -2          A12X+007328Y+028710X0198Y0197R180 S2      
327m0214            VIA   -    M      A12X+006120Y+027640X0260Y         S2      
327m0214            R302  -1          A12X+006600Y+028492X0198Y0197R270 S2      
327m0214            U37   -6          A12X+006422Y+026530X0140Y0590     S2      
327m0214            R299  -2   M      A12X+006600Y+027442X0198Y0197R090 S2      
327m0215            VIA   -    M      A12X+007230Y+028250X0260Y         S2      
327m0215            R300  -1          A12X+007012Y+028710X0198Y0197R180 S2      
327m0215            U37   -7          A12X+006678Y+026530X0140Y0590     S2      
327m0215            R298  -2   M      A12X+007000Y+027442X0198Y0197R090 S2      
327m0216            R33   -2          A01X+029284Y+039160X0198Y0197     S1      
327m0216            J10   -6          A01X+032013Y+038329X0240Y0650R270 S1      
327m0217            R47   -1          A01X+029284Y+038750X0198Y0197R180 S1      
327m0217            VIA   -    M      A01X+029045Y+038269X0300Y         S1      
327m0217            J10   -10         A01X+030351Y+037739X0240Y0650R090 S1      
327m0218            R303  -1          A12X+007200Y+033108X0198Y0197R090 S2      
327m0218            VIA   -    M      A12X+007450Y+033570X0260Y         S2      
317m0218            VIA   -    MD0100PA00X+008136Y+034957X0180Y         S0      
327m0218            U25   -C9         A01X+008291Y+035113X0160Y    R180 S1      
327m0219            R272  -1          A12X+006800Y+031958X0198Y0197R090 S2      
327m0219            VIA   -    M      A12X+007330Y+031958X0260Y         S2      
327m0219            U25   -A9         A01X+008291Y+034483X0160Y    R180 S1      
317m0219            VIA   -    MD0100PA00X+008170Y+034260X0200Y         S0      
327m0220            R426  -2          A01X+015562Y+017480X0198Y0197R180 S1      
317m0220            VIA   -    M      A01X+012981Y+019131X0300Y         S1      
017m0220            VIA   -    M      A12X+012981Y+019131X0200Y         S1      
017m0220                  -    MD0100PA00X+012981Y+019131                       
327m0220            R438  -2   M      A01X+014215Y+018400X0198Y0197R270 S1      
317m0220            VIA   -    MD0100PA00X+009440Y+030720X0200Y         S0      
317m0220            VIA   -    MD0100PA00X+027770Y+040610X0200Y         S0      
327m0220            R46   -1          A12X+026140Y+041748X0198Y0197R270 S2      
317m0220            VIA   -    MD0100PA00X+024792Y+031900X0200Y         S0      
327m0221            R429  -2   M      A12X+015066Y+019260X0198Y0197R180 S2      
317m0221            VIA   -    MD0100PA00X+009440Y+031110X0200Y         S0      
317m0221            VIA   -    MD0100PA00X+014910Y+018996X0200Y         S0      
327m0221            R425  -2          A12X+015563Y+019258X0198Y0197     S2      
317m0221            VIA   -    M      A01X+027770Y+041258X0200Y         S2      
017m0221            VIA   -    M      A12X+027770Y+041258X0260Y         S2      
017m0221                  -    MD0100PA00X+027770Y+041258                       
327m0221            R36   -1          A12X+026540Y+041748X0198Y0197R270 S2      
317m0221            VIA   -    MD0100PA00X+024301Y+032340X0200Y         S0      
327m0222            GF1   -A2         A12X+024750Y+046638X0150Y0840R180 S2      
327m0222            R46   -2          A12X+026140Y+042062X0198Y0197R270 S2      
327m0222            VIA   -    M      A12X+025710Y+042880X0260Y         S2      
327m0223            GF1   -A1         A12X+024986Y+046638X0150Y0840R180 S2      
327m0223            R36   -2          A12X+026540Y+042062X0198Y0197R270 S2      
327m0223            VIA   -    M      A12X+026219Y+042530X0260Y         S2      
317m0224            VIA   -    M      A01X+007750Y+031610X0200Y         S2      
017m0224            VIA   -    M      A12X+007750Y+031610X0260Y         S2      
017m0224                  -    MD0100PA00X+007750Y+031610                       
317m0224            VIA   -    MD0100PA00X+013875Y+045450X0200Y         S0      
327m0224            GF1   -A41        A12X+014195Y+046638X0150Y0840R180 S2      
327m0224            R428  -2          A12X+015128Y+018211X0198Y0197R180 S2      
317m0224            VIA   -    MD0100PA00X+015000Y+018497X0200Y         S0      
327m0224            R424  -2          A12X+015563Y+018908X0198Y0197     S2      
327m0225            VIA   -    M      A12X+014897Y+017343X0260Y         S2      
327m0225            R422  -2          A12X+015344Y+017572X0198Y0197     S2      
317m0225            VIA   -    MD0100PA00X+007340Y+031370X0200Y         S0      
317m0225            VIA   -    MD0100PA00X+015062Y+017865X0200Y         S0      
327m0225            R423  -2          A01X+014852Y+018259X0198Y0197R180 S1      
327m0225            GF1   -A40        A12X+014431Y+046559X0150Y0680R180 S2      
317m0225            VIA   -    MD0100PA00X+013875Y+045150X0200Y         S0      
327m0226            U5    -AB16       A01X+020825Y+022115X0160Y    R180 S1      
317m0226            VIA   -    MD0100PA00X+020669Y+022270X0180Y         S2      
327m0226            R448  -2          A12X+019250Y+025018X0198Y0197R090 S2      
327m0227            R456  -2          A12X+005008Y+034400X0198Y0197R180 S2      
327m0227            VIA   -    M      A12X+005453Y+034820X0260Y         S2      
317m0227            VIA   -    MD0100PA00X+006876Y+035902X0180Y         S0      
327m0227            U25   -F13        A01X+007031Y+036058X0160Y    R180 S1      
327m0228            R443  -2          A01X+015928Y+016710X0198Y0197     S1      
327m0228            U5    -J25        A01X+017990Y+018020X0160Y    R180 S1      
327m0228            VIA   -    M      A01X+016447Y+016990X0300Y         S1      
327m0229            R454  -2          A01X+005008Y+034000X0198Y0197     S1      
327m0229            U25   -D15        A01X+006401Y+035428X0160Y    R180 S1      
327m0230            R442  -2          A01X+015868Y+016340X0198Y0197     S1      
327m0230            U5    -H26        A01X+017675Y+017705X0160Y    R180 S1      
327m0230            VIA   -    M      A01X+016498Y+016484X0300Y         S1      
327m0231            R453  -2          A01X+005008Y+033600X0198Y0197     S1      
327m0231            U25   -C16        A01X+006086Y+035113X0160Y    R180 S1      
327m0232            U5    -AA17       A01X+020510Y+021800X0160Y    R180 S1      
317m0232            VIA   -    MD0100PA00X+020354Y+021955X0180Y         S0      
327m0232            R449  -2          A12X+018850Y+025018X0198Y0197R090 S2      
327m0233            R457  -2          A12X+005008Y+037200X0198Y0197R180 S2      
327m0233            VIA   -    M      A12X+005960Y+036310X0260Y         S2      
317m0233            VIA   -    MD0100PA00X+007191Y+036217X0180Y         S0      
327m0233            U25   -G12        A01X+007346Y+036373X0160Y    R180 S1      
327m0234            R108  -1          A01X+003682Y+031710X0198Y0197     S1      
327m0234            U6    -4          A01X+003574Y+032244X0170Y0240R270 S1      
327m0235            J40   -3          A01X+014801Y+036657X0200Y0590     S1      
327m0235            VIA   -    M      A01X+015300Y+034860X0300Y         S1      
327m0235            U17   -3   M      A01X+014801Y+036520X0170Y0670     S1      
327m0235            R496  -2          A01X+015792Y+035050X0198Y0197R180 S1      
327m0236            R90   -2          A01X+007950Y+026942X0198Y0197R270 S1      
327m0236            R561  -1   M      A01X+008350Y+027258X0198Y0197R270 S1      
327m0236            J4    -19         A01X+008661Y+031854X0110Y0630     S1      
327m0237            R562  -1          A01X+008750Y+027258X0198Y0197R270 S1      
327m0237            J4    -21         A01X+008858Y+031854X0110Y0630     S1      
327m0238            R691  -1          A01X+005008Y+034400X0198Y0197R180 S1      
327m0238            U25   -E16        A01X+006086Y+035743X0160Y    R180 S1      
327RST_EXTRST_R_N   R447  -1          A01X+006880Y+033138X0198Y0197R270 S1      
327RST_EXTRST_R_N   U25   -A11        A01X+007661Y+034483X0160Y    R180 S1      
327RST_EXTRST_N     R447  -2          A01X+006880Y+032822X0198Y0197R270 S1      
317RST_EXTRST_N     VIA   -    MD0100PA00X+005660Y+031800X0200Y         S0      
317RST_EXTRST_N     VIA   -    MD0100PA00X+009092Y+029352X0200Y         S0      
317RST_EXTRST_N     VIA   -    MD0100PA00X+013154Y+039469X0200Y         S0      
327RST_EXTRST_N     R636  -1          A01X+021350Y+038908X0198Y0197R270 S1      
327RST_EXTRST_N     U5    -B10        A01X+022715Y+015816X0160Y    R180 S1      
327RST_EXTRST_N     R623  -2          A01X+023351Y+013814X0198Y0197R090 S1      
327RST_EXTRST_N     VIA   -    M      A01X+023351Y+014298X0300Y         S1      
317RST_EXTRST_N     VIA   -    MD0100PA00X+022770Y+015190X0200Y         S0      
327m0239            R108  -2          A01X+003998Y+031710X0198Y0197     S1      
327m0239            R125  -1   M      A01X+004142Y+041970X0198Y0197     S1      
327m0239            R315  -1          A01X+004142Y+041570X0198Y0197     S1      
327m0239            R124  -2   M      A01X+004080Y+042342X0198Y0197R270 S1      
317m0239            VIA   -    M      A01X+003800Y+042880X0200Y         S2      
017m0239            VIA   -    M      A12X+003800Y+042880X0260Y         S2      
017m0239                  -    MD0100PA00X+003800Y+042880                       
317m0239            VIA   -    MD0100PA00X+003510Y+035240X0200Y         S0      
327m0239            C223  -1   M      A01X+003792Y+035200X0198Y0197     S1      
327m0239            R192  -2          A01X+004108Y+034850X0198Y0197     S1      
317m0239            VIA   -    MD0100PA00X+004350Y+031710X0200Y         S0      
327m0240            U13   -2          A01X+005182Y+041866X0160Y0200R090 S1      
317m0240            VIA   -    M      A01X+004610Y+041270X0200Y         S2      
017m0240            VIA   -    M      A12X+004610Y+041270X0260Y         S2      
017m0240                  -    MD0100PA00X+004610Y+041270                       
327m0240            R315  -2          A01X+004458Y+041570X0198Y0197     S1      
327m0241            VIA   -    M      A12X+012795Y+039575X0260Y         S2      
327m0241            R450  -2          A12X+012600Y+039942X0198Y0197R090 S2      
327m0241            U58   -1          A12X+012661Y+038702X0280Y0400R180 S2      
327m0242            R271  -2   M      A12X+005008Y+036000X0198Y0197R180 S2      
327m0242            R641  -2          A12X+005000Y+035292X0198Y0197R090 S2      
317m0242            VIA   -    MD0100PA00X+006876Y+036217X0180Y         S2      
327m0242            U25   -G13        A01X+007031Y+036373X0160Y    R180 S1      
327m0243            R96   -1          A01X+025240Y+027734X0198Y0197R090 S1      
317m0243            VIA   -    M      A01X+025714Y+027970X0300Y         S1      
017m0243            VIA   -    M      A12X+025714Y+027970X0200Y         S1      
017m0243                  -    MD0100PA00X+025714Y+027970                       
327m0243            U5    -AA12       A01X+022085Y+021800X0160Y    R180 S1      
317m0243            VIA   -    MD0100PA00X+022240Y+021955X0180Y    R180 S0      
327m0244            VIA   -    M      A01X+008968Y+042194X0300Y         S1      
327m0244            R314  -1   M      A01X+008968Y+041700X0198Y0197     S1      
327m0244            C173  -1   M      A01X+008968Y+041250X0198Y0197     S1      
327m0244            C161  -2          A01X+009142Y+042802X0198Y0197R180 S1      
327m0244            U12   -G          A01X+008308Y+041356X0400Y0560R090 S1      
327m0245            D17   -2          A01X+009898Y+041520X0260Y0540R270 S1      
327m0245            C161  -1          A01X+009456Y+042802X0198Y0197R180 S1      
327m0245            R313  -1   M      A01X+009868Y+042538X0198Y0197R090 S1      
327m0246            R888  -2          A01X+004692Y+036000X0180Y0200     S1      
327m0246            R271  -1          A12X+004692Y+036000X0198Y0197R180 S2      
317m0246            VIA   -    MD0100PA00X+004452Y+036000X0200Y         S0      
327m0246            R494  -2          A01X+022180Y+025218X0198Y0197R090 S1      
317m0246            VIA   -    MD0100PA00X+012170Y+042400X0200Y         S0      
317m0246            VIA   -    MD0100PA00X+023190Y+027270X0200Y         S0      
317m0246            VIA   -    M      A01X+022013Y+040078X0200Y         S2      
017m0246            VIA   -    M      A12X+022013Y+040078X0260Y         S2      
017m0246                  -    MD0100PA00X+022013Y+040078                       
327m0246            R450  -1          A12X+012600Y+040258X0198Y0197R090 S2      
327m0247            R110  -1          A01X+032992Y+036750X0198Y0197     S1      
317m0247            VIA   -    M      A01X+032590Y+036564X0200Y         S2      
017m0247            VIA   -    M      A12X+032590Y+036564X0260Y         S2      
017m0247                  -    MD0100PA00X+032590Y+036564                       
327m0247            J10   -2          A01X+032013Y+036754X0240Y0650R270 S1      
317m0248            VIA   -    M      A01X+033548Y+036750X0200Y         S2      
017m0248            VIA   -    M      A12X+033548Y+036750X0260Y         S2      
017m0248                  -    MD0100PA00X+033548Y+036750                       
327m0248            R110  -2          A01X+033308Y+036750X0198Y0197     S1      
327m0248            R106  -2   M      A01X+021350Y+037958X0198Y0197R090 S1      
327m0248            R287  -2          A01X+019375Y+038858X0198Y0197R090 S1      
327m0248            Q1    -C   M      A01X+020360Y+038695X0400Y0500     S1      
327m0248            R636  -2   M      A01X+021350Y+038592X0198Y0197R270 S1      
317m0248            VIA   -    MD0100PA00X+020800Y+037324X0200Y         S0      
327m0249            U12   -D   M      A01X+007442Y+041730X0400Y0560R090 S1      
327m0249            U13   -4          A01X+005930Y+041610X0160Y0200R090 S1      
317m0249            VIA   -    M      A01X+007478Y+041380X0200Y         S2      
017m0249            VIA   -    M      A12X+007478Y+041380X0260Y         S2      
017m0249                  -    MD0100PA00X+007478Y+041380                       
317m0249            VIA   -    MD0100PA00X+019005Y+038914X0200Y         S0      
327m0249            R291  -2   M      A01X+019375Y+036818X0198Y0197R270 S1      
327m0249            R290  -2          A01X+019375Y+036382X0198Y0197R090 S1      
327PWR_LED_CPLD     R317  -1          A12X+005008Y+038400X0198Y0197     S2      
327PWR_LED_CPLD     VIA   -    M      A12X+006192Y+038348X0260Y         S2      
317PWR_LED_CPLD     VIA   -    MD0100PA00X+006872Y+038103X0180Y         S0      
327PWR_LED_CPLD     U25   -M14        A01X+006716Y+037948X0160Y    R180 S1      
327PWR_LED          R317  -2          A12X+004692Y+038400X0198Y0197     S2      
317PWR_LED          VIA   -    MD0100PA00X+005212Y+007837X0200Y         S0      
327PWR_LED          R839  -1   M      A01X+005250Y+007308X0198Y0197R270 S1      
317PWR_LED          VIA   -    M      A01X+003150Y+042850X0200Y         S2      
017PWR_LED          VIA   -    M      A12X+003150Y+042850X0260Y         S2      
017PWR_LED                -    MD0100PA00X+003150Y+042850                       
317PWR_LED          VIA   -    MD0100PA00X+003130Y+032990X0200Y         S0      
317PWR_LED          VIA   -    MD0100PA00X+012060Y+029347X0200Y         S0      
317PWR_LED          VIA   -    MD0100PA00X+012615Y+019908X0200Y         S0      
327PWR_LED          R316  -2          A01X+013392Y+020150X0198Y0197R180 S1      
327PWR_LED          Q12   -2          A01X+004450Y+007224X0170Y0200     S1      
327m0250            R871  -2          A01X+004352Y+024490X0198Y0197R180 S1      
327m0250            R381  -2   M      A01X+004432Y+024880X0198Y0197R180 S1      
327m0250            PU1   -5          A01X+003464Y+025133X0098Y0276     S1      
317m0250            VIA   -    M      A01X+004110Y+024890X0200Y         S2      
017m0250            VIA   -    M      A12X+004110Y+024890X0260Y         S2      
017m0250                  -    MD0100PA00X+004110Y+024890                       
327m0251            D23   -2          A12X+004850Y+039628X0260Y0540     S2      
317m0251            VIA   -    MD0100PA00X+004708Y+039173X0200Y         S0      
327m0251            R886  -2   M      A01X+005008Y+038770X0198Y0197     S1      
327m0251            U25   -M15        A01X+006401Y+037948X0160Y    R180 S1      
327m0252            PU38  -9          A01X+003331Y+020346X0120Y0320R270 S1      
327m0252            R868  -1          A01X+003688Y+021470X0198Y0197R180 S1      
327m0252            VIA   -    M      A01X+003629Y+020859X0300Y         S1      
327m0252            C150  -1   M      A12X+004450Y+021558X0198Y0197R090 S2      
327m0252            PR241 -2   M      A01X+004241Y+021472X0198Y0197R180 S1      
327m0252            PR245 -1   M      A01X+004241Y+021070X0198Y0197     S1      
327m0252            R292  -1          A12X+004696Y+022048X0198Y0197R180 S2      
317m0252            VIA   -    MD0100PA00X+003980Y+021380X0200Y         S0      
327m0253            R322  -1          A12X+007450Y+039992X0198Y0197R270 S2      
327m0253            VIA   -    M      A12X+008390Y+038570X0260Y         S2      
317m0253            VIA   -    MD0100PA00X+008136Y+038418X0180Y         S0      
327m0253            U25   -N9         A01X+008291Y+038263X0160Y    R180 S1      
327m0254            R709  -2          A01X+028032Y+012325X0198Y0197     S1      
327m0254            R872  -1          A01X+028130Y+011148X0198Y0197R270 S1      
327m0254            C252  -1   M      A01X+027720Y+011908X0198Y0197R270 S1      
327m0254            R99   -1          A01X+028125Y+011908X0198Y0197R270 S1      
317m0254            VIA   -           A01X+028040Y+012600X0200Y         S2      
017m0254            VIA   -           A12X+028040Y+012600X0260Y         S2      
017m0254                  -     D0100PA00X+028040Y+012600                       
327m0255            U39   -6          A01X+032142Y+012610X0110Y0360     S1      
327m0255            R382  -2          A01X+032087Y+012028X0198Y0197R090 S1      
317m0255            VIA   -           A01X+032094Y+012268X0200Y         S2      
017m0255            VIA   -           A12X+032094Y+012268X0260Y         S2      
017m0255                  -     D0100PA00X+032094Y+012268                       
327m0256            R318  -1          A01X+005048Y+039435X0198Y0197R180 S1      
327m0256            U25   -N16        A01X+006086Y+038263X0160Y    R180 S1      
327m0257            PU1   -9          A01X+003267Y+025841X0100Y0360R180 S1      
327m0257            C151  -1   M      A01X+004447Y+026698X0198Y0197R270 S1      
327m0257            PR242 -2          A01X+004872Y+026080X0198Y0197R180 S1      
327m0257            R293  -1   M      A01X+004872Y+026460X0198Y0197     S1      
327EN_P1V8_R        U41   -6          A01X+013826Y+022416X0110Y0360R270 S1      
327EN_P1V8_R        R875  -2          A01X+012872Y+022462X0198Y0197R270 S1      
317EN_P1V8_R        VIA   -           A01X+013489Y+022517X0200Y         S2      
017EN_P1V8_R        VIA   -           A12X+013489Y+022517X0260Y         S2      
017EN_P1V8_R              -     D0100PA00X+013489Y+022517                       
327EN_P1V8_R        R393  -2          A01X+013240Y+022462X0198Y0197R270 S1      
327m0258            R320  -1          A12X+005008Y+038800X0198Y0197     S2      
327m0258            VIA   -    M      A12X+005460Y+038800X0260Y         S2      
317m0258            VIA   -    MD0100PA00X+006561Y+038418X0180Y         S0      
327m0258            U25   -N14        A01X+006716Y+038263X0160Y    R180 S1      
327m0259            U39   -5          A01X+032142Y+013831X0110Y0360     S1      
327m0259            C153  -1          A01X+032200Y+014492X0198Y0197R090 S1      
327m0259            R403  -2   M      A12X+031800Y+013332X0198Y0197R270 S2      
327m0259            VIA   -    M      A12X+032253Y+013895X0260Y         S2      
327m0259            R35   -2          A12X+031400Y+013332X0198Y0197R270 S2      
317m0259            VIA   -    MD0100PA00X+032160Y+014210X0200Y         S0      
327EN_P3V3_RGM_R    R380  -2          A01X+026590Y+011308X0198Y0197R090 S1      
327EN_P3V3_RGM_R    R869  -2          A01X+027730Y+010898X0198Y0197R090 S1      
327EN_P3V3_RGM_R    VIA   -    M      A01X+027150Y+011160X0300Y         S1      
327EN_P3V3_RGM_R    U14   -4          A01X+026359Y+011808X0220Y0320R180 S1      
327m0260            R321  -1          A12X+007850Y+039992X0198Y0197R270 S2      
317m0260            VIA   -    M      A01X+007900Y+039550X0200Y         S2      
017m0260            VIA   -    M      A12X+007900Y+039550X0260Y         S2      
017m0260                  -    MD0100PA00X+007900Y+039550                       
327m0260            U25   -M8         A01X+008606Y+037948X0160Y    R180 S1      
327m0261            U41   -5          A01X+015047Y+022416X0110Y0360R270 S1      
327m0261            R874  -2          A01X+014950Y+022942X0198Y0197R270 S1      
327m0261            R275  -2          A01X+015350Y+022892X0198Y0197R270 S1      
327m0261            C154  -1          A01X+015750Y+022892X0198Y0197R090 S1      
327m0261            R406  -2          A01X+015642Y+022400X0198Y0197R180 S1      
327EN_P1V0_AUX_R    R878  -2          A01X+006009Y+012624X0198Y0197R090 S1      
327EN_P1V0_AUX_R    PU42  -5          A01X+007035Y+012623X0100Y0280R270 S1      
327EN_P1V0_AUX_R    R399  -2   M      A01X+006392Y+012623X0198Y0197R090 S1      
317EN_P1V0_AUX_R    VIA   -    M      A01X+006690Y+012530X0200Y    R180 S2      
017EN_P1V0_AUX_R    VIA   -    M      A12X+006690Y+012530X0260Y    R180 S2      
017EN_P1V0_AUX_R          -    MD0100PA00X+006690Y+012530                       
327m0262            R323  -1          A01X+007900Y+040292X0198Y0197R090 S1      
327m0262            U25   -T9         A01X+008291Y+039208X0160Y    R180 S1      
327m0263            PU41  -13         A01X+032754Y+028910X0100Y0280R270 S1      
327m0263            R877  -1          A01X+033650Y+030022X0198Y0197R090 S1      
327m0263            C155  -1   M      A01X+033372Y+029590X0198Y0197     S1      
327m0263            R276  -1   M      A01X+033250Y+030022X0198Y0197R090 S1      
327m0263            PR498 -2   M      A01X+033375Y+029208X0198Y0197R180 S1      
327m0264            R49   -2          A01X+013752Y+014390X0198Y0197R090 S1      
327m0264            U43   -3          A01X+013724Y+015298X0240Y0420     S1      
327m0265            R379  -1          A12X+007050Y+039992X0198Y0197R270 S2      
327m0265            VIA   -    M      A12X+008136Y+039030X0260Y         S2      
317m0265            VIA   -    MD0100PA00X+008136Y+038733X0180Y         S0      
327m0265            U25   -P9         A01X+008291Y+038578X0160Y    R180 S1      
327m0266            VIA   -    M      A01X+008395Y+013495X0300Y    R180 S1      
327m0266            PU42  -13         A01X+008177Y+013017X0100Y0280R270 S1      
327m0266            R277  -1          A01X+010040Y+013192X0198Y0197R090 S1      
327m0266            PR500 -2   M      A01X+009240Y+013191X0198Y0197R270 S1      
327m0266            C156  -1   M      A01X+009640Y+013192X0198Y0197R090 S1      
327m0267            VIA   -    M      A01X+012480Y+014813X0300Y         S1      
327m0267            R751  -2          A01X+013350Y+014408X0198Y0197R090 S1      
327m0267            U43   -1          A01X+012976Y+015298X0240Y0420     S1      
327m0267            R451  -2   M      A01X+012950Y+014408X0198Y0197R090 S1      
317m0268            VIA   -    M      A01X+003856Y+032974X0200Y         S2      
017m0268            VIA   -    M      A12X+003856Y+032974X0260Y         S2      
017m0268                  -    MD0100PA00X+003856Y+032974                       
327m0268            R192  -1          A01X+003792Y+034850X0198Y0197     S1      
327m0268            U6    -6          A01X+003574Y+032756X0170Y0240R270 S1      
317m0269            VIA   -    MD0100PA00X+017170Y+015690X0200Y         S0      
327m0269            U5    -D26        A01X+017675Y+016445X0160Y    R180 S1      
327m0269            R405  -1          A01X+014358Y+017916X0198Y0197R180 S1      
317m0269            VIA   -    M      A01X+014688Y+017750X0200Y         S2      
017m0269            VIA   -    M      A12X+014688Y+017750X0260Y         S2      
017m0269                  -    MD0100PA00X+014688Y+017750                       
327m0270            U30   -15         A12X+020418Y+030841X0140Y0590R270 S2      
327m0270            U21   -15         A12X+016130Y+040680X0140Y0590R090 S2      
327m0270            R870  -2   M      A12X+014882Y+040175X0198Y0197R180 S2      
327m0270            R405  -2          A01X+014044Y+017916X0198Y0197R180 S1      
327m0270            VIA   -    M      A12X+015411Y+040409X0260Y         S2      
317m0270            VIA   -    MD0100PA00X+015126Y+039950X0200Y    R090 S0      
327m0270            R467  -1   M      A12X+014882Y+039750X0198Y0197     S2      
317m0270            VIA   -    MD0100PA00X+019716Y+031422X0200Y         S0      
317m0270            VIA   -    MD0100PA00X+013790Y+017916X0200Y         S0      
317m0270            VIA   -    MD0100PA00X+012410Y+031110X0200Y         S0      
327IRQ_SGPIO_R_N    R690  -1          A12X+005220Y+033108X0198Y0197R090 S2      
327IRQ_SGPIO_R_N    VIA   -    M      A12X+005450Y+034139X0260Y         S2      
317IRQ_SGPIO_R_N    VIA   -    MD0100PA00X+006561Y+035587X0180Y         S0      
327IRQ_SGPIO_R_N    U25   -E14        A01X+006716Y+035743X0160Y    R180 S1      
327m0271            VIA   -    M      A01X+029050Y+037740X0300Y         S1      
327m0271            J10   -9          A01X+030351Y+037345X0240Y0650R090 S1      
327m0271            R113  -2          A01X+029158Y+037270X0198Y0197     S1      
327m0272            R123  -1          A01X+009800Y+032812X0198Y0197R090 S1      
327m0272            U5    -R24        A01X+018305Y+019910X0160Y    R180 S1      
317m0272            VIA   -    MD0100PA00X+015545Y+040100X0200Y         S0      
317m0272            VIA   -    MD0100PA00X+018150Y+019751X0180Y         S0      
317m0272            VIA   -    M      A01X+011663Y+041150X0200Y         S2      
017m0272            VIA   -    M      A12X+011663Y+041150X0260Y         S2      
017m0272                  -    MD0100PA00X+011663Y+041150                       
317m0272            VIA   -    MD0100PA00X+029678Y+037150X0200Y         S0      
317m0272            VIA   -    MD0100PA00X+009780Y+032570X0200Y         S0      
327m0272            J10   -8          A01X+030351Y+036951X0240Y0650R090 S1      
327m0272            R50   -2   M      A01X+029330Y+036751X0198Y0197     S1      
327FM_PWR_R_BTN     R432  -1          A12X+005008Y+038000X0198Y0197     S2      
327FM_PWR_R_BTN     VIA   -    M      A12X+005480Y+038180X0260Y         S2      
317FM_PWR_R_BTN     VIA   -    MD0100PA00X+006561Y+037473X0180Y         S0      
327FM_PWR_R_BTN     U25   -K14        A01X+006716Y+037318X0160Y    R180 S1      
317m0273            VIA   -    M      A01X+004448Y+032876X0200Y         S2      
017m0273            VIA   -    M      A12X+004448Y+032876X0260Y         S2      
017m0273                  -    MD0100PA00X+004448Y+032876                       
327m0273            U5    -E14        A01X+021455Y+016760X0160Y    R180 S1      
317m0273            VIA   -    MD0100PA00X+010967Y+013606X0200Y         S0      
317m0273            VIA   -    MD0100PA00X+021299Y+016605X0180Y    R180 S0      
327m0273            R439  -2          A01X+004692Y+032800X0198Y0197R180 S1      
327FM_PECI_SEL_N    R439  -1          A01X+005008Y+032800X0198Y0197R180 S1      
327FM_PECI_SEL_N    R446  -2   M      A01X+005008Y+033200X0198Y0197     S1      
327FM_PECI_SEL_N    U25   -B16        A01X+006086Y+034798X0160Y    R180 S1      
327m0274            R444  -2          A12X+016678Y+017320X0198Y0197R180 S2      
327m0274            U5    -H25        A01X+017990Y+017705X0160Y    R180 S1      
317m0274            VIA   -    MD0100PA00X+017835Y+017550X0180Y    R180 S2      
327m0275            R270  -1          A12X+006922Y+033522X0198Y0197     S2      
317m0275            VIA   -    MD0100PA00X+007821Y+035587X0180Y         S0      
327m0275            U25   -E10        A01X+007976Y+035743X0160Y    R180 S1      
327m0276            VIA   -    M      A12X+019429Y+030040X0260Y         S2      
317m0276            VIA   -    MD0100PA00X+019785Y+030720X0200Y         S0      
327m0276            U5    -AE14       A01X+021455Y+023060X0160Y    R180 S1      
317m0276            VIA   -    MD0100PA00X+021299Y+023215X0180Y    R180 S0      
327m0276            R55   -2   M      A12X+019892Y+030040X0198Y0197     S2      
327m0276            R111  -1          A12X+018828Y+030030X0198Y0197     S2      
327m0277            R111  -2          A12X+018512Y+030030X0198Y0197     S2      
317m0277            VIA   -    M      A01X+003702Y+038560X0200Y         S2      
017m0277            VIA   -    M      A12X+003702Y+038560X0260Y         S2      
017m0277                  -    MD0100PA00X+003702Y+038560                       
317m0277            VIA   -    MD0100PA00X+006876Y+037473X0180Y         S0      
327m0277            U25   -K13        A01X+007031Y+037318X0160Y    R180 S1      
317m0277            VIA   -    MD0100PA00X+018223Y+029642X0200Y         S0      
327m0278            R852  -2   M      A12X+017436Y+030090X0198Y0197R180 S2      
327m0278            VIA   -    M      A12X+017890Y+030110X0260Y         S2      
327m0278            U30   -1          A12X+018118Y+030585X0140Y0590R270 S2      
317m0278            VIA   -    MD0100PA00X+019460Y+031330X0200Y         S0      
327m0278            U21   -1          A12X+018430Y+040936X0140Y0590R090 S2      
317m0278            VIA   -    MD0100PA00X+019027Y+040996X0200Y         S0      
327m0278            R866  -1          A12X+019448Y+041025X0198Y0197R180 S2      
317m0279            VIA   -    MD0100PA00X+017289Y+015326X0200Y         S0      
327m0279            R112  -1   M      A01X+017190Y+013798X0198Y0197R270 S1      
327m0279            R56   -2          A01X+016800Y+013808X0198Y0197R090 S1      
317m0279            VIA   -    MD0100PA00X+018150Y+016290X0180Y         S0      
327m0279            U5    -D24        A01X+018305Y+016445X0160Y    R180 S1      
317m0280            VIA   -    MD0100PA00X+011090Y+037850X0200Y         S0      
317m0280            VIA   -    MD0100PA00X+007191Y+037473X0180Y         S0      
327m0280            U25   -K12        A01X+007346Y+037318X0160Y    R180 S1      
317m0280            VIA   -    MD0100PA00X+017061Y+013190X0200Y         S0      
327m0280            R112  -2          A01X+017190Y+013482X0198Y0197R270 S1      
317m0281            VIA   -    MD0100PA00X+022433Y+008321X0200Y         S0      
327m0281            R219  -1   M      A12X+022750Y+009342X0198Y0197R270 S2      
327m0281            U29   -4          A12X+022755Y+008654X0240Y0240R270 S2      
327m0281            VIA   -    M      A12X+015350Y+037340X0260Y         S2      
317m0281            VIA   -    MD0100PA00X+014900Y+038307X0200Y         S0      
327m0281            U22   -14         A12X+016016Y+036850X0110Y0260     S2      
327m0282            U22   -15         A12X+016213Y+036850X0110Y0260     S2      
317m0282            VIA   -    MD0100PA00X+015450Y+038735X0200Y         S0      
317m0282            VIA   -    M      A01X+024000Y+006740X0200Y         S2      
017m0282            VIA   -    M      A12X+024000Y+006740X0260Y         S2      
017m0282                  -    MD0100PA00X+024000Y+006740                       
327m0282            U36   -2          A12X+024500Y+007946X0160Y0240R180 S2      
327m0282            R274  -2   M      A12X+024202Y+007190X0198Y0197     S2      
327m0283            VIA   -    M      A12X+003750Y+011650X0260Y         S2      
327m0283            U37   -5          A12X+006166Y+026530X0140Y0590     S2      
317m0283            VIA   -    MD0100PA00X+003189Y+011040X0200Y         S0      
317m0283            VIA   -    MD0100PA00X+018770Y+009900X0200Y         S0      
327m0283            R670  -2          A12X+018547Y+009652X0198Y0197R270 S2      
327m0284            R693  -1   M      A12X+017300Y+007808X0198Y0197R090 S2      
327m0284            VIA   -    M      A12X+022380Y+005070X0260Y         S2      
317m0284            VIA   -    MD0100PA00X+017630Y+009870X0200Y         S0      
327m0284            U23   -2   M      A12X+017836Y+008371X0220Y0320R270 S2      
327m0284            U36   -1          A12X+024795Y+007946X0240Y0240R270 S2      
327m0284            U29   -1   M      A12X+023345Y+007946X0240Y0240R270 S2      
327m0284            Q6    -G   M      A12X+023499Y+005761X0320Y0360     S2      
317m0284            VIA   -    MD0100PA00X+015170Y+035790X0200Y         S0      
327m0284            U22   -9          A12X+015622Y+035984X0110Y0260     S2      
327BMC_PWR_LED      R316  -1          A01X+013708Y+020150X0198Y0197R180 S1      
317BMC_PWR_LED      VIA   -    M      A01X+014374Y+020340X0200Y         S2      
017BMC_PWR_LED      VIA   -    M      A12X+014374Y+020340X0260Y         S2      
017BMC_PWR_LED            -    MD0100PA00X+014374Y+020340                       
327BMC_PWR_LED      U5    -W23        A01X+018620Y+021170X0160Y    R180 S1      
317BMC_PWR_LED      VIA   -    MD0100PA00X+018779Y+021010X0180Y         S0      
327m0285            R531  -1          A01X+005008Y+036800X0198Y0197R180 S1      
317m0285            VIA   -    MD0100PA00X+005248Y+036400X0200Y         S0      
317m0285            VIA   -    MD0100PA00X+006561Y+035902X0180Y         S2      
327m0285            U25   -F14        A01X+006716Y+036058X0160Y    R180 S1      
327m0286            U5    -AA11       A01X+022400Y+021800X0160Y    R180 S1      
317m0286            VIA   -    MD0100PA00X+022555Y+021955X0180Y    R270 S0      
317m0286            VIA   -    MD0100PA00X+024269Y+025530X0200Y         S0      
327m0286            R469  -1          A12X+024269Y+025770X0198Y0197R270 S2      
327m0287            R531  -2          A01X+004692Y+036800X0198Y0197R180 S1      
327m0287            R595  -2          A01X+004692Y+036400X0198Y0197R180 S1      
327m0288            R526  -1          A01X+005008Y+034800X0198Y0197R180 S1      
327m0288            U25   -F15        A01X+006401Y+036058X0160Y    R180 S1      
327m0289            R468  -1          A01X+025832Y+025990X0198Y0197     S1      
327m0289            U5    -AB11       A01X+022400Y+022115X0160Y    R180 S1      
317m0289            VIA   -    MD0100PA00X+025570Y+026000X0200Y         S0      
317m0289            VIA   -    MD0100PA00X+022244Y+022270X0180Y    R270 S2      
327m0290            R593  -2          A01X+004750Y+035192X0198Y0197R270 S1      
327m0290            R526  -2          A01X+004692Y+034800X0198Y0197R180 S1      
327m0291            U5    -AD14       A01X+021455Y+022745X0160Y    R180 S1      
317m0291            VIA   -    MD0100PA00X+021299Y+022900X0180Y    R180 S2      
317m0291            VIA   -    MD0100PA00X+018740Y+025570X0200Y         S0      
327m0291            R461  -2          A01X+018755Y+025966X0198Y0197R270 S1      
327m0292            R460  -2          A01X+027325Y+027242X0198Y0197R270 S1      
327m0292            U5    -AC10       A01X+022715Y+022430X0160Y    R180 S1      
317m0292            VIA   -    MD0100PA00X+026660Y+026870X0200Y         S0      
317m0292            VIA   -    MD0100PA00X+022723Y+027054X0200Y         S0      
317m0292            VIA   -    MD0100PA00X+022559Y+022585X0180Y         S2      
327m0293            R458  -1          A12X+023125Y+024738X0198Y0197R270 S2      
327m0293            U5    -AD11       A01X+022400Y+022745X0160Y    R180 S1      
327m0293            VIA   -    M      A12X+022782Y+023390X0260Y         S2      
317m0293            VIA   -    MD0100PA00X+022555Y+022900X0180Y    R180 S0      
327m0294            R579  -2          A01X+009250Y+040292X0198Y0197R270 S1      
327m0294            U25   -R5         A01X+009551Y+038892X0160Y    R180 S1      
327m0295            R578  -2          A01X+010850Y+040292X0198Y0197R270 S1      
327m0295            U25   -R3         A01X+010181Y+038892X0160Y    R180 S1      
327m0296            R643  -2          A01X+025613Y+025010X0198Y0197R270 S1      
317m0296            VIA   -    MD0100PA00X+025264Y+024788X0200Y         S0      
317m0296            VIA   -    MD0100PA00X+022874Y+021644X0180Y         S0      
327m0296            U5    -AA9        A01X+023030Y+021800X0160Y    R180 S1      
327m0297            R747  -1          A01X+008450Y+040608X0198Y0197R270 S1      
317m0297            VIA   -    MD0100PA00X+011220Y+023452X0200Y         S0      
327m0297            R749  -2          A12X+008250Y+040308X0198Y0197R270 S2      
317m0297            VIA   -    MD0100PA00X+008480Y+040976X0200Y         S0      
317m0297            VIA   -    MD0100PA00X+013430Y+041641X0200Y         S0      
317m0297            VIA   -    MD0100PA00X+009584Y+042476X0200Y         S0      
317m0297            VIA   -    MD0100PA00X+011470Y+034850X0200Y         S0      
327m0297            VIA   -    M      A12X+014759Y+011981X0260Y         S2      
317m0297            VIA   -    MD0100PA00X+014760Y+011700X0200Y         S0      
327m0297            R760  -1          A12X+016062Y+014700X0198Y0197R180 S2      
327m0298            R577  -2          A01X+011250Y+040292X0198Y0197R270 S1      
327m0298            U25   -T2         A01X+010496Y+039208X0160Y    R180 S1      
327m0299            R489  -2          A12X+017730Y+021672X0198Y0197R090 S2      
327m0299            U5    -AA26       A01X+017675Y+021800X0160Y    R180 S1      
317m0299            VIA   -    MD0100PA00X+017460Y+021780X0180Y         S0      
327m0300            R575  -2          A12X+009850Y+039992X0198Y0197R090 S2      
327m0300            VIA   -    M      A12X+009850Y+039480X0260Y         S2      
317m0300            VIA   -    MD0100PA00X+010022Y+038733X0180Y         S0      
327m0300            U25   -P4         A01X+009866Y+038578X0160Y    R180 S1      
327m0301            R479  -2          A01X+015602Y+024275X0198Y0197     S1      
327m0301            U5    -AC26       A01X+017675Y+022430X0160Y    R180 S1      
327m0302            R575  -1   M      A12X+009850Y+040308X0198Y0197R090 S2      
317m0302            VIA   -    MD0100PA00X+017922Y+027853X0200Y         S0      
317m0302            VIA   -    MD0100PA00X+009830Y+040760X0200Y         S0      
327m0302            R621  -2          A12X+009450Y+040308X0198Y0197R270 S2      
327m0302            R479  -1          A01X+015286Y+024275X0198Y0197     S1      
327m0303            R519  -1          A12X+011759Y+036262X0198Y0197     S2      
327m0303            R629  -1          A12X+025300Y+007508X0198Y0197R090 S2      
317m0303            VIA   -    MD0100PA00X+008030Y+024370X0200Y         S0      
327m0303            R586  -2   M      A12X+011758Y+035850X0198Y0197R180 S2      
317m0303            VIA   -    M      A01X+015671Y+007342X0200Y         S2      
017m0303            VIA   -    M      A12X+015671Y+007342X0260Y         S2      
017m0303                  -    MD0100PA00X+015671Y+007342                       
317m0303            VIA   -    MD0100PA00X+012020Y+036160X0200Y         S0      
317m0303            VIA   -    MD0100PA00X+025300Y+007750X0200Y         S0      
327m0303            R65   -2          A01X+014150Y+024158X0198Y0197R090 S1      
317m0303            VIA   -    M      A01X+012120Y+023489X0300Y         S1      
017m0303            VIA   -    M      A12X+012120Y+023489X0200Y         S1      
017m0303                  -    MD0100PA00X+012120Y+023489                       
317m0304            VIA   -    MD0100PA00X+018620Y+012560X0200Y         S0      
327m0304            R60   -1          A01X+018380Y+012308X0198Y0197R270 S1      
317m0304            VIA   -    MD0100PA00X+018779Y+017235X0180Y         S2      
327m0304            U5    -G22        A01X+018935Y+017390X0160Y    R180 S1      
327m0305            R574  -2          A01X+006300Y+040292X0198Y0197R270 S1      
327m0305            U25   -R16        A01X+006086Y+038892X0160Y    R180 S1      
327m0306            R537  -1          A01X+005008Y+037600X0198Y0197R180 S1      
327m0306            U25   -H15        A01X+006401Y+036688X0160Y    R180 S1      
327m0307            R466  -1          A01X+022230Y+027902X0198Y0197R090 S1      
317m0307            VIA   -    MD0100PA00X+022650Y+027300X0200Y         S0      
327m0307            U5    -E16        A01X+020825Y+016760X0160Y    R180 S1      
317m0307            VIA   -    MD0100PA00X+020669Y+016605X0180Y         S0      
327m0308            R537  -2          A01X+004692Y+037600X0198Y0197R180 S1      
327m0308            R608  -2          A12X+004692Y+037600X0198Y0197     S2      
317m0308            VIA   -    MD0100PA00X+004452Y+037600X0200Y         S0      
327m0309            R536  -1          A01X+005008Y+037200X0198Y0197R180 S1      
327m0309            U25   -G16        A01X+006086Y+036373X0160Y    R180 S1      
327m0310            R465  -1          A01X+022520Y+025893X0198Y0197R180 S1      
327m0310            U5    -AE11       A01X+022400Y+023060X0160Y    R180 S1      
327m0311            R536  -2          A01X+004692Y+037200X0198Y0197R180 S1      
317m0311            VIA   -    M      A01X+003620Y+036840X0200Y         S2      
017m0311            VIA   -    M      A12X+003620Y+036840X0260Y         S2      
017m0311                  -    MD0100PA00X+003620Y+036840                       
327m0311            R607  -2          A12X+004098Y+037102X0198Y0197R090 S2      
327BJT_Q3_C         R289  -2          A01X+019375Y+037958X0198Y0197R090 S1      
327BJT_Q3_C         Q3    -C          A01X+020375Y+036990X0400Y0500     S1      
327BJT_Q3_C         Q1    -B   M      A01X+019960Y+037815X0400Y0500     S1      
327BJT_Q3_B         R290  -1          A01X+019375Y+036068X0198Y0197R090 S1      
327BJT_Q3_B         Q3    -B          A01X+019975Y+036110X0400Y0500     S1      
327FM_ESPI_PLD_EN   R833  -1          A12X+004692Y+034800X0198Y0197R180 S2      
327FM_ESPI_PLD_EN   VIA   -    M      A12X+012890Y+018370X0260Y         S2      
317FM_ESPI_PLD_EN   VIA   -    MD0100PA00X+012570Y+018370X0200Y         S0      
327FM_ESPI_PLD_EN   R444  -1          A12X+016362Y+017320X0198Y0197R180 S2      
317FM_ESPI_PLD_EN   VIA   -    MD0100PA00X+006405Y+020101X0200Y         S0      
317FM_ESPI_PLD_EN   VIA   -    MD0100PA00X+004450Y+034800X0200Y         S0      
327I3C1_SDA_R       R185  -2          A01X+016097Y+024944X0198Y0197R270 S1      
327I3C1_SDA_R       U5    -AE24       A01X+018305Y+023060X0160Y    R180 S1      
327I3C1_SCL_R       R184  -2          A01X+016480Y+025739X0198Y0197R270 S1      
327I3C1_SCL_R       U5    -AF23       A01X+018620Y+023374X0160Y    R180 S1      
327P3V3_AUX_REF     PC273 -1          A01X+004133Y+025964X0198Y0197     S1      
317P3V3_AUX_REF     VIA   -    M      A01X+003748Y+025881X0200Y    R090 S2      
017P3V3_AUX_REF     VIA   -    M      A12X+003748Y+025881X0260Y    R090 S2      
017P3V3_AUX_REF           -    MD0100PA00X+003748Y+025881                       
327P3V3_AUX_REF     PU1   -8          A01X+003464Y+025881X0098Y0276R180 S1      
327P3V3_AUX_MODE    PR532 -2          A01X+002130Y+025978X0198Y0197     S1      
317P3V3_AUX_MODE    VIA   -    M      A01X+002470Y+025877X0200Y         S2      
017P3V3_AUX_MODE    VIA   -    M      A12X+002470Y+025877X0260Y         S2      
017P3V3_AUX_MODE          -    MD0100PA00X+002470Y+025877                       
327P3V3_AUX_MODE    PU1   -12         A01X+002677Y+025881X0098Y0276R180 S1      
327P3V3_AUX_CS      PR276 -2          A01X+003642Y+024612X0198Y0197R180 S1      
327P3V3_AUX_CS      PU1   -4          A01X+003267Y+025172X0100Y0360R180 S1      
327PVCC2_AUX        PR205 -2          A01X+009970Y+012218X0198Y0197R090 S1      
327PVCC2_AUX        PR193 -2   M      A01X+009580Y+012218X0198Y0197R090 S1      
327PVCC2_AUX        VIA   -    M      A01X+009450Y+012700X0300Y    R180 S1      
327PVCC2_AUX        PR541 -1          A01X+009192Y+012217X0198Y0197R270 S1      
327PVCC1_AUX        PR275 -2          A01X+033760Y+027582X0198Y0197R270 S1      
327PVCC1_AUX        PR274 -2          A01X+032982Y+027582X0198Y0197R270 S1      
327PVCC1_AUX        PR539 -1   M      A01X+033384Y+027582X0198Y0197R090 S1      
327m0312            U25   -D14        A01X+006716Y+035428X0160Y    R180 S1      
317m0312            VIA   -    MD0100PA00X+006561Y+035272X0180Y         S2      
327m0312            U5    -AB23       A01X+018620Y+022115X0160Y    R180 S1      
317m0312            VIA   -    MD0100PA00X+018464Y+022270X0180Y         S0      
327m0313            VIA   -    M      A01X+016480Y+019800X0300Y         S1      
327m0313            U25   -A15        A01X+006401Y+034483X0160Y    R180 S1      
317m0313            VIA   -    MD0100PA00X+006246Y+034328X0180Y         S0      
327m0313            R400  -2          A01X+015738Y+019570X0198Y0197     S1      
327m0313            U5    -T26        A01X+017675Y+020225X0160Y    R180 S1      
317m0313            VIA   -    MD0100PA00X+017520Y+020380X0180Y         S0      
327FM_PWR_BTN       R432  -2          A12X+004692Y+038000X0198Y0197     S2      
327FM_PWR_BTN       R225  -1          A12X+016661Y+023848X0198Y0197     S2      
317FM_PWR_BTN       VIA   -    MD0100PA00X+003730Y+037500X0200Y         S0      
327FM_PWR_BTN       U5    -AB22       A01X+018935Y+022115X0160Y    R180 S1      
327FM_PWR_BTN       VIA   -    M      A12X+017614Y+023286X0260Y         S2      
317FM_PWR_BTN       VIA   -    MD0100PA00X+007301Y+024636X0200Y         S0      
317FM_PWR_BTN       VIA   -    MD0100PA00X+018779Y+022270X0180Y    R180 S0      
327FM_PCHHOT_R_N    U25   -K11        A01X+007661Y+037318X0160Y    R180 S1      
317FM_PCHHOT_R_N    VIA   -    MD0100PA00X+007506Y+037473X0180Y         S0      
327FM_PCHHOT_R_N    U5    -AD16       A01X+020825Y+022745X0160Y    R180 S1      
317FM_PCHHOT_R_N    VIA   -    MD0100PA00X+020669Y+022900X0180Y         S2      
317m0314            VIA   -    MD0100PA00X+011187Y+036545X0200Y         S0      
317m0314            VIA   -    MD0100PA00X+009077Y+035902X0180Y         S0      
327m0314            U25   -F7         A01X+008921Y+036058X0160Y    R180 S1      
317m0314            VIA   -    MD0100PA00X+015810Y+044270X0200Y         S0      
327m0314            U5    -AD23       A01X+018620Y+022745X0160Y    R180 S1      
317m0314            VIA   -    MD0100PA00X+018464Y+022900X0180Y    R180 S2      
317m0315            VIA   -    M      A01X+012233Y+036467X0200Y         S2      
017m0315            VIA   -    M      A12X+012233Y+036467X0260Y         S2      
017m0315                  -    MD0100PA00X+012233Y+036467                       
327m0315            U25   -J16        A01X+006086Y+037003X0160Y    R180 S1      
317m0315            VIA   -    MD0100PA00X+017520Y+022900X0180Y         S0      
327m0315            U5    -AD26       A01X+017675Y+022745X0160Y    R180 S1      
317m0316            VIA   -    MD0100PA00X+005856Y+035428X0180Y         S2      
327m0316            U25   -D16        A01X+006086Y+035428X0160Y    R180 S1      
327m0316            U5    -AB24       A01X+018305Y+022115X0160Y    R180 S1      
317m0316            VIA   -    MD0100PA00X+018150Y+022270X0180Y         S0      
317m0317            VIA   -    MD0100PA00X+006246Y+035587X0180Y         S2      
327m0317            U25   -E15        A01X+006401Y+035743X0160Y    R180 S1      
317m0317            VIA   -    MD0100PA00X+018464Y+022585X0180Y    R180 S0      
327m0317            U5    -AC23       A01X+018620Y+022430X0160Y    R180 S1      
327m0318            U25   -A12        A01X+007346Y+034483X0160Y    R180 S1      
317m0318            VIA   -    M      A01X+007170Y+034060X0200Y         S2      
017m0318            VIA   -    M      A12X+007170Y+034060X0260Y         S2      
017m0318                  -    MD0100PA00X+007170Y+034060                       
317m0318            VIA   -    MD0100PA00X+018150Y+022585X0180Y         S0      
327m0318            U5    -AC24       A01X+018305Y+022430X0160Y    R180 S1      
327m0319            R835  -2          A12X+005978Y+037630X0198Y0197R180 S2      
327m0319            U5    -AD25       A01X+017990Y+022745X0160Y    R180 S1      
317m0319            VIA   -    MD0100PA00X+017750Y+036910X0200Y         S0      
317m0319            VIA   -    MD0100PA00X+017835Y+022900X0180Y         S2      
317m0319            VIA   -    MD0100PA00X+006876Y+037158X0180Y         S0      
327m0319            U25   -J13        A01X+007031Y+037003X0160Y    R180 S1      
327m0320            R565  -1          A01X+014560Y+023848X0198Y0197R270 S1      
327m0320            U5    -AA23       A01X+018620Y+021800X0160Y    R180 S1      
317m0320            VIA   -    MD0100PA00X+016720Y+022260X0200Y         S0      
317m0320            VIA   -    MD0100PA00X+018464Y+021955X0180Y         S2      
327TP_U14_FLAG_N    U14   -3          A01X+026359Y+012752X0220Y0320R180 S1      
327m0321            U5    -A15        A01X+021140Y+015500X0160Y    R180 S1      
317m0321            VIA   -    MD0100PA00X+020984Y+015345X0180Y         S0      
327m0321            R826  -1          A12X+021080Y+013794X0198Y0197R090 S2      
327m0322            VIA   -    M      A01X+020267Y+040460X0300Y         S1      
317m0322            VIA   -    MD0100PA00X+019988Y+040285X0200Y    R090 S0      
327m0322            U21   -2          A12X+018430Y+040680X0140Y0590R090 S2      
327m0322            R862  -2          A01X+020672Y+041960X0198Y0197R180 S1      
317m0323            VIA   -    MD0100PA00X+021320Y+039917X0200Y         S0      
327m0323            R860  -2          A01X+021570Y+042912X0198Y0197R270 S1      
317m0323            VIA   -    MD0100PA00X+021418Y+033374X0200Y         S0      
327m0323            U30   -2          A12X+018118Y+030841X0140Y0590R270 S2      
327m0323            VIA   -    M      A12X+020244Y+033342X0260Y         S2      
327m0324            VIA   -    M      A01X+020830Y+039815X0300Y         S1      
327m0324            U21   -5          A12X+018430Y+039912X0140Y0590R090 S2      
317m0324            VIA   -    MD0100PA00X+020022Y+039815X0200Y         S0      
327m0324            R861  -2          A01X+021170Y+042912X0198Y0197R270 S1      
327m0325            VIA   -    M      A12X+018718Y+032959X0260Y         S2      
327m0325            U30   -5          A12X+018118Y+031608X0140Y0590R270 S2      
327m0325            R863  -2          A01X+020730Y+042912X0198Y0197R270 S1      
317m0325            VIA   -    MD0100PA00X+021640Y+033597X0200Y         S0      
317m0325            VIA   -    MD0100PA00X+020728Y+041602X0200Y         S0      
327m0326            U30   -11         A12X+020418Y+031864X0140Y0590R270 S2      
327m0326            R859  -2          A01X+022650Y+040372X0198Y0197R270 S1      
317m0326            VIA   -    MD0100PA00X+022299Y+040032X0200Y         S0      
317m0326            VIA   -    MD0100PA00X+021730Y+032280X0200Y         S0      
327m0326            VIA   -    M      A12X+021093Y+031864X0260Y         S2      
317m0327            VIA   -    MD0100PA00X+010651Y+034957X0180Y         S0      
317m0327            VIA   -    MD0100PA00X+008762Y+035587X0180Y         S0      
327m0327            U25   -E8         A01X+008606Y+035743X0160Y    R180 S1      
327m0327            U5    -U26        A01X+017675Y+020540X0160Y    R180 S1      
317m0327            VIA   -    MD0100PA00X+017520Y+020696X0180Y         S2      
317m0328            VIA   -    M      A01X+012310Y+029597X0200Y         S2      
017m0328            VIA   -    M      A12X+012310Y+029597X0260Y         S2      
017m0328                  -    MD0100PA00X+012310Y+029597                       
327m0328            U5    -W26        A01X+017675Y+021170X0160Y    R180 S1      
317m0328            VIA   -    MD0100PA00X+017520Y+021325X0180Y         S0      
317m0328            VIA   -    MD0100PA00X+007506Y+034957X0180Y         S0      
327m0328            U25   -C11        A01X+007661Y+035113X0160Y    R180 S1      
317m0329            VIA   -    MD0100PA00X+010652Y+035272X0180Y         S0      
317m0329            VIA   -    MD0100PA00X+009077Y+035587X0180Y         S0      
327m0329            U25   -E7         A01X+008921Y+035743X0160Y    R180 S1      
327m0329            U5    -T23        A01X+018620Y+020225X0160Y    R180 S1      
317m0329            VIA   -    MD0100PA00X+018464Y+020380X0180Y         S0      
317m0330            VIA   -    MD0100PA00X+007506Y+035272X0180Y         S0      
327m0330            U25   -D11        A01X+007661Y+035428X0160Y    R180 S1      
327m0330            U5    -U25        A01X+017990Y+020540X0160Y    R180 S1      
317m0330            VIA   -    MD0100PA00X+017835Y+020696X0180Y    R180 S0      
317m0331            VIA   -    M      A01X+012296Y+030099X0200Y         S2      
017m0331            VIA   -    M      A12X+012296Y+030099X0260Y         S2      
017m0331                  -    MD0100PA00X+012296Y+030099                       
317m0331            VIA   -    MD0100PA00X+007821Y+035902X0180Y         S2      
327m0331            U25   -F10        A01X+007976Y+036058X0160Y    R180 S1      
327m0331            U5    -V26        A01X+017675Y+020855X0160Y    R180 S1      
317m0331            VIA   -    MD0100PA00X+017520Y+021010X0180Y         S0      
317m0332            VIA   -    MD0100PA00X+006876Y+034642X0180Y         S2      
327m0332            U25   -B13        A01X+007031Y+034798X0160Y    R180 S1      
327m0332            U5    -V24        A01X+018305Y+020855X0160Y    R180 S1      
317m0332            VIA   -    MD0100PA00X+018150Y+020696X0180Y         S0      
317m0333            VIA   -    MD0100PA00X+008190Y+033710X0200Y         S0      
327m0333            U25   -B7         A01X+008921Y+034798X0160Y    R180 S1      
327m0333            U5    -U24        A01X+018305Y+020540X0160Y    R180 S1      
317m0333            VIA   -    MD0100PA00X+018150Y+020380X0180Y         S2      
317m0334            VIA   -    MD0100PA00X+007506Y+034642X0180Y         S2      
327m0334            U25   -B11        A01X+007661Y+034798X0160Y    R180 S1      
327m0334            U5    -V25        A01X+017990Y+020855X0160Y    R180 S1      
317m0334            VIA   -    MD0100PA00X+017835Y+021010X0180Y    R180 S0      
327m0335            R456  -1          A12X+004692Y+034400X0198Y0197R180 S2      
317m0335            VIA   -    M      A01X+018855Y+032636X0300Y    R180 S1      
017m0335            VIA   -    M      A12X+018855Y+032636X0200Y    R180 S1      
017m0335                  -    MD0100PA00X+018855Y+032636                       
317m0335            VIA   -    MD0100PA00X+004450Y+034400X0200Y         S0      
327m0335            R842  -2          A12X+019026Y+026700X0198Y0197R180 S2      
327m0335            R448  -1          A12X+019250Y+025333X0198Y0197R090 S2      
317m0335            VIA   -    MD0100PA00X+019457Y+025529X0200Y         S0      
327m0336            R574  -1          A01X+006300Y+040608X0198Y0197R270 S1      
327m0336            R54   -2          A12X+008250Y+007208X0198Y0197R270 S2      
317m0336            VIA   -    MD0100PA00X+006320Y+040860X0200Y         S0      
317m0336            VIA   -    MD0100PA00X+012260Y+039460X0200Y         S0      
327m0336            R848  -2          A12X+019069Y+024298X0198Y0197R090 S2      
327m0336            U5    -AC17       A01X+020510Y+022430X0160Y    R180 S1      
317m0336            VIA   -    MD0100PA00X+020354Y+022585X0180Y         S2      
317m0336            VIA   -    MD0100PA00X+014750Y+028940X0200Y         S0      
317m0336            VIA   -    MD0100PA00X+030070Y+034130X0200Y         S0      
317m0336            VIA   -    MD0100PA00X+028350Y+008950X0200Y         S0      
317m0336            VIA   -    MD0100PA00X+010460Y+005050X0200Y         S0      
317m0336            VIA   -    MD0100PA00X+008450Y+006650X0200Y         S0      
317m0337            VIA   -    MD0100PA00X+007191Y+037788X0180Y         S0      
327m0337            U25   -L12        A01X+007346Y+037633X0160Y    R180 S1      
327m0337            R846  -2          A12X+019473Y+024298X0198Y0197R090 S2      
317m0337            VIA   -    MD0100PA00X+019169Y+023637X0200Y         S0      
327m0337            U5    -AA16       A01X+020825Y+021800X0160Y    R180 S1      
317m0337            VIA   -    MD0100PA00X+020669Y+021955X0180Y         S0      
327m0338            U25   -L14        A01X+006716Y+037633X0160Y    R180 S1      
317m0338            VIA   -    MD0100PA00X+006561Y+038103X0180Y         S0      
327m0338            VIA   -    M      A12X+020761Y+024291X0260Y         S2      
327m0338            U5    -AE16       A01X+020825Y+023060X0160Y    R180 S1      
317m0338            VIA   -    MD0100PA00X+020669Y+023215X0180Y         S0      
327m0338            R844  -2          A12X+020046Y+025018X0198Y0197R090 S2      
327m0339            R457  -1          A12X+004692Y+037200X0198Y0197R180 S2      
317m0339            VIA   -    M      A01X+018740Y+037940X0200Y         S2      
017m0339            VIA   -    M      A12X+018740Y+037940X0260Y         S2      
017m0339                  -    MD0100PA00X+018740Y+037940                       
317m0339            VIA   -    MD0100PA00X+004452Y+036800X0200Y         S0      
327m0339            R843  -2          A12X+018707Y+025934X0198Y0197R090 S2      
327m0339            R449  -1   M      A12X+018850Y+025332X0198Y0197R090 S2      
317m0339            VIA   -    MD0100PA00X+015090Y+036032X0200Y         S0      
317m0339            VIA   -    MD0100PA00X+019308Y+025740X0200Y         S0      
327m0340            R841  -1          A01X+005008Y+038400X0198Y0197R180 S1      
327m0340            U25   -K15        A01X+006401Y+037318X0160Y    R180 S1      
327m0341            U5    -B12        A01X+022085Y+015816X0160Y    R180 S1      
317m0341            VIA   -    MD0100PA00X+022240Y+015660X0180Y    R180 S0      
317m0341            VIA   -    MD0100PA00X+022530Y+012520X0200Y         S0      
327m0341            R840  -2          A01X+022330Y+012308X0198Y0197R090 S1      
327m0342            R837  -2          A12X+010602Y+033770X0198Y0197     S2      
327m0342            VIA   -    M      A12X+009838Y+034152X0260Y         S2      
317m0342            VIA   -    MD0100PA00X+009707Y+034957X0180Y         S0      
327m0342            U25   -C5         A01X+009551Y+035113X0160Y    R180 S1      
327m0343            R836  -2          A01X+022860Y+012308X0198Y0197R090 S1      
327m0343            U5    -A12        A01X+022085Y+015500X0160Y    R180 S1      
327m0344            R833  -2          A12X+005008Y+034800X0198Y0197R180 S2      
327m0344            VIA   -    M      A12X+005450Y+035500X0260Y         S2      
317m0344            VIA   -    MD0100PA00X+006876Y+036532X0180Y         S0      
327m0344            U25   -H13        A01X+007031Y+036688X0160Y    R180 S1      
327m0345            R824  -2          A01X+026700Y+041682X0198Y0197R270 S1      
317m0345            VIA   -    MD0100PA00X+027666Y+031690X0200Y         S0      
317m0345            VIA   -    MD0100PA00X+024764Y+022585X0180Y    R090 S0      
327m0345            U5    -B13        A01X+021770Y+015816X0160Y    R180 S1      
317m0345            VIA   -    MD0100PA00X+021925Y+015660X0180Y         S0      
317m0345            VIA   -    M      A01X+027150Y+041830X0200Y         S2      
017m0345            VIA   -    M      A12X+027150Y+041830X0260Y         S2      
017m0345                  -    MD0100PA00X+027150Y+041830                       
327m0346            R825  -2          A12X+005008Y+036800X0198Y0197R180 S2      
317m0346            VIA   -    MD0100PA00X+007191Y+036532X0180Y         S2      
327m0346            U25   -H12        A01X+007346Y+036688X0160Y    R180 S1      
327RST_ROT_CPU_N    R748  -2          A01X+011880Y+035728X0198Y0197R090 S1      
327RST_ROT_CPU_N    R825  -1          A12X+004692Y+036800X0198Y0197R180 S2      
327RST_ROT_CPU_N    R60   -2          A01X+018380Y+011992X0198Y0197R270 S1      
327RST_ROT_CPU_N    VIA   -    M      A12X+008950Y+043200X0260Y         S2      
317RST_ROT_CPU_N    VIA   -    MD0100PA00X+015342Y+034198X0200Y         S0      
317RST_ROT_CPU_N    VIA   -    MD0100PA00X+004452Y+036400X0200Y         S0      
317RST_ROT_CPU_N    VIA   -    MD0100PA00X+008780Y+041030X0200Y         S0      
327RST_ROT_CPU_N    R828  -2   M      A12X+008880Y+042088X0198Y0197R270 S2      
327RST_ROT_CPU_N    GF1   -A53        A12X+009663Y+046559X0150Y0680R180 S2      
317RST_ROT_CPU_N    VIA   -    MD0100PA00X+012435Y+035245X0200Y    R090 S0      
317RST_ROT_CPU_N    VIA   -    MD0100PA00X+013600Y+034100X0200Y         S0      
317RST_ROT_CPU_N    VIA   -    MD0100PA00X+018473Y+011582X0200Y         S0      
327m0347            R824  -1          A01X+026700Y+041998X0198Y0197R270 S1      
327m0347            GF1   -OA14       A12X+026716Y+046638X0150Y0840R180 S2      
327m0347            VIA   -    M      A01X+026140Y+043310X0300Y         S1      
327m0347            R823  -2   M      A01X+026800Y+042688X0198Y0197R090 S1      
317m0347            VIA   -    MD0100PA00X+026513Y+044007X0200Y         S0      
317FM_PRSNT_1_N     VIA   -    MD0100PA00X+007280Y+043790X0200Y         S0      
317FM_PRSNT_1_N     VIA   -    M      A01X+028130Y+041620X0200Y         S2      
017FM_PRSNT_1_N     VIA   -    M      A12X+028130Y+041620X0260Y         S2      
017FM_PRSNT_1_N           -    MD0100PA00X+028130Y+041620                       
327FM_PRSNT_1_N     R822  -1          A01X+028410Y+041672X0198Y0197R090 S1      
327FM_PRSNT_1_N     GF1   -A57        A12X+008718Y+046559X0150Y0680R180 S2      
327FM_PRSNT_0_R_N   VIA   -    M      A01X+028550Y+042610X0300Y         S1      
327FM_PRSNT_0_R_N   GF1   -OB3        A01X+029315Y+046638X0150Y0840R180 S1      
327FM_PRSNT_0_R_N   R822  -2          A01X+028410Y+041988X0198Y0197R090 S1      
317GND_P1           VIA   -    MD0100PA00X+040386Y+040934X0200Y    R270 S0      
317GND_P1           VIA   -    MD0100PA00X+040495Y+041238X0200Y    R270 S0      
317GND_P1           VIA   -    MD0100PA00X+040245Y+041238X0200Y    R270 S0      
317GND_P1           VIA   -    MD0100PA00X+040495Y+041563X0200Y    R270 S0      
317GND_P1           VIA   -    MD0100PA00X+040245Y+041563X0200Y    R270 S0      
317GND_P1           VIA   -    MD0100PA00X+040364Y-006775X0200Y    R090 S0      
317GND_P1           VIA   -    MD0100PA00X+040255Y-007079X0200Y    R090 S0      
317GND_P1           VIA   -    MD0100PA00X+040505Y-007079X0200Y    R090 S0      
317GND_P1           VIA   -    MD0100PA00X+040255Y-007404X0200Y    R090 S0      
317GND_P1           VIA   -    MD0100PA00X+040505Y-007404X0200Y    R090 S0      
317GND_P1           VIA   -    MD0100PA00X+040386Y+021107X0200Y    R270 S0      
317GND_P1           VIA   -    MD0100PA00X+040495Y+021411X0200Y    R270 S0      
317GND_P1           VIA   -    MD0100PA00X+040245Y+021411X0200Y    R270 S0      
317GND_P1           VIA   -    MD0100PA00X+040495Y+021736X0200Y    R270 S0      
317GND_P1           VIA   -    MD0100PA00X+040245Y+021736X0200Y    R270 S0      
317GND_P1           VIA   -    MD0100PA00X+040364Y+026152X0200Y    R090 S0      
317GND_P1           VIA   -    MD0100PA00X+040255Y+025848X0200Y    R090 S0      
317GND_P1           VIA   -    MD0100PA00X+040505Y+025848X0200Y    R090 S0      
317GND_P1           VIA   -    MD0100PA00X+040255Y+025523X0200Y    R090 S0      
317GND_P1           VIA   -    MD0100PA00X+040505Y+025523X0200Y    R090 S0      
317GND_P1           VIA   -    MD0100PA00X+041414Y+026152X0200Y    R090 S0      
317GND_P1           VIA   -    MD0100PA00X+040805Y+025524X0200Y    R090 S0      
317GND_P1           VIA   -    MD0100PA00X+041055Y+025523X0200Y    R090 S0      
317GND_P1           VIA   -    MD0100PA00X+041305Y+025848X0200Y    R090 S0      
317GND_P1           VIA   -    MD0100PA00X+041305Y+025523X0200Y    R090 S0      
317GND_P1           VIA   -    MD0100PA00X+041555Y+025523X0200Y    R090 S0      
327GND_P1           J20   -3   M      A12X+040875Y+025840X0850Y1560R270 S2      
317GND_P1           VIA   -    MD0100PA00X+041555Y+025848X0200Y    R090 S0      
317GND_P1           VIA   -    MD0100PA00X+039336Y+026152X0200Y    R090 S0      
317GND_P1           VIA   -    MD0100PA00X+039945Y+025524X0200Y    R090 S0      
317GND_P1           VIA   -    MD0100PA00X+039695Y+025523X0200Y    R090 S0      
317GND_P1           VIA   -    MD0100PA00X+039445Y+025848X0200Y    R090 S0      
317GND_P1           VIA   -    MD0100PA00X+039445Y+025523X0200Y    R090 S0      
317GND_P1           VIA   -    MD0100PA00X+039195Y+025523X0200Y    R090 S0      
327GND_P1           J9    -3   M      A01X+039875Y+025840X0850Y1560R090 S1      
317GND_P1           VIA   -    MD0100PA00X+039195Y+025848X0200Y    R090 S0      
317GND_P1           VIA   -    MD0100PA00X+039336Y+021107X0200Y    R270 S0      
317GND_P1           VIA   -    MD0100PA00X+039945Y+021734X0200Y    R270 S0      
317GND_P1           VIA   -    MD0100PA00X+039695Y+021736X0200Y    R270 S0      
317GND_P1           VIA   -    MD0100PA00X+039445Y+021411X0200Y    R270 S0      
317GND_P1           VIA   -    MD0100PA00X+039445Y+021736X0200Y    R270 S0      
317GND_P1           VIA   -    MD0100PA00X+039195Y+021736X0200Y    R270 S0      
327GND_P1           J24   -3   M      A12X+039875Y+021419X0850Y1560R090 S2      
317GND_P1           VIA   -    MD0100PA00X+039195Y+021411X0200Y    R270 S0      
317GND_P1           VIA   -    MD0100PA00X+039336Y+040934X0200Y    R270 S0      
317GND_P1           VIA   -    MD0100PA00X+039945Y+041562X0200Y    R270 S0      
317GND_P1           VIA   -    MD0100PA00X+039695Y+041563X0200Y    R270 S0      
317GND_P1           VIA   -    MD0100PA00X+039445Y+041238X0200Y    R270 S0      
317GND_P1           VIA   -    MD0100PA00X+039445Y+041563X0200Y    R270 S0      
317GND_P1           VIA   -    MD0100PA00X+039195Y+041563X0200Y    R270 S0      
327GND_P1           J12   -3   M      A01X+039875Y+041246X0850Y1560R270 S1      
317GND_P1           VIA   -    MD0100PA00X+039195Y+041238X0200Y    R270 S0      
317GND_P1           VIA   -    MD0100PA00X+041414Y+040934X0200Y    R270 S0      
317GND_P1           VIA   -    MD0100PA00X+040805Y+041562X0200Y    R270 S0      
317GND_P1           VIA   -    MD0100PA00X+041055Y+041563X0200Y    R270 S0      
317GND_P1           VIA   -    MD0100PA00X+041305Y+041238X0200Y    R270 S0      
317GND_P1           VIA   -    MD0100PA00X+041305Y+041563X0200Y    R270 S0      
317GND_P1           VIA   -    MD0100PA00X+041555Y+041563X0200Y    R270 S0      
327GND_P1           J17   -3   M      A12X+040875Y+041246X0850Y1560R090 S2      
317GND_P1           VIA   -    MD0100PA00X+041555Y+041238X0200Y    R270 S0      
317GND_P1           VIA   -    MD0100PA00X+041414Y+021107X0200Y    R270 S0      
317GND_P1           VIA   -    MD0100PA00X+040805Y+021734X0200Y    R270 S0      
317GND_P1           VIA   -    MD0100PA00X+041055Y+021736X0200Y    R270 S0      
317GND_P1           VIA   -    MD0100PA00X+041305Y+021411X0200Y    R270 S0      
317GND_P1           VIA   -    MD0100PA00X+041305Y+021736X0200Y    R270 S0      
317GND_P1           VIA   -    MD0100PA00X+041555Y+021736X0200Y    R270 S0      
327GND_P1           J22   -3   M      A01X+040875Y+021419X0850Y1560R270 S1      
317GND_P1           VIA   -    MD0100PA00X+041555Y+021411X0200Y    R270 S0      
317GND_P1           VIA   -    MD0100PA00X+041414Y-006775X0200Y    R090 S0      
317GND_P1           VIA   -    MD0100PA00X+040805Y-007403X0200Y    R090 S0      
317GND_P1           VIA   -    MD0100PA00X+041055Y-007404X0200Y    R090 S0      
317GND_P1           VIA   -    MD0100PA00X+041305Y-007079X0200Y    R090 S0      
317GND_P1           VIA   -    MD0100PA00X+041305Y-007404X0200Y    R090 S0      
317GND_P1           VIA   -    MD0100PA00X+041555Y-007404X0200Y    R090 S0      
327GND_P1           J25   -3   M      A01X+040875Y-007087X0850Y1560R090 S1      
317GND_P1           VIA   -    MD0100PA00X+041555Y-007079X0200Y    R090 S0      
317GND_P1           VIA   -    MD0100PA00X+039695Y-007404X0200Y    R090 S0      
317GND_P1           VIA   -    MD0100PA00X+039445Y-007079X0200Y    R090 S0      
317GND_P1           VIA   -    MD0100PA00X+039195Y-007079X0200Y    R090 S0      
317GND_P1           VIA   -    MD0100PA00X+039195Y-007404X0200Y    R090 S0      
317GND_P1           VIA   -    MD0100PA00X+039445Y-007404X0200Y    R090 S0      
317GND_P1           VIA   -    MD0100PA00X+039336Y-006775X0200Y    R090 S0      
317GND_P1           VIA   -    MD0100PA00X+039945Y-007403X0200Y    R090 S0      
327GND_P1           J27   -3   M      A12X+039875Y-007087X0850Y1560R270 S2      
317GND_P1           VIA   -    MD0100PA00X+040004Y-011203X0200Y    R270 S0      
317GND_P1           VIA   -    MD0100PA00X+040296Y-011528X0200Y    R270 S0      
317GND_P1           VIA   -    MD0100PA00X+040548Y-011528X0200Y    R270 S0      
317GND_P1           VIA   -    MD0100PA00X+040548Y-011203X0200Y    R270 S0      
317GND_P1           VIA   -    MD0100PA00X+040296Y-011203X0200Y    R270 S0      
317GND_P1           VIA   -    MD0100PA00X+040417Y-011832X0200Y    R270 S0      
317GND_P1           VIA   -    MD0100PA00X+039339Y-011832X0200Y    R270 S0      
317GND_P1           VIA   -    MD0100PA00X+039460Y-011203X0200Y    R270 S0      
317GND_P1           VIA   -    MD0100PA00X+039752Y-011205X0200Y    R270 S0      
317GND_P1           VIA   -    MD0100PA00X+039208Y-011203X0200Y    R270 S0      
317GND_P1           VIA   -    MD0100PA00X+039208Y-011528X0200Y    R270 S0      
327GND_P1           J28   -3   M      A12X+039878Y-011520X0850Y1560R090 S2      
317GND_P1           VIA   -    MD0100PA00X+039460Y-011528X0200Y    R270 S0      
317GND_P1           VIA   -    MD0100PA00X+039743Y-047320X0200Y    R090 S0      
317GND_P1           VIA   -    MD0100PA00X+039451Y-046994X0200Y    R090 S0      
317GND_P1           VIA   -    MD0100PA00X+039199Y-046994X0200Y    R090 S0      
317GND_P1           VIA   -    MD0100PA00X+039199Y-047320X0200Y    R090 S0      
317GND_P1           VIA   -    MD0100PA00X+039451Y-047320X0200Y    R090 S0      
317GND_P1           VIA   -    MD0100PA00X+039330Y-046690X0200Y    R090 S0      
317GND_P1           VIA   -    MD0100PA00X+040408Y-046690X0200Y    R090 S0      
317GND_P1           VIA   -    MD0100PA00X+040288Y-047320X0200Y    R090 S0      
317GND_P1           VIA   -    MD0100PA00X+039995Y-047318X0200Y    R090 S0      
317GND_P1           VIA   -    MD0100PA00X+040539Y-047320X0200Y    R090 S0      
317GND_P1           VIA   -    MD0100PA00X+040539Y-046994X0200Y    R090 S0      
327GND_P1           J30   -3   M      A12X+039869Y-047002X0850Y1560R270 S2      
317GND_P1           VIA   -    MD0100PA00X+040288Y-046994X0200Y    R090 S0      
317GND_P1           VIA   -    MD0100PA00X+037635Y-044713X0200Y    R090 S0      
317GND_P1           VIA   -    MD0100PA00X+037342Y-044388X0200Y    R090 S0      
317GND_P1           VIA   -    MD0100PA00X+037090Y-044388X0200Y    R090 S0      
317GND_P1           VIA   -    MD0100PA00X+037090Y-044713X0200Y    R090 S0      
317GND_P1           VIA   -    MD0100PA00X+037342Y-044713X0200Y    R090 S0      
317GND_P1           VIA   -    MD0100PA00X+037221Y-044084X0200Y    R090 S0      
317GND_P1           VIA   -    MD0100PA00X+038300Y-044084X0200Y    R090 S0      
317GND_P1           VIA   -    MD0100PA00X+038179Y-044713X0200Y    R090 S0      
317GND_P1           VIA   -    MD0100PA00X+037886Y-044712X0200Y    R090 S0      
317GND_P1           VIA   -    MD0100PA00X+038430Y-044713X0200Y    R090 S0      
317GND_P1           VIA   -    MD0100PA00X+038430Y-044388X0200Y    R090 S0      
327GND_P1           J29   -3   M      A12X+037760Y-044396X0850Y1560R270 S2      
317GND_P1           VIA   -    MD0100PA00X+038179Y-044388X0200Y    R090 S0      
317GND_P1           VIA   -    MD0100PA00X+037892Y-020697X0200Y    R270 S0      
317GND_P1           VIA   -    MD0100PA00X+038185Y-021022X0200Y    R270 S0      
317GND_P1           VIA   -    MD0100PA00X+038436Y-021022X0200Y    R270 S0      
317GND_P1           VIA   -    MD0100PA00X+038436Y-020697X0200Y    R270 S0      
317GND_P1           VIA   -    MD0100PA00X+038185Y-020697X0200Y    R270 S0      
317GND_P1           VIA   -    MD0100PA00X+038306Y-021326X0200Y    R270 S0      
317GND_P1           VIA   -    MD0100PA00X+037227Y-021326X0200Y    R270 S0      
317GND_P1           VIA   -    MD0100PA00X+037348Y-020697X0200Y    R270 S0      
317GND_P1           VIA   -    MD0100PA00X+037641Y-020698X0200Y    R270 S0      
317GND_P1           VIA   -    MD0100PA00X+037096Y-020697X0200Y    R270 S0      
317GND_P1           VIA   -    MD0100PA00X+037096Y-021022X0200Y    R270 S0      
327GND_P1           J11   -3   M      A12X+037766Y-021014X0850Y1560R090 S2      
317GND_P1           VIA   -    MD0100PA00X+037348Y-021022X0200Y    R270 S0      
317GND_P1           VIA   -    MD0100PA00X+037632Y-016886X0200Y    R090 S0      
317GND_P1           VIA   -    MD0100PA00X+037339Y-016561X0200Y    R090 S0      
317GND_P1           VIA   -    MD0100PA00X+037088Y-016561X0200Y    R090 S0      
317GND_P1           VIA   -    MD0100PA00X+037088Y-016886X0200Y    R090 S0      
317GND_P1           VIA   -    MD0100PA00X+037339Y-016886X0200Y    R090 S0      
317GND_P1           VIA   -    MD0100PA00X+037218Y-016257X0200Y    R090 S0      
317GND_P1           VIA   -    MD0100PA00X+038297Y-016257X0200Y    R090 S0      
317GND_P1           VIA   -    MD0100PA00X+038176Y-016886X0200Y    R090 S0      
317GND_P1           VIA   -    MD0100PA00X+037883Y-016885X0200Y    R090 S0      
317GND_P1           VIA   -    MD0100PA00X+038428Y-016886X0200Y    R090 S0      
317GND_P1           VIA   -    MD0100PA00X+038428Y-016561X0200Y    R090 S0      
327GND_P1           J16   -3   M      A01X+037758Y-016569X0850Y1560R090 S1      
317GND_P1           VIA   -    MD0100PA00X+038176Y-016561X0200Y    R090 S0      
317GND_P1           VIA   -    MD0100PA00X+037892Y+002130X0200Y    R270 S0      
317GND_P1           VIA   -    MD0100PA00X+038185Y+001805X0200Y    R270 S0      
317GND_P1           VIA   -    MD0100PA00X+038436Y+001805X0200Y    R270 S0      
317GND_P1           VIA   -    MD0100PA00X+038436Y+002130X0200Y    R270 S0      
317GND_P1           VIA   -    MD0100PA00X+038185Y+002130X0200Y    R270 S0      
317GND_P1           VIA   -    MD0100PA00X+038306Y+001501X0200Y    R270 S0      
317GND_P1           VIA   -    MD0100PA00X+037227Y+001501X0200Y    R270 S0      
317GND_P1           VIA   -    MD0100PA00X+037348Y+002130X0200Y    R270 S0      
317GND_P1           VIA   -    MD0100PA00X+037641Y+002129X0200Y    R270 S0      
317GND_P1           VIA   -    MD0100PA00X+037096Y+002130X0200Y    R270 S0      
317GND_P1           VIA   -    MD0100PA00X+037096Y+001805X0200Y    R270 S0      
327GND_P1           J19   -3   M      A01X+037766Y+001813X0850Y1560R270 S1      
317GND_P1           VIA   -    MD0100PA00X+037348Y+001805X0200Y    R270 S0      
317GND_P1           VIA   -    MD0100PA00X+037635Y+005941X0200Y    R090 S0      
317GND_P1           VIA   -    MD0100PA00X+037342Y+006266X0200Y    R090 S0      
317GND_P1           VIA   -    MD0100PA00X+037090Y+006266X0200Y    R090 S0      
317GND_P1           VIA   -    MD0100PA00X+037090Y+005941X0200Y    R090 S0      
317GND_P1           VIA   -    MD0100PA00X+037342Y+005941X0200Y    R090 S0      
317GND_P1           VIA   -    MD0100PA00X+037221Y+006570X0200Y    R090 S0      
317GND_P1           VIA   -    MD0100PA00X+038300Y+006570X0200Y    R090 S0      
317GND_P1           VIA   -    MD0100PA00X+038179Y+005941X0200Y    R090 S0      
317GND_P1           VIA   -    MD0100PA00X+037886Y+005942X0200Y    R090 S0      
317GND_P1           VIA   -    MD0100PA00X+038430Y+005941X0200Y    R090 S0      
317GND_P1           VIA   -    MD0100PA00X+038430Y+006266X0200Y    R090 S0      
327GND_P1           J23   -3   M      A01X+037760Y+006258X0850Y1560R090 S1      
317GND_P1           VIA   -    MD0100PA00X+038179Y+006266X0200Y    R090 S0      
317GND_P1           VIA   -    MD0100PA00X+038306Y+038428X0200Y    R270 S0      
317GND_P1           VIA   -    MD0100PA00X+038436Y+038732X0200Y    R270 S0      
317GND_P1           VIA   -    MD0100PA00X+038436Y+039057X0200Y    R270 S0      
317GND_P1           VIA   -    MD0100PA00X+038185Y+038732X0200Y    R270 S0      
317GND_P1           VIA   -    MD0100PA00X+038185Y+039057X0200Y    R270 S0      
317GND_P1           VIA   -    MD0100PA00X+037096Y+039057X0200Y    R270 S0      
317GND_P1           VIA   -    MD0100PA00X+037096Y+038732X0200Y    R270 S0      
317GND_P1           VIA   -    MD0100PA00X+037348Y+039057X0200Y    R270 S0      
317GND_P1           VIA   -    MD0100PA00X+037348Y+038732X0200Y    R270 S0      
317GND_P1           VIA   -    MD0100PA00X+037641Y+039056X0200Y    R270 S0      
317GND_P1           VIA   -    MD0100PA00X+037892Y+039057X0200Y    R270 S0      
327GND_P1           J26   -3   M      A01X+037766Y+038740X0850Y1560R270 S1      
317GND_P1           VIA   -    MD0100PA00X+037227Y+038428X0200Y    R270 S0      
317GND_P1           X7    -2   MD0098PA00X+045100Y+043000X0785Y    R270 S3      
317GND_P1           VIA   -    MD0100PA00X+038060Y-043553X0200Y         S0      
317GND_P1           VIA   -    MD0100PA00X+037498Y-043538X0200Y         S0      
317GND_P1           VIA   -    MD0100PA00X+037467Y-021857X0200Y         S0      
317GND_P1           VIA   -    MD0100PA00X+038029Y-021872X0200Y         S0      
317GND_P1           VIA   -    MD0100PA00X+037495Y-015711X0200Y         S0      
317GND_P1           VIA   -    MD0100PA00X+038057Y-015726X0200Y         S0      
317GND_P1           VIA   -    MD0100PA00X+037467Y+000970X0200Y         S0      
317GND_P1           VIA   -    MD0100PA00X+038029Y+000955X0200Y         S0      
317GND_P1           VIA   -    MD0100PA00X+037498Y+007116X0200Y         S0      
317GND_P1           VIA   -    MD0100PA00X+038060Y+007101X0200Y         S0      
317GND_P1           VIA   -    MD0100PA00X+037467Y+037897X0200Y         S0      
317GND_P1           VIA   -    MD0100PA00X+038029Y+037882X0200Y         S0      
317GND_P1           X7    -3   MD0098PA00X+044100Y+043000X0785Y    R270 S3      
317GND_P1           X8    -2   MD0098PA00X+045100Y+031400X0785Y    R270 S3      
317GND_P1           X1    -3   MD0098PA00X+045100Y+032600X0785Y    R090 S3      
317GND_P1           X8    -3   MD0098PA00X+044100Y+031400X0785Y    R270 S3      
317GND_P1           X1    -2   MD0098PA00X+044100Y+032600X0785Y    R090 S3      
317GND_P1           X5    -3   MD0098PA00X+045100Y+021000X0785Y    R090 S3      
317GND_P1           X2    -3   MD0098PA00X+045100Y+022000X0785Y    R090 S3      
317GND_P1           X5    -2   MD0098PA00X+044100Y+021000X0785Y    R090 S3      
317GND_P1           X2    -2   MD0098PA00X+044100Y+022000X0785Y    R090 S3      
317GND_P1           X12   -3   MD0098PA00X+045100Y+010600X0785Y    R090 S3      
317GND_P1           X11   -2   MD0098PA00X+045100Y+011600X0785Y    R270 S3      
317GND_P1           X12   -2   MD0098PA00X+044100Y+010600X0785Y    R090 S3      
317GND_P1           X11   -3   MD0098PA00X+044100Y+011600X0785Y    R270 S3      
317GND_P1           X6    -2   MD0098PA00X+045100Y+000200X0785Y    R270 S3      
317GND_P1           X6    -3   MD0098PA00X+044100Y+000200X0785Y    R270 S3      
317GND_P1           X19   -2   MD0098PA00X+045100Y-000800X0785Y    R270 S3      
317GND_P1           X19   -3   MD0098PA00X+044100Y-000800X0785Y    R270 S3      
317GND_P1           X13   -3   MD0098PA00X+045100Y-011700X0785Y    R090 S3      
317GND_P1           X13   -2   MD0098PA00X+044100Y-011700X0785Y    R090 S3      
317GND_P1           VIA   -    MD0100PA00X+039578Y-012363X0200Y         S0      
317GND_P1           X20   -2   MD0098PA00X+045100Y-012660X0785Y    R270 S3      
317GND_P1           X20   -3   MD0098PA00X+044100Y-012660X0785Y    R270 S3      
317GND_P1           VIA   -    MD0100PA00X+040141Y-012379X0200Y         S0      
317GND_P1           X14   -3   MD0098PA00X+045100Y-022500X0785Y    R090 S3      
317GND_P1           X14   -2   MD0098PA00X+044100Y-022500X0785Y    R090 S3      
317GND_P1           X17   -3   MD0098PA00X+045100Y-023500X0785Y    R090 S3      
317GND_P1           X17   -2   MD0098PA00X+044100Y-023500X0785Y    R090 S3      
317GND_P1           X23   -2   MD0098PA00X+045100Y-033340X0785Y    R270 S3      
317GND_P1           X23   -3   MD0098PA00X+044100Y-033340X0785Y    R270 S3      
317GND_P1           X18   -3   MD0098PA00X+045100Y-034500X0785Y    R090 S3      
317GND_P1           X18   -2   MD0098PA00X+044100Y-034500X0785Y    R090 S3      
317GND_P1           VIA   -    MD0100PA00X+040169Y-046160X0200Y         S0      
317GND_P1           VIA   -    MD0100PA00X+039606Y-046144X0200Y         S0      
317GND_P1           X24   -2   MD0098PA00X+045100Y-045400X0785Y    R270 S3      
317GND_P1           X24   -3   MD0098PA00X+044100Y-045400X0785Y    R270 S3      
327m0348            J22   -1          A01X+040973Y+021094X0120Y0200R180 S1      
327m0348            J25   -2          A01X+040973Y-006762X0120Y0200     S1      
327m0349            J22   -2          A01X+040777Y+021094X0120Y0200R180 S1      
327m0349            J25   -1          A01X+040777Y-006762X0120Y0200     S1      
317m0350            VIA   -    MD0100PA00X+037596Y+038158X0200Y         S0      
327m0350            J26   -2          A01X+037668Y+038415X0120Y0200R180 S1      
327m0350            J23   -1          A01X+037662Y+006583X0120Y0200     S1      
317m0350            VIA   -    MD0100PA00X+037590Y+006840X0200Y    R180 S0      
317m0351            VIA   -    MD0100PA00X+037936Y+038158X0200Y         S0      
327m0351            J26   -1          A01X+037865Y+038415X0120Y0200R180 S1      
327m0351            J23   -2          A01X+037859Y+006583X0120Y0200     S1      
317m0351            VIA   -    MD0100PA00X+037930Y+006840X0200Y    R180 S0      
317m0352            VIA   -    MD0100PA00X+040048Y-012102X0200Y         S0      
327m0352            J28   -2          A12X+039976Y-011845X0120Y0200R180 S2      
317m0352            VIA   -    MD0100PA00X+040039Y-046421X0200Y    R180 S0      
327m0352            J30   -1          A12X+039968Y-046678X0120Y0200     S2      
317m0353            VIA   -    MD0100PA00X+039708Y-012102X0200Y         S0      
327m0353            J28   -1          A12X+039780Y-011845X0120Y0200R180 S2      
317m0353            VIA   -    MD0100PA00X+039699Y-046421X0200Y    R180 S0      
327m0353            J30   -2          A12X+039771Y-046678X0120Y0200     S2      
327m0354            J27   -2          A12X+039777Y-006762X0120Y0200     S2      
327m0354            J24   -1          A12X+039777Y+021094X0120Y0200R180 S2      
327m0355            J27   -1          A12X+039973Y-006762X0120Y0200     S2      
327m0355            J24   -2          A12X+039973Y+021094X0120Y0200R180 S2      
317m0356            D14   -C    D0320PA00X+007390Y+002476X0480Y         S3      
327m0356            VIA   -    M      A12X+005955Y+006300X0260Y         S2      
327m0356            R812  -2          A12X+005858Y+008600X0198Y0197R180 S2      
327m0356            C326  -1   M      A12X+005950Y+008208X0198Y0197R090 S2      
327m0356            R814  -2   M      A12X+005550Y+008208X0198Y0197R270 S2      
327PWR_LED_BUF_N    VIA   -    M      A01X+006232Y+006920X0300Y         S1      
327PWR_LED_BUF_N    R812  -1          A12X+005542Y+008600X0198Y0197R180 S2      
317PWR_LED_BUF_N    VIA   -    MD0100PA00X+005250Y+008098X0200Y         S0      
327PWR_LED_BUF_N    Q12   -6          A01X+004706Y+006476X0170Y0200     S1      
317HDD_LED_BUF_R    D15   -C    D0320PA00X+010047Y+002476X0480Y         S3      
327HDD_LED_BUF_R    R815  -2          A01X+011650Y+003892X0198Y0197R270 S1      
327HDD_LED_BUF_R    C324  -1   M      A01X+011250Y+003892X0198Y0197R090 S1      
327HDD_LED_BUF_R    R813  -2   M      A01X+010850Y+003892X0198Y0197R270 S1      
317HDD_LED_BUF      VIA   -    MD0100PA00X+010700Y+004450X0200Y         S0      
327HDD_LED_BUF      R813  -1          A01X+010850Y+004208X0198Y0197R270 S1      
317HDD_LED_BUF      VIA   -    MD0100PA00X+005360Y+004410X0200Y         S0      
327HDD_LED_BUF      Q12   -3          A01X+004194Y+007224X0170Y0200     S1      
327m0357            VIA   -    M      A01X+034100Y+006130X0300Y         S1      
327m0357            R733  -1   M      A01X+033422Y+006600X0198Y0197     S1      
327m0357            R504  -2   M      A01X+033422Y+007000X0198Y0197R180 S1      
327m0357            U32   -2          A01X+032502Y+007050X0140Y0490R270 S1      
327m0357            C199  -1   M      A01X+033422Y+007400X0198Y0197     S1      
327m0357            SW7   -2          A01X+033169Y+002752X0590Y0790     S1      
327m0358            R810  -1          A01X+006100Y+033108X0198Y0197R270 S1      
327m0358            U25   -A13        A01X+007031Y+034483X0160Y    R180 S1      
327m0359            R748  -1          A01X+011880Y+035412X0198Y0197R090 S1      
317m0359            VIA   -    MD0100PA00X+011133Y+035780X0200Y         S0      
317m0359            VIA   -    MD0100PA00X+007821Y+038103X0180Y         S0      
327m0359            U25   -M10        A01X+007976Y+037948X0160Y    R180 S1      
327m0359            R809  -1   M      A01X+011872Y+035030X0198Y0197     S1      
327m0360            VIA   -    M      A12X+006540Y+034420X0260Y         S2      
327m0360            R808  -1          A12X+005610Y+033108X0198Y0197R090 S2      
317m0360            VIA   -    MD0100PA00X+006876Y+034957X0180Y         S0      
327m0360            U25   -C13        A01X+007031Y+035113X0160Y    R180 S1      
327m0361            R806  -2          A12X+007190Y+031008X0198Y0197R270 S2      
327m0361            OSC2  -1          A12X+007776Y+030839X0340Y0460R090 S2      
327m0362            VIA   -    M      A12X+008870Y+031830X0260Y         S2      
327m0362            R807  -1          A12X+008870Y+032792X0198Y0197R270 S2      
327m0362            OSC2  -3          A12X+008603Y+030190X0340Y0460R090 S2      
327m0363            VIA   -    M      A12X+008870Y+033712X0260Y         S2      
327m0363            R807  -2          A12X+008870Y+033108X0198Y0197R270 S2      
327m0363            U25   -C8         A01X+008606Y+035113X0160Y    R180 S1      
317m0363            VIA   -    MD0100PA00X+008762Y+034957X0180Y         S0      
327m0364            R527  -1          A01X+024620Y+013886X0198Y0197R270 S1      
327m0364            U5    -A6         A01X+023974Y+015500X0160Y    R180 S1      
327m0365            U5    -B6         A01X+023974Y+015816X0160Y    R180 S1      
327m0365            R528  -1          A01X+025021Y+013886X0198Y0197R270 S1      
327m0366            GF1   -B50        A01X+010372Y+046559X0150Y0680R180 S1      
317m0366            VIA   -    MD0100PA00X+009937Y+044548X0200Y         S0      
317m0366            VIA   -    MD0100PA00X+024649Y+010579X0200Y         S0      
327m0366            R527  -2          A01X+024620Y+013571X0198Y0197R270 S1      
327m0367            GF1   -B51        A01X+010136Y+046559X0150Y0680R180 S1      
317m0367            VIA   -    MD0100PA00X+009587Y+044548X0200Y         S0      
317m0367            VIA   -    MD0100PA00X+024999Y+010579X0200Y         S0      
327m0367            R528  -2          A01X+025021Y+013571X0198Y0197R270 S1      
327m0368            R440  -1   M      A01X+025518Y+011030X0198Y0197R180 S1      
317m0368            VIA   -    MD0100PA00X+025521Y+010610X0200Y         S0      
317m0368            VIA   -    MD0100PA00X+009630Y+045279X0200Y         S0      
327m0368            GF1   -B53        A01X+009663Y+046559X0150Y0680R180 S1      
327m0368            R217  -2          A01X+025433Y+011408X0198Y0197R270 S1      
327m0369            R441  -1   M      A01X+025892Y+011030X0198Y0197     S1      
317m0369            VIA   -    MD0100PA00X+025871Y+010610X0200Y         S0      
317m0369            VIA   -    MD0100PA00X+009280Y+045279X0200Y         S0      
327m0369            GF1   -B54        A01X+009427Y+046559X0150Y0680R180 S1      
327m0369            R218  -2          A01X+025834Y+011408X0198Y0197R270 S1      
327m0370            R170  -2          A12X+025670Y+013479X0198Y0197R090 S2      
317m0370            VIA   -    MD0100PA00X+026039Y+012500X0200Y         S0      
327m0370            VIA   -    M      A12X+025742Y+012984X0260Y         S2      
327m0370            R754  -2   M      A12X+017800Y+033875X0198Y0197R090 S2      
327m0370            R770  -2   M      A12X+018722Y+034592X0198Y0197R090 S2      
327m0370            U11   -2          A12X+017008Y+033644X0400Y0500R180 S2      
317m0370            VIA   -    MD0100PA00X+034550Y+034269X0200Y         S0      
317m0370            VIA   -    MD0100PA00X+019096Y+034809X0200Y         S0      
317m0370            VIA   -    MD0100PA00X+028758Y+008409X0200Y         S0      
327m0370            U47   -1          A01X+011024Y+024206X0170Y0240     S1      
317m0370            VIA   -    MD0100PA00X+012760Y+025970X0200Y         S0      
327UART_BMC_5_TXD   R170  -1          A12X+025670Y+013794X0198Y0197R090 S2      
327UART_BMC_5_TXD   U5    -C8         A01X+023344Y+016130X0160Y    R180 S1      
327UART_BMC_5_TXD   VIA   -    M      A12X+025259Y+014238X0260Y         S2      
317UART_BMC_5_TXD   VIA   -    MD0100PA00X+023500Y+015975X0180Y         S0      
317m0371            VIA   -    M      A01X+013800Y+024460X0200Y         S2      
017m0371            VIA   -    M      A12X+013800Y+024460X0260Y         S2      
017m0371                  -    MD0100PA00X+013800Y+024460                       
317m0371            VIA   -    MD0100PA00X+015825Y+007887X0200Y         S0      
327m0371            R757  -2          A01X+012450Y+026428X0198Y0197R090 S1      
327m0371            R758  -2   M      A01X+012962Y+026190X0198Y0197R180 S1      
317m0371            VIA   -    MD0100PA00X+010827Y+013863X0200Y         S0      
327m0371            R759  -2          A12X+026020Y+013480X0198Y0197R090 S2      
317m0371            VIA   -    MD0100PA00X+026020Y+013240X0200Y         S0      
327UART_BMC_5_RXD   R759  -1          A12X+026020Y+013794X0198Y0197R090 S2      
327UART_BMC_5_RXD   U5    -D8         A01X+023344Y+016445X0160Y    R180 S1      
327UART_BMC_5_RXD   VIA   -    M      A12X+024485Y+015335X0260Y         S2      
317UART_BMC_5_RXD   VIA   -    MD0100PA00X+023500Y+016290X0180Y    R180 S0      
317m0372            VIA   -    M      A01X+007620Y+024740X0200Y    R090 S2      
017m0372            VIA   -    M      A12X+007620Y+024740X0260Y    R090 S2      
017m0372                  -    MD0100PA00X+007620Y+024740                       
327m0372            U3    -3          A01X+007738Y+024008X0110Y0280     S1      
317m0372            VIA   -    MD0100PA00X+023990Y+011755X0200Y         S0      
327m0372            R427  -1          A12X+023959Y+011995X0198Y0197R270 S2      
317m0372            VIA   -    MD0100PA00X+007355Y+016668X0200Y         S0      
317m0372            VIA   -    MD0100PA00X+023966Y+009192X0200Y         S0      
327UART_BMC_1_RXD   U5    -D13        A01X+021770Y+016445X0160Y    R180 S1      
327UART_BMC_1_RXD   VIA   -    M      A12X+023662Y+012880X0260Y         S2      
317UART_BMC_1_RXD   VIA   -    MD0100PA00X+021925Y+016290X0180Y         S0      
327UART_BMC_1_RXD   R427  -2          A12X+023959Y+012310X0198Y0197R270 S2      
327m0373            R761  -2          A12X+015848Y+011920X0198Y0197R180 S2      
317m0373            VIA   -    MD0100PA00X+019094Y+016920X0180Y    R180 S0      
327m0373            U5    -E21        A01X+019250Y+016760X0160Y    R180 S1      
317m0374            VIA   -    MD0100PA00X+017600Y+014050X0200Y         S0      
327m0374            R762  -2          A01X+017600Y+013788X0198Y0197R090 S1      
327m0374            U5    -B22        A01X+018935Y+015816X0160Y    R180 S1      
317m0374            VIA   -    MD0100PA00X+018779Y+015660X0180Y    R180 S2      
317m0375            VIA   -    MD0100PA00X+016569Y+014962X0200Y         S0      
327m0375            R760  -2          A12X+016378Y+014700X0198Y0197R180 S2      
327m0375            U5    -E26        A01X+017675Y+016760X0160Y    R180 S1      
327m0376            R122  -2          A01X+015898Y+015830X0198Y0197     S1      
327m0376            U5    -F25        A01X+017990Y+017075X0160Y    R180 S1      
327U43_CT           VIA   -    M      A01X+013754Y+016950X0300Y         S1      
327U43_CT           C264  -1          A01X+013300Y+017342X0198Y0197R090 S1      
327U43_CT           U43   -4          A01X+013724Y+016362X0240Y0420     S1      
327U43_CT           R710  -2   M      A01X+014042Y+017520X0198Y0197R180 S1      
327SPI_TPM_CS_R_N   R594  -2          A01X+027190Y+042372X0198Y0197R270 S1      
327SPI_TPM_CS_R_N   VIA   -    M      A01X+027488Y+038729X0300Y         S1      
327SPI_TPM_CS_R_N   R500  -2          A01X+027004Y+038534X0198Y0197     S1      
327SPI_TPM_CS_N     VIA   -    M      A01X+027000Y+043160X0300Y         S1      
327SPI_TPM_CS_N     R594  -1          A01X+027190Y+042688X0198Y0197R270 S1      
327SPI_TPM_CS_N     GF1   -OB12       A01X+027189Y+046559X0150Y0680R180 S1      
327m0377            R862  -1          A01X+020988Y+041960X0198Y0197R180 S1      
327m0377            VIA   -    M      A01X+020883Y+042450X0300Y         S1      
327m0377            GF1   -B15        A01X+021679Y+046559X0150Y0680R180 S1      
317SPI_SYS_R_MOSI   VIA   -    M      A01X+027640Y+037040X0300Y    R180 S1      
017SPI_SYS_R_MOSI   VIA   -    M      A12X+027640Y+037040X0200Y    R180 S1      
017SPI_SYS_R_MOSI         -    MD0100PA00X+027640Y+037040                       
327SPI_SYS_R_MOSI   R498  -1          A01X+027004Y+036861X0198Y0197R180 S1      
327SPI_SYS_R_MOSI   R860  -1          A01X+021570Y+043228X0198Y0197R270 S1      
327SPI_SYS_R_MOSI   GF1   -B13        A01X+022152Y+046638X0150Y0840R180 S1      
317SPI_SYS_R_MOSI   VIA   -    MD0100PA00X+022342Y+036708X0200Y         S0      
317SPI_SYS_R_MOSI   VIA   -    MD0100PA00X+021710Y+043610X0200Y         S0      
327SPI_SYS_R_MISO   R499  -1          A01X+027004Y+038108X0198Y0197R180 S1      
327SPI_SYS_R_MISO   R861  -1          A01X+021170Y+043228X0198Y0197R270 S1      
327SPI_SYS_R_MISO   GF1   -B14        A01X+021915Y+046559X0150Y0680R180 S1      
317SPI_SYS_R_MISO   VIA   -    MD0100PA00X+021390Y+043600X0200Y         S0      
317SPI_SYS_R_MISO   VIA   -    MD0100PA00X+027310Y+038150X0200Y    R180 S0      
317SPI_SYS_R_MISO   VIA   -    M      A01X+022258Y+038762X0200Y         S2      
017SPI_SYS_R_MISO   VIA   -    M      A12X+022258Y+038762X0260Y         S2      
017SPI_SYS_R_MISO         -    MD0100PA00X+022258Y+038762                       
327SPI_SYS_R_CLK    VIA   -    M      A01X+022643Y+041160X0300Y         S1      
327SPI_SYS_R_CLK    R859  -1          A01X+022650Y+040688X0198Y0197R270 S1      
327SPI_SYS_R_CLK    R501  -2   M      A01X+021782Y+041600X0198Y0197R180 S1      
327SPI_SYS_R_CLK    GF1   -B11        A01X+022624Y+046559X0150Y0680R180 S1      
327m0378            R498  -2          A01X+026689Y+036861X0198Y0197R180 S1      
327m0378            VIA   -    M      A01X+026820Y+037340X0300Y         S1      
327m0378            J5    -3          A01X+025516Y+037148X0240Y0650R270 S1      
327m0379            VIA   -    M      A01X+027258Y+037628X0300Y         S1      
327m0379            R499  -2          A01X+026689Y+038108X0198Y0197R180 S1      
327m0379            J5    -4          A01X+025516Y+037542X0240Y0650R270 S1      
327SPI_SYS_R1_CLK   VIA   -    M      A01X+021980Y+036420X0300Y         S1      
327SPI_SYS_R1_CLK   J5    -1          A01X+025516Y+036361X0240Y0650R270 S1      
327SPI_SYS_R1_CLK   R501  -1          A01X+022098Y+041600X0198Y0197R180 S1      
327m0380            R863  -1          A01X+020730Y+043228X0198Y0197R270 S1      
327m0380            GF1   -B16        A01X+021443Y+046638X0150Y0840R180 S1      
327SPI_SYS_CS0_N    R864  -1          A01X+021960Y+043228X0198Y0197R270 S1      
327SPI_SYS_CS0_N    GF1   -B12        A01X+022388Y+046559X0150Y0680R180 S1      
327m0381            R802  -2          A12X+022712Y+024985X0198Y0197R090 S2      
327m0381            U5    -AA13       A01X+021770Y+021800X0160Y    R180 S1      
317m0381            VIA   -    MD0100PA00X+021925Y+021955X0180Y         S0      
327m0382            R801  -2          A12X+022327Y+023782X0198Y0197R090 S2      
327m0382            U5    -AB14       A01X+021455Y+022115X0160Y    R180 S1      
317m0382            VIA   -    MD0100PA00X+021610Y+021959X0180Y         S0      
327m0383            U21   -10         A12X+016130Y+039401X0140Y0590R090 S2      
327m0383            VIA   -    M      A12X+015333Y+039171X0260Y         S2      
327m0383            R728  -2          A12X+014882Y+039200X0198Y0197R180 S2      
327m0384            U30   -6          A12X+018118Y+031864X0140Y0590R270 S2      
327m0384            R725  -2          A12X+023910Y+025378X0198Y0197R270 S2      
327m0384            VIA   -    M      A12X+021625Y+032813X0260Y         S2      
317m0384            VIA   -    MD0100PA00X+023853Y+026308X0200Y         S0      
317m0384            VIA   -    MD0100PA00X+023169Y+033490X0200Y         S0      
327m0385            VIA   -           A01X+023501Y+026359X0300Y         S1      
327m0385            U21   -3          A12X+018430Y+040424X0140Y0590R090 S2      
327m0385            R724  -2          A01X+023510Y+025378X0198Y0197R090 S1      
317m0385            VIA   -    MD0100PA00X+024370Y+037273X0200Y         S0      
317m0385            VIA   -    MD0100PA00X+024209Y+027143X0200Y         S0      
327m0386            R725  -1          A12X+023910Y+025062X0198Y0197R270 S2      
327m0386            U5    -AB10       A01X+022715Y+022115X0160Y    R180 S1      
327m0386            VIA   -    M      A12X+023507Y+023699X0260Y         S2      
317m0386            VIA   -    MD0100PA00X+022559Y+022272X0180Y    R270 S0      
327m0387            R724  -1          A01X+023510Y+025062X0198Y0197R090 S1      
327m0387            U5    -AF9        A01X+023030Y+023374X0160Y    R180 S1      
327m0387            VIA   -    M      A01X+023533Y+024547X0300Y         S1      
327m0388            R799  -2          A01X+024294Y+025839X0198Y0197R270 S1      
327m0388            U5    -AE8        A01X+023344Y+023060X0160Y    R180 S1      
327m0388            VIA   -    M      A01X+024415Y+025092X0300Y         S1      
327QSPI_2_PLD_IO3   GF1   -B48        A01X+010844Y+046559X0150Y0680R180 S1      
317QSPI_2_PLD_IO3   VIA   -    M      A01X+010346Y+042588X0200Y         S2      
017QSPI_2_PLD_IO3   VIA   -    M      A12X+010346Y+042588X0260Y         S2      
017QSPI_2_PLD_IO3         -    MD0100PA00X+010346Y+042588                       
317QSPI_2_PLD_IO3   VIA   -    MD0100PA00X+019644Y+029406X0200Y         S0      
327QSPI_2_PLD_IO3   R682  -2          A01X+020950Y+027608X0198Y0197R090 S1      
327QSPI_2_PLD_IO2   VIA   -    M      A01X+010307Y+043263X0300Y         S1      
327QSPI_2_PLD_IO2   GF1   -B47        A01X+011081Y+046559X0150Y0680R180 S1      
317QSPI_2_PLD_IO2   VIA   -    MD0100PA00X+010411Y+042295X0200Y         S0      
317QSPI_2_PLD_IO2   VIA   -    MD0100PA00X+021550Y+024711X0200Y         S0      
327QSPI_2_PLD_IO2   R681  -2          A01X+021820Y+025218X0198Y0197R090 S1      
327QSPI_2_PLD_IO1   GF1   -B46        A01X+011317Y+046638X0150Y0840R180 S1      
317QSPI_2_PLD_IO1   VIA   -    MD0100PA00X+022010Y+023720X0200Y         S0      
327QSPI_2_PLD_IO1   R680  -2          A12X+021720Y+023862X0198Y0197R090 S2      
317QSPI_2_PLD_IO1   VIA   -    M      A01X+010870Y+041830X0200Y         S2      
017QSPI_2_PLD_IO1   VIA   -    M      A12X+010870Y+041830X0260Y         S2      
017QSPI_2_PLD_IO1         -    MD0100PA00X+010870Y+041830                       
327QSPI_2_PLD_IO0   VIA   -    M      A01X+010980Y+042230X0300Y         S1      
327QSPI_2_PLD_IO0   GF1   -B45        A01X+011553Y+046559X0150Y0680R180 S1      
317QSPI_2_PLD_IO0   VIA   -    MD0100PA00X+011300Y+041620X0200Y         S0      
317QSPI_2_PLD_IO0   VIA   -    MD0100PA00X+018244Y+028180X0200Y         S0      
327QSPI_2_PLD_IO0   R679  -2          A12X+018648Y+027920X0198Y0197R180 S2      
317QSPI_2_PLD_CLK   VIA   -    M      A01X+011280Y+042160X0200Y         S2      
017QSPI_2_PLD_CLK   VIA   -    M      A12X+011280Y+042160X0260Y         S2      
017QSPI_2_PLD_CLK         -    MD0100PA00X+011280Y+042160                       
327QSPI_2_PLD_CLK   GF1   -B43        A01X+012026Y+046638X0150Y0840R180 S1      
317QSPI_2_PLD_CLK   VIA   -    MD0100PA00X+020605Y+024791X0200Y         S0      
327QSPI_2_PLD_CLK   R678  -2          A01X+020756Y+024490X0198Y0197R180 S1      
327m0389            R421  -2          A12X+027169Y+010470X0198Y0197R180 S2      
317m0389            VIA   -    MD0100PA00X+027476Y+010514X0200Y         S0      
317m0389            VIA   -    M      A01X+019598Y+012929X0200Y         S2      
017m0389            VIA   -    M      A12X+019598Y+012929X0260Y         S2      
017m0389                  -    MD0100PA00X+019598Y+012929                       
327m0389            R880  -2          A12X+019600Y+011508X0198Y0197R270 S2      
327m0389            R265  -2   M      A12X+019550Y+012308X0198Y0197R270 S2      
327m0389            R153  -1          A12X+019500Y+013492X0198Y0197R270 S2      
327m0390            R420  -2          A12X+027169Y+010823X0198Y0197R180 S2      
327m0390            R879  -2          A12X+020000Y+011508X0198Y0197R270 S2      
327m0390            VIA   -    M      A12X+020450Y+011351X0260Y         S2      
327m0390            R264  -2   M      A12X+019950Y+012308X0198Y0197R270 S2      
327m0390            R152  -1          A12X+019900Y+013482X0198Y0197R270 S2      
317m0390            VIA   -    MD0100PA00X+020000Y+012876X0200Y         S0      
317m0390            VIA   -    MD0100PA00X+027420Y+010950X0200Y         S0      
327m0391            VIA   -    M      A12X+020040Y+015160X0260Y         S2      
327m0391            U5    -E18        A01X+020195Y+016760X0160Y    R180 S1      
317m0391            VIA   -    MD0100PA00X+020039Y+016605X0180Y         S0      
327m0391            R153  -2          A12X+019500Y+013808X0198Y0197R270 S2      
327m0392            U5    -C17        A01X+020510Y+016130X0160Y    R180 S1      
317m0392            VIA   -    MD0100PA00X+020354Y+015975X0180Y         S2      
327m0392            R152  -2          A12X+019900Y+013798X0198Y0197R270 S2      
327m0393            VIA   -    M      A12X+006538Y+021312X0260Y         S2      
317m0393            VIA   -    MD0100PA00X+007137Y+018899X0200Y         S0      
327m0393            R294  -1          A12X+006122Y+022972X0198Y0197R270 S2      
317m0393            VIA   -    MD0100PA00X+020412Y+013229X0200Y         S0      
327m0393            R236  -1          A01X+020412Y+013479X0198Y0197R090 S1      
327m0393            R692  -2          A01X+020400Y+012308X0198Y0197R090 S1      
327m0394            R135  -1          A12X+006522Y+022972X0198Y0197R270 S2      
317m0394            VIA   -    MD0100PA00X+007115Y+018649X0200Y         S0      
327m0394            VIA   -    M      A12X+006670Y+022052X0260Y         S2      
327m0394            R610  -2          A12X+019143Y+012306X0198Y0197R270 S2      
327m0394            R162  -1          A12X+019100Y+013492X0198Y0197R270 S2      
317m0394            VIA   -    MD0100PA00X+019148Y+012929X0200Y         S0      
327m0395            R236  -2          A01X+020412Y+013794X0198Y0197R090 S1      
327m0395            U5    -B17        A01X+020510Y+015816X0160Y    R180 S1      
327m0395            VIA   -    M      A01X+020370Y+014331X0300Y         S1      
327m0396            U5    -D18        A01X+020195Y+016445X0160Y    R180 S1      
317m0396            VIA   -    MD0100PA00X+020039Y+016290X0180Y         S2      
327m0396            R162  -2          A12X+019100Y+013808X0198Y0197R270 S2      
327m0397            GF1   -A39        A12X+014667Y+046559X0150Y0680R180 S2      
327m0397            VIA   -    M      A12X+013480Y+042740X0260Y         S2      
317m0397            VIA   -    MD0100PA00X+013357Y+042394X0200Y         S0      
317m0397            VIA   -    MD0100PA00X+016124Y+018174X0200Y         S0      
327m0397            R144  -2          A12X+016365Y+018174X0198Y0197     S2      
327m0397            R149  -2          A12X+015878Y+018157X0198Y0197R180 S2      
327m0398            R145  -2          A01X+015065Y+018735X0198Y0197     S1      
327m0398            GF1   -A38        A12X+014904Y+046638X0150Y0840R180 S2      
327m0398            R137  -2          A01X+015568Y+018735X0198Y0197R180 S1      
327m0398            VIA   -    M      A12X+014082Y+043303X0260Y         S2      
317m0398            VIA   -    MD0100PA00X+013899Y+042394X0200Y         S0      
317m0398            VIA   -    MD0100PA00X+015305Y+018735X0200Y         S0      
317FM_ME_BT_DONE    VIA   -    MD0100PA00X+008237Y+019701X0200Y         S0      
327FM_ME_BT_DONE    U5    -J26        A01X+017675Y+018020X0160Y    R180 S1      
327FM_ME_BT_DONE    VIA   -    M      A01X+016443Y+017498X0300Y         S1      
317FM_ME_BT_DONE    VIA   -    MD0100PA00X+017457Y+018020X0180Y         S0      
327FM_ME_BT_DONE    R266  -2          A01X+015878Y+017100X0198Y0197     S1      
327FM_ME_BT_DONE    U25   -D7         A01X+008921Y+035428X0160Y    R180 S1      
317FM_ME_BT_DONE    VIA   -    MD0100PA00X+009077Y+035272X0180Y         S0      
317m0399            VIA   -    MD0100PA00X+023665Y+010074X0200Y         S0      
317m0399            VIA   -    MD0100PA00X+019094Y+016605X0180Y    R180 S2      
327m0399            U5    -D21        A01X+019250Y+016445X0160Y    R180 S1      
327m0399            R851  -2          A12X+024408Y+010817X0198Y0197R090 S2      
327m0400            U5    -L24        A01X+018305Y+018650X0160Y    R180 S1      
317m0400            VIA   -    MD0100PA00X+018150Y+018494X0180Y         S0      
327m0400            R818  -1   M      A12X+016680Y+018595X0198Y0197     S2      
327m0400            R424  -1          A12X+015878Y+018908X0198Y0197     S2      
327m0401            U5    -L23        A01X+018620Y+018650X0160Y    R180 S1      
327m0401            VIA   -    M      A12X+017680Y+019420X0260Y         S2      
317m0401            VIA   -    MD0100PA00X+018464Y+018494X0180Y         S0      
327m0401            R819  -1   M      A12X+016680Y+019072X0198Y0197     S2      
327m0401            R425  -1          A12X+015878Y+019258X0198Y0197     S2      
327m0402            R426  -1   M      A01X+015878Y+017480X0198Y0197R180 S1      
327m0402            R820  -1          A01X+015879Y+017868X0198Y0197R180 S1      
327m0402            U5    -K25        A01X+017990Y+018335X0160Y    R180 S1      
327m0403            R423  -1          A01X+015167Y+018259X0198Y0197R180 S1      
327m0403            R817  -1   M      A01X+015868Y+018264X0198Y0197R180 S1      
327m0403            U5    -K26        A01X+017675Y+018335X0160Y    R180 S1      
327m0403            VIA   -    M      A01X+016460Y+018149X0300Y         S1      
327m0404            R10   -2          A12X+002100Y+032258X0198Y0197R270 S2      
317m0404            VIA   -    MD0100PA00X+002368Y+042242X0200Y         S0      
317m0404            VIA   -    MD0100PA00X+027640Y+043181X0200Y         S0      
327m0404            GF1   -OB11       A01X+027425Y+046559X0150Y0680R180 S1      
317m0404            VIA   -    MD0100PA00X+001387Y+035224X0200Y         S0      
317m0404            VIA   -    MD0100PA00X+002381Y+032253X0200Y         S0      
327m0404            R388  -1          A01X+001700Y+032008X0198Y0197R270 S1      
327m0405            R691  -2          A01X+004692Y+034400X0198Y0197R180 S1      
327m0405            R688  -2          A12X+016266Y+011975X0198Y0197R090 S2      
317m0405            VIA   -    MD0100PA00X+010318Y+033629X0200Y         S0      
317m0405            VIA   -    MD0100PA00X+004422Y+034101X0200Y         S0      
327m0405            GF1   -B39        A01X+014667Y+046559X0150Y0680R180 S1      
327m0405            R69   -2   M      A01X+013990Y+043208X0198Y0197R090 S1      
317m0405            VIA   -    MD0100PA00X+013307Y+042087X0200Y         S0      
317m0405            VIA   -    MD0100PA00X+016266Y+011730X0200Y         S0      
317m0406            VIA   -    MD0100PA00X+017210Y+014630X0200Y         S0      
327m0406            R688  -1          A12X+016266Y+012290X0198Y0197R090 S2      
317m0406            VIA   -    MD0100PA00X+018464Y+017550X0180Y         S2      
327m0406            U5    -H23        A01X+018620Y+017705X0160Y    R180 S1      
327m0407            R718  -2          A01X+011872Y+034250X0198Y0197R180 S1      
327m0407            U25   -A4         A01X+009866Y+034483X0160Y    R180 S1      
327m0408            R263  -2          A12X+006008Y+036770X0198Y0197R180 S2      
317m0408            VIA   -    MD0100PA00X+007506Y+036532X0180Y         S0      
327m0408            U25   -H11        A01X+007661Y+036688X0160Y    R180 S1      
327RST_MB_STBY_N    R263  -1          A12X+005692Y+036770X0198Y0197R180 S2      
317RST_MB_STBY_N    VIA   -    MD0100PA00X+005529Y+036973X0200Y         S0      
317RST_MB_STBY_N    VIA   -    M      A01X+012565Y+036865X0200Y         S2      
017RST_MB_STBY_N    VIA   -    M      A12X+012565Y+036865X0260Y         S2      
017RST_MB_STBY_N          -    MD0100PA00X+012565Y+036865                       
317RST_MB_STBY_N    VIA   -    MD0100PA00X+011151Y+043471X0200Y         S0      
327RST_MB_STBY_N    GF1   -A46        A12X+011317Y+046638X0150Y0840R180 S2      
327m0409            R117  -2   M      A12X+025340Y+027676X0198Y0197R180 S2      
327m0409            R312  -1          A12X+025750Y+027708X0198Y0197R090 S2      
317m0409            VIA   -    M      A01X+025810Y+029508X0200Y         S2      
017m0409            VIA   -    M      A12X+025810Y+029508X0260Y         S2      
017m0409                  -    MD0100PA00X+025810Y+029508                       
317m0409            VIA   -    MD0100PA00X+024338Y+044838X0200Y         S0      
327m0409            GF1   -B4         A01X+024278Y+046559X0150Y0680R180 S1      
327m0409            R120  -1   M      A12X+025340Y+028078X0198Y0197     S2      
327Q7_D             Q7    -D          A12X+029416Y+037602X0320Y0360R180 S2      
327Q7_D             R42   -2          A12X+029416Y+036913X0198Y0197R270 S2      
327Q7_D             VIA   -    M      A12X+029870Y+036913X0260Y         S2      
327m0410            R841  -2          A01X+004692Y+038400X0198Y0197R180 S1      
317m0410            VIA   -    MD0100PA00X+004452Y+038400X0200Y         S0      
327m0410            GF1   -A48        A12X+010844Y+046559X0150Y0680R180 S2      
317m0410            VIA   -    M      A01X+020410Y+006740X0200Y         S2      
017m0410            VIA   -    M      A12X+020410Y+006740X0260Y         S2      
017m0410                  -    MD0100PA00X+020410Y+006740                       
327m0410            R40   -2          A12X+009281Y+042090X0198Y0197R270 S2      
317m0410            VIA   -    MD0100PA00X+009326Y+042420X0200Y         S0      
317m0410            VIA   -    MD0100PA00X+002940Y+043090X0200Y         S0      
317m0410            VIA   -    MD0100PA00X+022330Y+011740X0200Y         S0      
327m0410            R840  -1          A01X+022330Y+011992X0198Y0197R090 S1      
327m0410            R701  -1          A12X+020068Y+033875X0198Y0197R180 S2      
317m0410            VIA   -    MD0100PA00X+019480Y+034170X0200Y         S0      
327m0411            R837  -1          A12X+010918Y+033770X0198Y0197     S2      
327m0411            R243  -1          A12X+012850Y+041792X0198Y0197R270 S2      
317m0411            VIA   -    M      A01X+012914Y+041025X0200Y         S2      
017m0411            VIA   -    M      A12X+012914Y+041025X0260Y         S2      
017m0411                  -    MD0100PA00X+012914Y+041025                       
317m0411            VIA   -    MD0100PA00X+019778Y+034662X0200Y         S0      
327m0411            R719  -1          A12X+020018Y+034575X0198Y0197R180 S2      
317m0411            VIA   -    MD0100PA00X+001470Y+042500X0200Y         S0      
317m0411            VIA   -    MD0100PA00X+016070Y+044555X0200Y         S0      
317m0411            VIA   -    MD0100PA00X+019450Y+040260X0200Y         S0      
327m0411            R66   -2   M      A01X+001682Y+032860X0198Y0197R180 S1      
327m0411            R711  -1          A01X+003492Y+033800X0198Y0197     S1      
317m0411            VIA   -    MD0100PA00X+011554Y+033524X0200Y         S0      
317m0411            VIA   -    MD0100PA00X+023029Y+011742X0200Y         S0      
317m0411            VIA   -    MD0100PA00X+014630Y+016101X0200Y         S0      
327m0411            R836  -1          A01X+022860Y+011992X0198Y0197R090 S1      
327PWRGD_P3V3_RGM   R322  -2          A12X+007450Y+040308X0198Y0197R270 S2      
317PWRGD_P3V3_RGM   VIA   -    M      A01X+007744Y+026276X0200Y    R090 S2      
017PWRGD_P3V3_RGM   VIA   -    M      A12X+007744Y+026276X0260Y    R090 S2      
017PWRGD_P3V3_RGM         -    MD0100PA00X+007744Y+026276                       
317PWRGD_P3V3_RGM   VIA   -    MD0100PA00X+005440Y+037470X0200Y         S0      
317PWRGD_P3V3_RGM   VIA   -    MD0100PA00X+006632Y+041349X0200Y         S0      
317PWRGD_P3V3_RGM   VIA   -    MD0100PA00X+028366Y+037924X0200Y         S0      
317PWRGD_P3V3_RGM   VIA   -    MD0100PA00X+030288Y+028249X0200Y         S0      
327PWRGD_P3V3_RGM   R99   -2          A01X+028125Y+011592X0198Y0197R270 S1      
317PWRGD_P3V3_RGM   VIA   -    MD0100PA00X+028525Y+011725X0200Y         S0      
327PWRGD_P3V3_RGM   U52   -2          A12X+031410Y+027409X0130Y0460R180 S2      
327PWRGD_P3V3_RGM   R530  -1          A01X+012250Y+025678X0198Y0197R270 S1      
317PWRGD_P3V3_RGM   VIA   -    MD0100PA00X+012002Y+025443X0200Y         S0      
317m0412            VIA   -    MD0100PA00X+026310Y+009172X0200Y         S0      
317m0412            VIA   -    MD0100PA00X+024948Y+005581X0200Y         S0      
327m0412            Q13   -2          A01X+024576Y+004400X0170Y0200R090 S1      
327m0412            VIA   -    M      A01X+009220Y+014154X0300Y         S1      
317m0412            VIA   -    MD0100PA00X+008917Y+014154X0200Y         S0      
327m0412            R451  -1          A01X+012950Y+014092X0198Y0197R090 S1      
317m0412            VIA   -    MD0100PA00X+001460Y+042250X0200Y         S0      
327m0412            U6    -1          A01X+002826Y+032756X0170Y0240R270 S1      
327m0412            R711  -2   M      A01X+003808Y+033800X0198Y0197     S1      
317m0412            VIA   -    MD0100PA00X+017460Y+011400X0200Y         S0      
327m0412            R395  -2          A01X+017800Y+010738X0198Y0197R090 S1      
327m0413            GF1   -A44        A12X+011789Y+046559X0150Y0680R180 S2      
327m0413            R243  -2          A12X+012850Y+042108X0198Y0197R270 S2      
327m0413            VIA   -    M      A12X+012850Y+042607X0260Y         S2      
327PU_SPI1WP_N      VIA   -    M      A01X+023040Y+024960X0300Y         S1      
327PU_SPI1WP_N      R683  -2          A01X+023278Y+025820X0198Y0197     S1      
327PU_SPI1WP_N      U5    -AE10       A01X+022715Y+023060X0160Y    R180 S1      
327PU_SPI1ABR       U5    -AD10       A01X+022715Y+022745X0160Y    R180 S1      
317PU_SPI1ABR       VIA   -    MD0100PA00X+022870Y+022900X0180Y    R180 S2      
317PU_SPI1ABR       VIA   -    MD0100PA00X+022963Y+026440X0200Y         S0      
327PU_SPI1ABR       R241  -2          A12X+022926Y+026200X0198Y0197R270 S2      
327PU_FWSPIWP_N     R240  -2          A12X+022536Y+026168X0198Y0197R270 S2      
327PU_FWSPIWP_N     R402  -1          A12X+022340Y+026542X0198Y0197R270 S2      
327m0414            R239  -2          A12X+022310Y+024922X0198Y0197R090 S2      
327m0414            R401  -1          A12X+021942Y+024580X0198Y0197R180 S2      
327m0415            VIA   -           A12X+023511Y+026278X0260Y         S2      
327m0415            C314  -1          A12X+023343Y+027985X0198Y0197     S2      
327m0415            R798  -1          A12X+023343Y+027584X0198Y0197     S2      
327m0415            R797  -2          A12X+023332Y+028391X0198Y0197     S2      
327m0415            VIA   -           A12X+023495Y+027130X0260Y         S2      
317m0415            VIA   -    MD0100PA00X+023303Y+026648X0200Y         S0      
317m0415            VIA   -    MD0100PA00X+019724Y+022270X0180Y    R180 S0      
327m0415            U5    -AB19       A01X+019880Y+022115X0160Y    R180 S1      
327m0416            Q4    -D          A12X+025329Y+039475X0320Y0360R090 S2      
327m0416            R645  -2          A12X+027020Y+036620X0280Y0320R180 S2      
317m0416            VIA   -           A01X+027358Y+035425X0300Y         S1      
017m0416            VIA   -           A12X+027358Y+035425X0200Y         S1      
017m0416                  -     D0100PA00X+027358Y+035425                       
327m0416            R646  -1          A12X+025651Y+038440X0280Y0320R270 S2      
317m0416            VIA   -    MD0100PA00X+025670Y+026380X0200Y         S0      
317m0416            VIA   -           A01X+026231Y+031122X0200Y         S2      
017m0416            VIA   -           A12X+026231Y+031122X0260Y         S2      
017m0416                  -     D0100PA00X+026231Y+031122                       
327m0416            L17   -1          A01X+025351Y+026349X0280Y0320R090 S1      
317m0416            VIA   -    MD0100PA00X+025800Y+026630X0200Y         S0      
317m0416            VIA   -    MD0100PA00X+027729Y+035582X0200Y         S0      
327m0416            Q5    -6          A12X+025651Y+036858X0280Y0400     S2      
327m0416            Q5    -1          A12X+025651Y+037802X0280Y0400     S2      
327m0416            Q5    -5          A12X+026025Y+036858X0280Y0400     S2      
327m0416            Q5    -2          A12X+026025Y+037802X0280Y0400     S2      
317m0416            VIA   -    MD0100PA00X+027552Y+035791X0200Y         S0      
327P5V_SENSOR       U5    -AC18       A01X+020195Y+022430X0160Y    R180 S1      
327P5V_SENSOR       C295  -1          A12X+022955Y+028994X0198Y0197     S2      
327P5V_SENSOR       R788  -1          A12X+022947Y+028591X0198Y0197     S2      
327P5V_SENSOR       R787  -2          A12X+022955Y+029396X0198Y0197R180 S2      
327P5V_SENSOR       VIA   -           A12X+023469Y+028893X0260Y         S2      
327P5V_SENSOR       VIA   -           A12X+023969Y+028893X0260Y         S2      
317P5V_SENSOR       VIA   -    MD0100PA00X+020039Y+022585X0180Y    R180 S0      
317P5V_SENSOR       VIA   -    MD0100PA00X+025146Y+028354X0200Y    R180 S0      
317P5V_SENSOR       VIA   -    MD0100PA00X+025146Y+028654X0200Y    R180 S0      
327P3V_BAT_SENSOR   U5    -AE18       A01X+020195Y+023060X0160Y    R180 S1      
327P3V_BAT_SENSOR   VIA   -    M      A12X+017501Y+028158X0260Y         S2      
317P3V_BAT_SENSOR   VIA   -    MD0100PA00X+017298Y+027700X0200Y         S0      
317P3V_BAT_SENSOR   VIA   -    MD0100PA00X+020039Y+023215X0180Y    R180 S0      
327P3V_BAT_SENSOR   Q11   -S   M      A12X+017571Y+028722X0400Y0480R090 S2      
327P3V_BAT_SENSOR   C275  -1   M      A12X+018683Y+028722X0198Y0197R180 S2      
327P3V_BAT_SENSOR   R778  -1          A12X+018683Y+028316X0198Y0197R180 S2      
327P3V_BAT_R1       R777  -2   M      A12X+016736Y+028185X0198Y0197     S2      
327P3V_BAT_R1       VIA   -           A12X+016030Y+028185X0260Y         S2      
327P3V_BAT_R1       Q11   -D          A12X+016690Y+029116X0400Y0480R090 S2      
317P3V_BAT_R        VIA   -    MD0100PA00X+018105Y+033225X0200Y         S0      
327P3V_BAT_R        R777  -1          A12X+017051Y+028185X0198Y0197     S2      
327P3V_BAT_R        VIA   -    M      A12X+015951Y+031250X0260Y         S2      
327P3V_BAT_R        U48   -1          A12X+016916Y+041476X0320Y0360R270 S2      
317P3V_BAT_R        VIA   -    MD0100PA00X+016370Y+042212X0200Y         S0      
317P3V_BAT_R        VIA   -    MD0100PA00X+013207Y+043311X0200Y         S0      
327P3V_BAT_R        C174  -1          A01X+012930Y+042908X0198Y0197R270 S1      
327P3V_BAT_R        GF1   -B41        A01X+014195Y+046638X0150Y0840R180 S1      
327P3V3_SENSOR      U5    -AE19       A01X+019880Y+023060X0160Y    R180 S1      
317P3V3_SENSOR      VIA   -    MD0100PA00X+020559Y+026913X0200Y         S0      
327P3V3_SENSOR      C299  -1          A12X+020581Y+027164X0198Y0197R270 S2      
327P3V3_SENSOR      R789  -2          A12X+019779Y+027164X0198Y0197R090 S2      
327P3V3_SENSOR      R790  -1          A12X+020179Y+027164X0198Y0197R270 S2      
317P3V3_SENSOR      VIA   -    MD0100PA00X+020309Y+026923X0200Y         S0      
317P3V3_SENSOR      VIA   -    MD0100PA00X+019724Y+023215X0180Y    R180 S0      
327P2V5_SENSOR      R791  -2          A12X+021381Y+027567X0198Y0197R090 S2      
327P2V5_SENSOR      U5    -AD19       A01X+019880Y+022745X0160Y    R180 S1      
327P2V5_SENSOR      VIA   -           A12X+021840Y+027040X0260Y         S2      
327P2V5_SENSOR      C303  -1          A12X+020981Y+027164X0198Y0197R270 S2      
327P2V5_SENSOR      R792  -1          A12X+021383Y+027067X0198Y0197R090 S2      
317P2V5_SENSOR      VIA   -    MD0100PA00X+019724Y+022900X0180Y    R180 S0      
317P2V5_SENSOR      VIA   -    MD0100PA00X+021326Y+027326X0200Y         S0      
317P1V8_SENSOR      VIA   -    MD0100PA00X+019724Y+022585X0180Y    R180 S0      
327P1V8_SENSOR      U5    -AC19       A01X+019880Y+022430X0160Y    R180 S1      
327P1V8_SENSOR      C307  -1          A12X+019866Y+028277X0198Y0197R180 S2      
327P1V8_SENSOR      R794  -1          A12X+019866Y+027874X0198Y0197R180 S2      
327P1V8_SENSOR      R793  -2          A12X+019866Y+028678X0198Y0197     S2      
327P1V8_SENSOR      VIA   -           A12X+019327Y+027833X0260Y         S2      
317P1V8_SENSOR      VIA   -    MD0100PA00X+019610Y+028182X0200Y    R270 S0      
317P1V8_SENSOR      VIA   -    MD0100PA00X+019620Y+027820X0200Y    R270 S0      
327P1V2_SENSOR      U5    -AB18       A01X+020195Y+022115X0160Y    R180 S1      
317P1V2_SENSOR      VIA   -    MD0100PA00X+021291Y+029387X0200Y         S0      
327P1V2_SENSOR      C309  -1          A12X+022115Y+029387X0198Y0197R090 S2      
327P1V2_SENSOR      R795  -2   M      A12X+021712Y+029387X0198Y0197R270 S2      
317P1V2_SENSOR      VIA   -    MD0100PA00X+020039Y+022270X0180Y         S2      
327P1V0_SENSOR      U5    -AB17       A01X+020510Y+022115X0160Y    R180 S1      
317P1V0_SENSOR      VIA   -    MD0100PA00X+020354Y+022270X0180Y         S0      
317P1V0_SENSOR      VIA   -    MD0100PA00X+020100Y+026250X0200Y         S0      
327P1V0_SENSOR      C311  -1          A12X+019410Y+026426X0198Y0197R090 S2      
327P1V0_SENSOR      R796  -2   M      A12X+019800Y+026422X0198Y0197R270 S2      
317P12V_SENSOR      VIA   -    MD0100PA00X+019409Y+022900X0180Y    R180 S0      
327P12V_SENSOR      U5    -AD20       A01X+019565Y+022745X0160Y    R180 S1      
317P12V_SENSOR      VIA   -    MD0100PA00X+013017Y+023473X0200Y         S0      
327P12V_SENSOR      C290  -1          A12X+012738Y+023830X0198Y0197     S2      
327P12V_SENSOR      VIA   -           A12X+013361Y+023500X0260Y         S2      
327P12V_SENSOR      VIA   -           A12X+013861Y+023500X0260Y         S2      
327P12V_SENSOR      R785  -2          A12X+012755Y+023130X0198Y0197R270 S2      
327P12V_SENSOR      R786  -1          A12X+012738Y+023480X0198Y0197     S2      
327m0417            Q7    -G          A12X+029042Y+038390X0320Y0360R180 S2      
327m0417            C267  -1          A12X+029014Y+039736X0198Y0197R180 S2      
327m0417            R714  -2   M      A12X+029014Y+039333X0198Y0197     S2      
327m0417            VIA   -    M      A12X+028547Y+039458X0260Y         S2      
327LPC_ESPI_SEL_R   R713  -1   M      A12X+030582Y+039335X0198Y0197     S2      
327LPC_ESPI_SEL_R   Q10   -G          A12X+030475Y+038630X0320Y0360R180 S2      
327LPC_ESPI_SEL_R   C273  -1          A12X+030582Y+039738X0198Y0197     S2      
327LPC_ESPI_SEL_R   VIA   -    M      A12X+031043Y+039335X0260Y         S2      
327LPC_ESPI_SEL_N   Q4    -G   M      A12X+026117Y+039849X0320Y0360R090 S2      
327LPC_ESPI_SEL_N   Q5    -3          A12X+026399Y+037802X0280Y0400     S2      
327LPC_ESPI_SEL_N   R493  -1   M      A12X+026722Y+038410X0198Y0197R180 S2      
317LPC_ESPI_SEL_N   VIA   -    MD0100PA00X+031192Y+036648X0200Y         S0      
317LPC_ESPI_SEL_N   VIA   -    MD0100PA00X+026510Y+039510X0200Y         S0      
327LPC_ESPI_SEL_N   C270  -1   M      A12X+031192Y+036900X0198Y0197R180 S2      
327LPC_ESPI_SEL_N   VIA   -    M      A12X+030700Y+036750X0260Y         S2      
327LPC_ESPI_SEL_N   Q10   -D          A12X+030849Y+037842X0320Y0360R180 S2      
327LPC_ESPI_SEL_N   R716  -2   M      A12X+030842Y+037300X0198Y0197     S2      
327LPC_ESPI_SEL     R41   -2          A12X+021580Y+042288X0198Y0197R270 S2      
327LPC_ESPI_SEL     GF1   -B9         A01X+023096Y+046559X0150Y0680R180 S1      
327LPC_ESPI_SEL     R713  -2          A12X+030268Y+039335X0198Y0197     S2      
327LPC_ESPI_SEL     R714  -1          A12X+029329Y+039333X0198Y0197     S2      
317LPC_ESPI_SEL     VIA   -    M      A01X+029815Y+039333X0200Y         S2      
017LPC_ESPI_SEL     VIA   -    M      A12X+029815Y+039333X0260Y         S2      
017LPC_ESPI_SEL           -    MD0100PA00X+029815Y+039333                       
317LPC_ESPI_SEL     VIA   -    MD0100PA00X+021925Y+042215X0200Y         S0      
327m0418            VIA   -    M      A01X+014831Y+019369X0300Y         S1      
317m0418            VIA   -    MD0100PA00X+008136Y+035587X0180Y         S0      
327m0418            U25   -E9         A01X+008291Y+035743X0160Y    R180 S1      
327m0418            R177  -2          A01X+015572Y+019170X0198Y0197R180 S1      
317m0418            VIA   -    MD0100PA00X+007667Y+020877X0200Y         S0      
317m0418            VIA   -    MD0100PA00X+014090Y+019942X0200Y         S0      
327IRQ_SGPIO_N      R690  -2          A12X+005220Y+032792X0198Y0197R090 S2      
317IRQ_SGPIO_N      VIA   -    MD0100PA00X+013619Y+015810X0200Y         S0      
327IRQ_SGPIO_N      R689  -1          A12X+016342Y+016550X0198Y0197R180 S2      
327IRQ_SGPIO_N      VIA   -    M      A12X+009481Y+030131X0260Y         S2      
327IRQ_SGPIO_N      R68   -2   M      A01X+013302Y+042900X0198Y0197R180 S1      
327IRQ_SGPIO_N      GF1   -B40        A01X+014431Y+046559X0150Y0680R180 S1      
317IRQ_SGPIO_N      VIA   -    MD0100PA00X+013350Y+040911X0200Y         S0      
317IRQ_SGPIO_N      VIA   -    MD0100PA00X+010510Y+030930X0200Y         S0      
327m0419            R689  -2          A12X+016658Y+016550X0198Y0197R180 S2      
327m0419            U5    -G24        A01X+018305Y+017390X0160Y    R180 S1      
317m0419            VIA   -    MD0100PA00X+018150Y+017235X0180Y         S2      
327m0420            R571  -2          A12X+007650Y+033108X0198Y0197R270 S2      
317m0420            VIA   -    M      A01X+007890Y+033660X0200Y         S2      
017m0420            VIA   -    M      A12X+007890Y+033660X0260Y         S2      
017m0420                  -    MD0100PA00X+007890Y+033660                       
327m0420            U25   -A8         A01X+008606Y+034483X0160Y    R180 S1      
327m0421            R571  -1          A12X+007650Y+032792X0198Y0197R270 S2      
327m0421            R61   -2          A12X+018850Y+020688X0198Y0197R270 S2      
327m0421            U5    -R23        A01X+018620Y+019910X0160Y    R180 S1      
317m0421            VIA   -    M      A01X+006914Y+041345X0200Y         S2      
017m0421            VIA   -    M      A12X+006914Y+041345X0260Y         S2      
017m0421                  -    MD0100PA00X+006914Y+041345                       
317m0421            VIA   -    MD0100PA00X+018905Y+039750X0200Y         S0      
317m0421            VIA   -    MD0100PA00X+018464Y+020066X0180Y         S0      
317m0421            VIA   -    MD0100PA00X+007690Y+032300X0200Y         S0      
327m0422            GF1   -B3         A01X+024514Y+046559X0150Y0680R180 S1      
317m0422            VIA   -    MD0100PA00X+024650Y+044850X0200Y         S0      
317m0422            VIA   -    M      A01X+025310Y+025780X0200Y         S2      
017m0422            VIA   -    M      A12X+025310Y+025780X0260Y         S2      
017m0422                  -    MD0100PA00X+025310Y+025780                       
327m0422            R116  -2   M      A01X+025002Y+025736X0198Y0197     S1      
327m0422            R119  -1          A01X+025050Y+025323X0198Y0197R270 S1      
327I3C2_SPD_SDA     R187  -1          A01X+016997Y+026054X0198Y0197R270 S1      
317I3C2_SPD_SDA     VIA   -    M      A01X+027890Y+042140X0200Y         S2      
017I3C2_SPD_SDA     VIA   -    M      A12X+027890Y+042140X0260Y         S2      
017I3C2_SPD_SDA           -    MD0100PA00X+027890Y+042140                       
327I3C2_SPD_SDA     GF1   -OA8        A12X+028134Y+046638X0150Y0840R180 S2      
327I3C2_SPD_SDA     R191  -2          A12X+016993Y+026041X0198Y0197R270 S2      
317I3C2_SPD_SDA     VIA   -    MD0100PA00X+017159Y+026331X0200Y         S0      
317I3C2_SPD_SDA     VIA   -    MD0100PA00X+028367Y+044998X0200Y         S0      
327I3C2_SPD_SCL     R186  -1          A01X+017399Y+026054X0198Y0197R270 S1      
317I3C2_SPD_SCL     VIA   -    M      A01X+027419Y+040890X0200Y         S2      
017I3C2_SPD_SCL     VIA   -    M      A12X+027419Y+040890X0260Y         S2      
017I3C2_SPD_SCL           -    MD0100PA00X+027419Y+040890                       
327I3C2_SPD_SCL     GF1   -OA7        A12X+028370Y+046638X0150Y0840R180 S2      
327I3C2_SPD_SCL     R190  -2          A12X+017399Y+026041X0198Y0197R270 S2      
317I3C2_SPD_SCL     VIA   -    MD0100PA00X+017429Y+026330X0200Y         S0      
317I3C2_SPD_SCL     VIA   -    MD0100PA00X+028372Y+045277X0200Y         S0      
327I3C1_SPD_SDA     R185  -1          A01X+016097Y+025259X0198Y0197R270 S1      
317I3C1_SPD_SDA     VIA   -    M      A01X+026970Y+041138X0200Y         S2      
017I3C1_SPD_SDA     VIA   -    M      A12X+026970Y+041138X0260Y         S2      
017I3C1_SPD_SDA           -    MD0100PA00X+026970Y+041138                       
327I3C1_SPD_SDA     GF1   -OA6        A12X+028606Y+046638X0150Y0840R180 S2      
327I3C1_SPD_SDA     R195  -2          A12X+016097Y+025259X0198Y0197R270 S2      
317I3C1_SPD_SDA     VIA   -    MD0100PA00X+027663Y+043950X0200Y         S0      
317I3C1_SPD_SDA     VIA   -    MD0100PA00X+016097Y+025499X0200Y         S0      
327I3C1_SPD_SCL     R184  -1          A01X+016480Y+026054X0198Y0197R270 S1      
317I3C1_SPD_SCL     VIA   -    M      A01X+027300Y+043050X0200Y         S2      
017I3C1_SPD_SCL     VIA   -    M      A12X+027300Y+043050X0260Y         S2      
017I3C1_SPD_SCL           -    MD0100PA00X+027300Y+043050                       
327I3C1_SPD_SCL     GF1   -OA5        A12X+028842Y+046638X0150Y0840R180 S2      
327I3C1_SPD_SCL     R194  -2          A12X+016480Y+026054X0198Y0197R270 S2      
317I3C1_SPD_SCL     VIA   -    MD0100PA00X+016480Y+026330X0200Y         S0      
327m0423            R769  -2          A01X+011910Y+039622X0198Y0197R270 S1      
317m0423            VIA   -    M      A01X+012205Y+037226X0200Y         S2      
017m0423            VIA   -    M      A12X+012205Y+037226X0260Y         S2      
017m0423                  -    MD0100PA00X+012205Y+037226                       
317m0423            VIA   -    MD0100PA00X+007191Y+037158X0180Y         S0      
327m0423            U25   -J12        A01X+007346Y+037003X0160Y    R180 S1      
327m0424            R773  -2          A12X+011452Y+036660X0198Y0197     S2      
317m0424            VIA   -    M      A01X+011195Y+037120X0200Y         S2      
017m0424            VIA   -    M      A12X+011195Y+037120X0260Y         S2      
017m0424                  -    MD0100PA00X+011195Y+037120                       
327m0424            U25   -G11        A01X+007661Y+036373X0160Y    R180 S1      
317m0424            VIA   -    MD0100PA00X+007506Y+036217X0180Y         S0      
327m0425            R51   -2          A12X+005978Y+037260X0198Y0197R180 S2      
327m0425            U25   -J14        A01X+006716Y+037003X0160Y    R180 S1      
317m0425            VIA   -    MD0100PA00X+006561Y+037158X0180Y         S2      
327m0426            R51   -1          A12X+005662Y+037260X0198Y0197R180 S2      
327m0426            U5    -D14        A01X+021455Y+016445X0160Y    R180 S1      
317m0426            VIA   -    MD0100PA00X+021299Y+016290X0180Y    R180 S2      
317m0426            VIA   -    MD0100PA00X+005804Y+037010X0200Y         S0      
327m0427            R70   -1          A01X+013290Y+018428X0198Y0197R270 S1      
327m0427            U5    -P23        A01X+018620Y+019595X0160Y    R180 S1      
327m0427            VIA   -    M      A01X+012391Y+018819X0300Y         S1      
317m0427            VIA   -    MD0100PA00X+012478Y+020163X0200Y         S0      
317m0427            VIA   -    MD0100PA00X+018464Y+019751X0180Y         S0      
327m0428            GF1   -A49        A12X+010608Y+046638X0150Y0840R180 S2      
327m0428            R158  -1          A12X+020700Y+013482X0198Y0197R270 S2      
327m0428            VIA   -    M      A12X+009471Y+043326X0260Y         S2      
317m0428            VIA   -    MD0100PA00X+020858Y+012896X0200Y         S0      
317m0428            VIA   -    MD0100PA00X+009287Y+043783X0200Y         S0      
327m0429            R237  -2          A12X+024183Y+013794X0198Y0197R270 S2      
327m0429            U5    -C12        A01X+022085Y+016130X0160Y    R180 S1      
317m0429            VIA   -    MD0100PA00X+022240Y+015975X0180Y    R180 S2      
327m0430            R237  -1          A12X+024183Y+013479X0198Y0197R270 S2      
317m0430            VIA   -    M      A01X+024250Y+012900X0200Y         S2      
017m0430            VIA   -    M      A12X+024250Y+012900X0260Y         S2      
017m0430                  -    MD0100PA00X+024250Y+012900                       
327m0430            GF1   -A50        A12X+010372Y+046559X0150Y0680R180 S2      
317m0430            VIA   -    MD0100PA00X+009577Y+043792X0200Y         S0      
327m0431            R852  -1          A12X+017122Y+030090X0198Y0197R180 S2      
317m0431            VIA   -    M      A01X+003990Y+021100X0200Y         S2      
017m0431            VIA   -    M      A12X+003990Y+021100X0260Y         S2      
017m0431                  -    MD0100PA00X+003990Y+021100                       
327m0431            U5    -J23        A01X+018620Y+018020X0160Y    R180 S1      
317m0431            VIA   -    MD0100PA00X+018464Y+017865X0180Y         S0      
317m0431            VIA   -    MD0100PA00X+003910Y+032160X0200Y         S0      
317m0431            VIA   -    MD0100PA00X+016450Y+031480X0200Y         S0      
317m0432            VIA   -    MD0100PA00X+009392Y+035272X0180Y         S2      
327m0432            U25   -D6         A01X+009236Y+035428X0160Y    R180 S1      
327m0432            R706  -2          A01X+016862Y+012310X0198Y0197R090 S1      
327m0432            R705  -1          A01X+018000Y+013472X0198Y0197R090 S1      
317m0432            VIA   -    MD0100PA00X+017828Y+013239X0200Y         S0      
327m0433            R242  -2          A12X+016780Y+015340X0198Y0197R180 S2      
317m0433            VIA   -    M      A01X+010657Y+028003X0200Y         S2      
017m0433            VIA   -    M      A12X+010657Y+028003X0260Y         S2      
017m0433                  -    MD0100PA00X+010657Y+028003                       
317m0433            VIA   -    MD0100PA00X+004220Y+043590X0200Y         S0      
317m0433            VIA   -    MD0100PA00X+003550Y+033500X0200Y         S0      
317m0433            VIA   -    MD0100PA00X+008136Y+037788X0180Y         S0      
327m0433            U25   -L9         A01X+008291Y+037633X0160Y    R180 S1      
317m0433            VIA   -    MD0100PA00X+016190Y+015050X0200Y         S0      
317m0434            VIA   -    MD0100PA00X+015990Y+015560X0200Y         S0      
327m0434            R242  -1          A12X+016465Y+015340X0198Y0197R180 S2      
317m0434            VIA   -    MD0100PA00X+018779Y+017550X0180Y         S0      
327m0434            U5    -H22        A01X+018935Y+017705X0160Y    R180 S1      
317m0435            VIA   -    MD0100PA00X+023140Y+045200X0200Y         S0      
327m0435            GF1   -B8         A01X+023333Y+046559X0150Y0680R180 S1      
327m0435            R131  -2          A12X+025046Y+024573X0198Y0197R270 S2      
327m0435            VIA   -    M      A12X+025090Y+025080X0260Y         S2      
317m0435            VIA   -    MD0100PA00X+025311Y+025491X0200Y         S0      
317m0436            VIA   -    M      A01X+024590Y+030500X0200Y         S2      
017m0436            VIA   -    M      A12X+024590Y+030500X0260Y         S2      
017m0436                  -    MD0100PA00X+024590Y+030500                       
327m0436            GF1   -B7         A01X+023569Y+046559X0150Y0680R180 S1      
317m0436            VIA   -    MD0100PA00X+023140Y+044950X0200Y         S0      
317m0436            VIA   -    MD0100PA00X+023773Y+024808X0200Y         S0      
327m0436            R130  -2          A12X+023841Y+024511X0198Y0197R270 S2      
327m0437            R129  -2          A12X+026180Y+024578X0198Y0197R270 S2      
327m0437            VIA   -    M      A12X+026180Y+025030X0260Y         S2      
317m0437            VIA   -    MD0100PA00X+026273Y+026760X0200Y         S0      
317m0437            VIA   -    MD0100PA00X+024021Y+045340X0200Y         S0      
327m0437            GF1   -B6         A01X+023805Y+046559X0150Y0680R180 S1      
327m0438            R128  -2          A12X+025447Y+024582X0198Y0197R270 S2      
327m0438            VIA   -    M      A12X+025950Y+025880X0260Y         S2      
317m0438            VIA   -    MD0100PA00X+025950Y+026370X0200Y         S0      
317m0438            VIA   -    MD0100PA00X+024001Y+045600X0200Y         S0      
327m0438            GF1   -B5         A01X+024041Y+046559X0150Y0680R180 S1      
327m0439            R115  -2   M      A01X+025401Y+042679X0198Y0197R090 S1      
327m0439            VIA   -    M      A01X+025080Y+043250X0300Y         S1      
327m0439            GF1   -B2         A01X+024750Y+046559X0150Y0680R180 S1      
327m0439            R311  -1          A01X+025790Y+042678X0198Y0197R270 S1      
327m0440            VIA   -    M      A01X+025640Y+043150X0300Y         S1      
327m0440            GF1   -B1         A01X+024986Y+046559X0150Y0680R180 S1      
327m0440            R310  -1          A01X+026190Y+042678X0198Y0197R270 S1      
327EN_P1V2_AUX_R    PU41  -5          A01X+031612Y+028516X0100Y0280R270 S1      
327EN_P1V2_AUX_R    R876  -2          A01X+030846Y+027710X0198Y0197     S1      
327EN_P1V2_AUX_R    R708  -2   M      A01X+030846Y+028109X0198Y0197     S1      
327EN_P1V2_AUX_R    VIA   -           A12X+030767Y+028516X0260Y         S2      
317EN_P1V2_AUX_R    VIA   -    MD0100PA00X+031167Y+028516X0200Y    R270 S0      
327EN_P1V2_AUX_R    R764  -2   M      A01X+030846Y+028509X0198Y0197     S1      
327EMMC_DT7_R       R650  -2   M      A01X+011526Y+027928X0198Y0197R090 S1      
327EMMC_DT7_R       J4    -52         A01X+011910Y+028882X0110Y0630     S1      
327EMMC_DT7_R       R662  -2          A01X+011526Y+027128X0198Y0197R090 S1      
327EMMC_DT6_R       R651  -2   M      A01X+011976Y+027928X0198Y0197R090 S1      
327EMMC_DT6_R       J4    -54         A01X+012106Y+028882X0110Y0630     S1      
327EMMC_DT6_R       R661  -2          A01X+011976Y+027128X0198Y0197R090 S1      
327EMMC_DT5_R       R652  -2          A01X+012426Y+027128X0198Y0197R090 S1      
327EMMC_DT5_R       J4    -56         A01X+012303Y+028882X0110Y0630     S1      
327EMMC_DT5_R       R660  -2   M      A01X+012426Y+027928X0198Y0197R090 S1      
327EMMC_DT4_R       R653  -2   M      A01X+012876Y+027928X0198Y0197R090 S1      
327EMMC_DT4_R       J4    -58         A01X+012500Y+028882X0110Y0630     S1      
327EMMC_DT4_R       R659  -2          A01X+012876Y+027128X0198Y0197R090 S1      
327EMMC_DT3_R       R532  -1          A01X+012992Y+032841X0198Y0197R090 S1      
327EMMC_DT3_R       R658  -2   M      A01X+012592Y+032841X0198Y0197R270 S1      
327EMMC_DT3_R       J4    -61         A01X+012795Y+031854X0110Y0630     S1      
327EMMC_DT2_R       R647  -1   M      A01X+013392Y+032841X0198Y0197R090 S1      
327EMMC_DT2_R       R657  -2          A01X+013792Y+032841X0198Y0197R270 S1      
327EMMC_DT2_R       J4    -65         A01X+013189Y+031854X0110Y0630     S1      
327EMMC_DT1_R       R648  -1   M      A01X+014592Y+032841X0198Y0197R090 S1      
327EMMC_DT1_R       R656  -2          A01X+014192Y+032841X0198Y0197R270 S1      
327EMMC_DT1_R       J4    -67         A01X+013386Y+031854X0110Y0630     S1      
327EMMC_DT0_R       R649  -1   M      A01X+014992Y+032841X0198Y0197R090 S1      
327EMMC_DT0_R       R655  -2          A01X+015392Y+032841X0198Y0197R270 S1      
327EMMC_DT0_R       J4    -71         A01X+013780Y+031854X0110Y0630     S1      
327EMMC_CMD_R       R48   -1          A01X+011792Y+032841X0198Y0197R090 S1      
327EMMC_CMD_R       R663  -2   M      A01X+012192Y+032841X0198Y0197R270 S1      
327EMMC_CMD_R       J4    -59         A01X+012598Y+031854X0110Y0630     S1      
327EMMC_CLK_R       R654  -1          A01X+011392Y+032841X0198Y0197R090 S1      
327EMMC_CLK_R       J4    -55         A01X+012205Y+031854X0110Y0630     S1      
317BMC_EMMC_WP_N    VIA   -    M      A01X+028591Y+027957X0300Y         S1      
017BMC_EMMC_WP_N    VIA   -    M      A12X+028591Y+027957X0200Y         S1      
017BMC_EMMC_WP_N          -    MD0100PA00X+028591Y+027957                       
327BMC_EMMC_WP_N    R686  -2          A12X+028591Y+027550X0198Y0197R270 S2      
327BMC_EMMC_WP_N    R684  -1          A12X+028591Y+028208X0198Y0197R270 S2      
317BMC_EMMC_WP_N    VIA   -    MD0100PA00X+018464Y+015345X0180Y    R180 S0      
327BMC_EMMC_WP_N    U5    -A23        A01X+018620Y+015500X0160Y    R180 S1      
327BMC_EMMC_RST_N   R11   -2          A01X+013300Y+027108X0198Y0197R090 S1      
327BMC_EMMC_RST_N   R96   -2          A01X+025240Y+028048X0198Y0197R090 S1      
317BMC_EMMC_RST_N   VIA   -    MD0100PA00X+024259Y+033068X0200Y         S0      
327BMC_EMMC_RST_N   VIA   -    M      A12X+024600Y+033390X0260Y         S2      
317BMC_EMMC_RST_N   VIA   -    MD0100PA00X+025800Y+028490X0200Y         S0      
327BMC_EMMC_RST_N   J4    -66  M      A01X+013287Y+028882X0110Y0630     S1      
317BMC_EMMC_RST_N   VIA   -    MD0100PA00X+015029Y+030212X0200Y         S0      
317BMC_EMMC_RST_N   VIA   -    MD0100PA00X+026630Y+030750X0200Y         S0      
327BMC_EMMC_DT7     R650  -1          A01X+011526Y+027613X0198Y0197R090 S1      
327BMC_EMMC_DT7     U5    -E20        A01X+019565Y+016760X0160Y    R180 S1      
317BMC_EMMC_DT7     VIA   -    MD0100PA00X+019409Y+016605X0180Y    R180 S0      
317BMC_EMMC_DT7     VIA   -    MD0100PA00X+011500Y+027370X0200Y         S0      
317BMC_EMMC_DT7     VIA   -    M      A01X+028994Y+030906X0200Y         S2      
017BMC_EMMC_DT7     VIA   -    M      A12X+028994Y+030906X0260Y         S2      
017BMC_EMMC_DT7           -    MD0100PA00X+028994Y+030906                       
327BMC_EMMC_DT6     R651  -1          A01X+011976Y+027613X0198Y0197R090 S1      
317BMC_EMMC_DT6     VIA   -    M      A01X+028751Y+030160X0200Y         S2      
017BMC_EMMC_DT6     VIA   -    M      A12X+028751Y+030160X0260Y         S2      
017BMC_EMMC_DT6           -    MD0100PA00X+028751Y+030160                       
317BMC_EMMC_DT6     VIA   -    MD0100PA00X+012007Y+027370X0200Y         S0      
317BMC_EMMC_DT6     VIA   -    MD0100PA00X+019240Y+015280X0180Y    R180 S0      
327BMC_EMMC_DT6     U5    -A21        A01X+019250Y+015500X0160Y    R180 S1      
327BMC_EMMC_DT5     R652  -1          A01X+012426Y+026813X0198Y0197R090 S1      
317BMC_EMMC_DT5     VIA   -    M      A01X+029100Y+029770X0200Y         S2      
017BMC_EMMC_DT5     VIA   -    M      A12X+029100Y+029770X0260Y         S2      
017BMC_EMMC_DT5           -    MD0100PA00X+029100Y+029770                       
317BMC_EMMC_DT5     VIA   -    MD0100PA00X+013708Y+027804X0200Y         S0      
317BMC_EMMC_DT5     VIA   -    MD0100PA00X+018779Y+015345X0180Y    R180 S0      
327BMC_EMMC_DT5     U5    -A22        A01X+018935Y+015500X0160Y    R180 S1      
327BMC_EMMC_DT4     R653  -1          A01X+012876Y+027613X0198Y0197R090 S1      
327BMC_EMMC_DT4     U5    -C21        A01X+019250Y+016130X0160Y    R180 S1      
317BMC_EMMC_DT4     VIA   -    MD0100PA00X+019094Y+015975X0180Y    R180 S2      
317BMC_EMMC_DT4     VIA   -    MD0100PA00X+012876Y+027370X0200Y         S0      
317BMC_EMMC_DT4     VIA   -    MD0100PA00X+028705Y+030585X0200Y         S0      
327BMC_EMMC_DT3     R532  -2          A01X+012992Y+033156X0198Y0197R090 S1      
317BMC_EMMC_DT3     VIA   -    MD0100PA00X+023500Y+033530X0200Y         S0      
327BMC_EMMC_DT3     U5    -A25        A01X+017990Y+015500X0160Y    R180 S1      
317BMC_EMMC_DT3     VIA   -    MD0100PA00X+018150Y+015345X0180Y    R180 S2      
317BMC_EMMC_DT3     VIA   -    MD0100PA00X+013330Y+033410X0200Y         S0      
327BMC_EMMC_DT2     R647  -2          A01X+013392Y+033156X0198Y0197R090 S1      
317BMC_EMMC_DT2     VIA   -    MD0100PA00X+029000Y+033560X0200Y         S0      
317BMC_EMMC_DT2     VIA   -    M      A01X+013610Y+033400X0200Y         S2      
017BMC_EMMC_DT2     VIA   -    M      A12X+013610Y+033400X0260Y         S2      
017BMC_EMMC_DT2           -    MD0100PA00X+013610Y+033400                       
317BMC_EMMC_DT2     VIA   -    MD0100PA00X+019094Y+016290X0180Y    R180 S0      
327BMC_EMMC_DT2     U5    -C22        A01X+018935Y+016130X0160Y    R180 S1      
327BMC_EMMC_DT1     R648  -2          A01X+014592Y+033156X0198Y0197R090 S1      
317BMC_EMMC_DT1     VIA   -    M      A01X+028637Y+032677X0200Y         S2      
017BMC_EMMC_DT1     VIA   -    M      A12X+028637Y+032677X0260Y         S2      
017BMC_EMMC_DT1           -    MD0100PA00X+028637Y+032677                       
317BMC_EMMC_DT1     VIA   -    MD0100PA00X+014470Y+033410X0200Y         S0      
327BMC_EMMC_DT1     U5    -C23        A01X+018620Y+016130X0160Y    R180 S1      
317BMC_EMMC_DT1     VIA   -    MD0100PA00X+018464Y+015975X0180Y    R180 S0      
327BMC_EMMC_DT0     R649  -2          A01X+014992Y+033156X0198Y0197R090 S1      
317BMC_EMMC_DT0     VIA   -    MD0100PA00X+014480Y+033670X0200Y         S0      
317BMC_EMMC_DT0     VIA   -    M      A01X+028960Y+032225X0200Y         S2      
017BMC_EMMC_DT0     VIA   -    M      A12X+028960Y+032225X0260Y         S2      
017BMC_EMMC_DT0           -    MD0100PA00X+028960Y+032225                       
327BMC_EMMC_DT0     U5    -D23        A01X+018620Y+016445X0160Y    R180 S1      
317BMC_EMMC_DT0     VIA   -    MD0100PA00X+018464Y+016290X0180Y         S0      
327BMC_EMMC_CMD     R48   -2          A01X+011792Y+033156X0198Y0197R090 S1      
317BMC_EMMC_CMD     VIA   -    M      A01X+029012Y+033937X0300Y         S1      
017BMC_EMMC_CMD     VIA   -    M      A12X+029012Y+033937X0200Y         S1      
017BMC_EMMC_CMD           -    MD0100PA00X+029012Y+033937                       
317BMC_EMMC_CMD     VIA   -    MD0100PA00X+012590Y+033760X0200Y         S0      
327BMC_EMMC_CMD     U5    -E22        A01X+018935Y+016760X0160Y    R180 S1      
317BMC_EMMC_CMD     VIA   -    MD0100PA00X+018779Y+016605X0180Y    R180 S0      
327BMC_EMMC_CLK     R654  -2          A01X+011392Y+033156X0198Y0197R090 S1      
317BMC_EMMC_CLK     VIA   -    M      A01X+028637Y+032070X0300Y         S1      
017BMC_EMMC_CLK     VIA   -    M      A12X+028637Y+032070X0200Y         S1      
017BMC_EMMC_CLK           -    MD0100PA00X+028637Y+032070                       
317BMC_EMMC_CLK     VIA   -    MD0100PA00X+010685Y+032329X0200Y         S0      
327BMC_EMMC_CLK     U5    -D22        A01X+018935Y+016445X0160Y    R180 S1      
317BMC_EMMC_CLK     VIA   -    MD0100PA00X+018779Y+016290X0180Y    R180 S0      
327BMC_EMMC_CD_N    R685  -1          A12X+028189Y+028208X0198Y0197R270 S2      
327BMC_EMMC_CD_N    R687  -2          A12X+028189Y+027550X0198Y0197R270 S2      
317BMC_EMMC_CD_N    VIA   -    MD0100PA00X+028291Y+027957X0200Y         S0      
317BMC_EMMC_CD_N    VIA   -    MD0100PA00X+018464Y+015660X0180Y    R180 S0      
327BMC_EMMC_CD_N    U5    -A24        A01X+018305Y+015500X0160Y    R180 S1      
327m0441            R776  -1   M      A12X+018680Y+029117X0198Y0197R180 S2      
327m0441            Q11   -G          A12X+017571Y+029510X0400Y0480R090 S2      
327m0441            VIA   -    M      A12X+018186Y+028987X0260Y         S2      
327m0441            R775  -2          A12X+018681Y+029510X0198Y0197     S2      
317BATTERY_DETECT   VIA   -    M      A01X+019238Y+029190X0300Y         S1      
017BATTERY_DETECT   VIA   -    M      A12X+019238Y+029190X0200Y         S1      
017BATTERY_DETECT         -    MD0100PA00X+019238Y+029190                       
327BATTERY_DETECT   U5    -AE15       A01X+021140Y+023060X0160Y    R180 S1      
327BATTERY_DETECT   R775  -1          A12X+018996Y+029510X0198Y0197     S2      
317BATTERY_DETECT   VIA   -    MD0100PA00X+020984Y+023215X0180Y    R180 S0      
317ADCVREFEXT1      VIA   -           A01X+024126Y+028265X0200Y         S2      
017ADCVREFEXT1      VIA   -           A12X+024126Y+028265X0260Y         S2      
017ADCVREFEXT1            -     D0100PA00X+024126Y+028265                       
327ADCVREFEXT1      U5    -AF17       A01X+020510Y+023374X0160Y    R180 S1      
327ADCVREFEXT1      VIA   -           A12X+023890Y+029695X0260Y         S2      
327ADCVREFEXT1      C279  -1          A12X+020624Y+023832X0198Y0197R090 S2      
327ADCVREFEXT1      C277  -1          A12X+020981Y+027874X0198Y0197     S2      
327ADCVREFEXT1      R779  -2          A12X+021368Y+028276X0198Y0197     S2      
327ADCVREFEXT1      R781  -2          A12X+020981Y+028678X0198Y0197R180 S2      
327ADCVREFEXT1      R782  -2          A12X+021368Y+028678X0198Y0197     S2      
327ADCVREFEXT1      VIA   -           A12X+022678Y+029885X0260Y         S2      
317ADCVREFEXT1      VIA   -    MD0100PA00X+020354Y+023530X0180Y         S0      
317ADCVREFEXT1      VIA   -    MD0100PA00X+024651Y+029682X0200Y    R090 S0      
317ADCVREFEXT1      VIA   -    MD0100PA00X+024651Y+029432X0200Y    R090 S0      
327ADCVREFEXT0      U5    -AF19       A01X+019880Y+023374X0160Y    R180 S1      
327ADCVREFEXT0      C284  -1          A12X+019448Y+023546X0198Y0197R270 S2      
327ADCVREFEXT0      C282  -1          A12X+022229Y+027978X0198Y0197R180 S2      
327ADCVREFEXT0      R784  -2          A12X+022229Y+028371X0198Y0197R090 S2      
327ADCVREFEXT0      R783  -2          A12X+022229Y+027577X0198Y0197     S2      
327ADCVREFEXT0      R780  -2          A12X+021786Y+027566X0198Y0197R090 S2      
317ADCVREFEXT0      VIA   -    MD0100PA00X+019724Y+023530X0180Y    R180 S0      
317ADCVREFEXT0      VIA   -    M      A01X+022087Y+027216X0300Y         S1      
017ADCVREFEXT0      VIA   -    M      A12X+022087Y+027216X0200Y         S1      
017ADCVREFEXT0            -    MD0100PA00X+022087Y+027216                       
327m0442            J12   -1          A01X+039973Y+040921X0120Y0200R180 S1      
327m0442            J9    -2          A01X+039973Y+026165X0120Y0200     S1      
327m0443            J12   -2          A01X+039777Y+040921X0120Y0200R180 S1      
327m0443            J9    -1          A01X+039777Y+026165X0120Y0200     S1      
317m0444            VIA   -    MD0100PA00X+037936Y+001231X0200Y         S0      
327m0444            J19   -1          A01X+037865Y+001488X0120Y0200R180 S1      
327m0444            J16   -2          A01X+037856Y-016244X0120Y0200     S1      
317m0444            VIA   -    MD0100PA00X+037928Y-015987X0200Y         S0      
317m0445            VIA   -    MD0100PA00X+037596Y+001231X0200Y         S0      
327m0445            J19   -2          A01X+037668Y+001488X0120Y0200R180 S1      
327m0445            J16   -1          A01X+037659Y-016244X0120Y0200     S1      
317m0445            VIA   -    MD0100PA00X+037588Y-015987X0200Y         S0      
317m0446            VIA   -    MD0100PA00X+037930Y-043814X0200Y    R180 S0      
327m0446            J29   -1          A12X+037859Y-044071X0120Y0200     S2      
317m0446            VIA   -    MD0100PA00X+037936Y-021596X0200Y         S0      
327m0446            J11   -2          A12X+037865Y-021339X0120Y0200R180 S2      
317m0447            VIA   -    MD0100PA00X+037590Y-043814X0200Y    R180 S0      
327m0447            J29   -2          A12X+037662Y-044071X0120Y0200     S2      
317m0447            VIA   -    MD0100PA00X+037596Y-021596X0200Y         S0      
327m0447            J11   -1          A12X+037668Y-021339X0120Y0200R180 S2      
327m0448            J20   -1          A12X+040973Y+026165X0120Y0200     S2      
327m0448            J17   -2          A12X+040973Y+040921X0120Y0200R180 S2      
327m0449            J20   -2          A12X+040777Y+026165X0120Y0200     S2      
327m0449            J17   -1          A12X+040777Y+040921X0120Y0200R180 S2      
327m0450            VIA   -    M      A12X+014715Y+027300X0260Y         S2      
317m0450            VIA   -    MD0100PA00X+015024Y+027794X0200Y         S0      
327m0450            R804  -2          A12X+015452Y+024263X0198Y0197     S2      
327m0450            U15   -1          A01X+015544Y+027371X0130Y0460     S1      
327m0451            VIA   -    M      A12X+014095Y+039005X0260Y         S2      
317m0451            VIA   -    MD0100PA00X+024792Y+031640X0200Y         S0      
327m0451            R799  -1          A01X+024294Y+026154X0198Y0197R270 S1      
327m0451            R728  -1          A12X+014568Y+039200X0198Y0197R180 S2      
317m0451            VIA   -    MD0100PA00X+013940Y+039246X0200Y    R090 S0      
317m0451            VIA   -    MD0100PA00X+023667Y+039455X0200Y         S0      
317m0451            VIA   -    MD0100PA00X+024294Y+026850X0200Y         S0      
317m0452            VIA   -    MD0100PA00X+007215Y+020481X0200Y         S0      
327m0452            U5    -AC15       A01X+021140Y+022430X0160Y    R180 S1      
317m0452            VIA   -    MD0100PA00X+020984Y+022585X0180Y         S0      
317m0452            VIA   -    MD0100PA00X+007877Y+029071X0200Y         S0      
327m0452            R821  -2   M      A12X+015675Y+033016X0198Y0197R180 S2      
327m0452            R430  -2   M      A12X+015675Y+032613X0198Y0197R180 S2      
327m0452            U11   -1          A12X+016208Y+033644X0400Y0500R180 S2      
317m0452            VIA   -    MD0100PA00X+015500Y+032110X0200Y         S0      
317m0452            VIA   -    M      A01X+011741Y+038135X0200Y         S2      
017m0452            VIA   -    M      A12X+011741Y+038135X0260Y         S2      
017m0452                  -    MD0100PA00X+011741Y+038135                       
327m0452            U25   -L13        A01X+007031Y+037633X0160Y    R180 S1      
317m0452            VIA   -    MD0100PA00X+006876Y+037788X0180Y         S0      
327PGPPA_BMC_AUX    R117  -1          A12X+025025Y+027676X0198Y0197R180 S2      
327PGPPA_BMC_AUX    R115  -1          A01X+025401Y+042364X0198Y0197R090 S1      
327PGPPA_BMC_AUX    VIA   -    M      A01X+025180Y+041660X0300Y         S1      
317PGPPA_BMC_AUX    VIA   -    MD0100PA00X+023686Y+040730X0200Y         S0      
327PGPPA_BMC_AUX    R116  -1          A01X+024687Y+025736X0198Y0197     S1      
327PGPPA_BMC_AUX    C224  -1   M      A01X+025024Y+026840X0198Y0197     S1      
327PGPPA_BMC_AUX    U5    -W15        A01X+021140Y+021170X0160Y    R180 S1      
327PGPPA_BMC_AUX    C96   -1          A12X+021033Y+021548X0198Y0197R270 S2      
327PGPPA_BMC_AUX    R797  -1          A12X+023647Y+028391X0198Y0197     S2      
327PGPPA_BMC_AUX    VIA   -           A12X+024128Y+027465X0260Y         S2      
317PGPPA_BMC_AUX    VIA   -    MD0100PA00X+020984Y+021325X0180Y         S0      
317PGPPA_BMC_AUX    VIA   -    MD0100PA00X+025029Y+027358X0200Y         S0      
327PGPPA_BMC_AUX    L17   -2   M      A01X+024771Y+026349X0280Y0320R090 S1      
327JTAG_SCM_TMS     R511  -1          A01X+025738Y+009510X0198Y0197R180 S1      
317JTAG_SCM_TMS     VIA   -    MD0100PA00X+025989Y+009007X0200Y         S0      
327JTAG_SCM_TMS     U5    -A9         A01X+023030Y+015500X0160Y    R180 S1      
317JTAG_SCM_TMS     VIA   -    M      A01X+023238Y+014888X0200Y         S2      
017JTAG_SCM_TMS     VIA   -    M      A12X+023238Y+014888X0260Y         S2      
017JTAG_SCM_TMS           -    MD0100PA00X+023238Y+014888                       
327JTAG_SCM_TMS     R203  -2          A01X+023766Y+013794X0198Y0197R090 S1      
327JTAG_SCM_TDO     U5    -C9         A01X+023030Y+016130X0160Y    R180 S1      
327JTAG_SCM_TDO     VIA   -    M      A12X+023962Y+015406X0260Y         S2      
317JTAG_SCM_TDO     VIA   -    MD0100PA00X+023185Y+015975X0180Y    R180 S0      
327JTAG_SCM_TDO     R523  -2          A12X+025633Y+012310X0198Y0197R270 S2      
317JTAG_SCM_TDO     VIA   -    MD0100PA00X+027640Y+009230X0200Y         S0      
327JTAG_SCM_TDO     R513  -1          A01X+027680Y+009935X0198Y0197R180 S1      
327JTAG_SCM_TDI     VIA   -    M      A12X+026180Y+010730X0280Y         S2      
327JTAG_SCM_TDI     R204  -2          A12X+025610Y+011002X0198Y0197R090 S2      
317JTAG_SCM_TDI     VIA   -    MD0100PA00X+026097Y+009860X0200Y         S0      
327JTAG_SCM_TDI     R512  -1          A01X+025738Y+009860X0198Y0197R180 S1      
327JTAG_SCM_TDI     U5    -D9         A01X+023030Y+016445X0160Y    R180 S1      
317JTAG_SCM_TDI     VIA   -    MD0100PA00X+023185Y+016290X0180Y    R180 S0      
327JTAG_SCM_TCK     VIA   -           A12X+026170Y+011470X0280Y         S2      
317JTAG_SCM_TCK     VIA   -    MD0100PA00X+026580Y+010604X0200Y         S0      
327JTAG_SCM_TCK     R510  -1          A01X+026980Y+010548X0198Y0197R270 S1      
327JTAG_SCM_TCK     R834  -2          A01X+024600Y+012308X0198Y0197R090 S1      
327JTAG_SCM_TCK     R202  -2   M      A01X+024220Y+012308X0198Y0197R090 S1      
327JTAG_SCM_TCK     U5    -B9         A01X+023030Y+015816X0160Y    R180 S1      
317JTAG_SCM_TCK     VIA   -    MD0100PA00X+023185Y+015660X0180Y         S0      
327JTAG_MB_TDO      VIA   -    M      A12X+014118Y+042690X0260Y         S2      
327JTAG_MB_TDO      GF1   -A37        A12X+015140Y+046559X0150Y0680R180 S2      
327JTAG_MB_TDO      R224  -2          A12X+014200Y+042032X0198Y0197R270 S2      
327JTAG_MB_TDO      R230  -2   M      A12X+013800Y+042032X0198Y0197R270 S2      
327JTAG_MB_TDI      GF1   -A36        A12X+015376Y+046559X0150Y0680R180 S2      
327JTAG_MB_TDI      R639  -2          A01X+020863Y+013479X0198Y0197R270 S1      
327JTAG_MB_TDI      R226  -2   M      A12X+014600Y+042032X0198Y0197R270 S2      
327JTAG_MB_TDI      VIA   -    M      A12X+014600Y+042990X0260Y         S2      
317JTAG_MB_TDI      VIA   -    MD0100PA00X+014060Y+041230X0200Y         S0      
317JTAG_MB_TDI      VIA   -    MD0100PA00X+020863Y+013239X0200Y         S0      
317JTAG_MB_TDI      VIA   -    MD0100PA00X+002520Y+042533X0200Y         S0      
327m0453            R224  -1          A12X+014200Y+041718X0198Y0197R270 S2      
317m0453            VIA   -    MD0100PA00X+014300Y+041460X0200Y         S0      
317m0453            VIA   -    MD0100PA00X+012434Y+020474X0200Y         S0      
327m0453            R398  -2          A12X+013402Y+019560X0198Y0197     S2      
317m0453            VIA   -    M      A01X+003300Y+031870X0200Y         S2      
017m0453            VIA   -    M      A12X+003300Y+031870X0260Y         S2      
017m0453                  -    MD0100PA00X+003300Y+031870                       
317m0453            VIA   -    MD0100PA00X+004795Y+020100X0200Y         S0      
327m0454            R445  -1          A01X+010050Y+040608X0198Y0197R270 S1      
317m0454            VIA   -    MD0100PA00X+010046Y+040910X0200Y         S0      
317m0454            VIA   -    MD0100PA00X+021739Y+040134X0200Y         S0      
317m0454            VIA   -    MD0100PA00X+012450Y+042400X0200Y         S0      
317m0454            VIA   -    M      A01X+021403Y+026148X0300Y         S1      
017m0454            VIA   -    M      A12X+021403Y+026148X0200Y         S1      
017m0454                  -    MD0100PA00X+021403Y+026148                       
327m0454            R38   -2   M      A12X+020850Y+026198X0198Y0197R270 S2      
327m0454            R407  -2          A12X+020400Y+026102X0198Y0197R090 S2      
327m0455            R518  -1          A01X+004050Y+038858X0198Y0197R270 S1      
317m0455            J7    -4    D0410PA00X+002382Y+037915X0610Y         S3      
317m0456            VIA   -    MD0100PA00X+025120Y+009380X0200Y         S0      
327m0456            R511  -2          A01X+025422Y+009510X0198Y0197R180 S1      
317m0456            VIA   -    M      A01X+008100Y+032190X0200Y         S2      
017m0456            VIA   -    M      A12X+008100Y+032190X0260Y         S2      
017m0456                  -    MD0100PA00X+008100Y+032190                       
317m0456            VIA   -    MD0100PA00X+003780Y+037122X0200Y         S0      
327m0456            R515  -1          A01X+004050Y+037092X0198Y0197R090 S1      
317m0456            VIA   -    MD0100PA00X+007870Y+034000X0200Y         S0      
327m0456            U25   -B8         A01X+008606Y+034798X0160Y    R180 S1      
327m0457            R513  -2          A01X+027364Y+009935X0198Y0197R180 S1      
317m0457            VIA   -    MD0100PA00X+027340Y+009280X0200Y         S0      
317m0457            VIA   -    MD0100PA00X+006899Y+026046X0200Y         S0      
317m0457            VIA   -    MD0100PA00X+003707Y+039834X0200Y         S0      
327m0457            R517  -1          A01X+004050Y+039942X0198Y0197R090 S1      
317m0457            VIA   -    MD0100PA00X+009392Y+034957X0180Y         S0      
327m0457            U25   -C6         A01X+009236Y+035113X0160Y    R180 S1      
317m0457            VIA   -    M      A01X+009270Y+032322X0200Y         S2      
017m0457            VIA   -    M      A12X+009270Y+032322X0260Y         S2      
017m0457                  -    MD0100PA00X+009270Y+032322                       
317m0458            VIA   -    M      A01X+009999Y+030790X0200Y         S2      
017m0458            VIA   -    M      A12X+009999Y+030790X0260Y         S2      
017m0458                  -    MD0100PA00X+009999Y+030790                       
327m0458            R516  -1          A01X+004050Y+039558X0198Y0197R270 S1      
317m0458            VIA   -    MD0100PA00X+003691Y+039492X0200Y         S0      
317m0458            VIA   -    MD0100PA00X+009506Y+032762X0200Y         S0      
327m0458            U25   -A6         A01X+009236Y+034483X0160Y    R180 S1      
327m0458            R512  -2          A01X+025422Y+009860X0198Y0197R180 S1      
317m0458            VIA   -    MD0100PA00X+025190Y+010010X0200Y         S0      
317m0458            VIA   -    MD0100PA00X+007587Y+029070X0200Y         S0      
327m0459            VIA   -           A12X+025490Y+009250X0260Y         S2      
327m0459            R510  -2          A01X+026980Y+010232X0198Y0197R270 S1      
317m0459            VIA   -    MD0100PA00X+006576Y+025604X0200Y         S0      
317m0459            VIA   -    MD0100PA00X+008550Y+032670X0200Y         S0      
327m0459            U25   -A7         A01X+008921Y+034483X0160Y    R180 S1      
317m0459            VIA   -    MD0100PA00X+003590Y+036302X0200Y         S0      
327m0459            R285  -1   M      A01X+004050Y+036392X0198Y0197R090 S1      
327m0459            R514  -1          A01X+004050Y+036008X0198Y0197R270 S1      
317m0459            VIA   -    MD0100PA00X+025690Y+008730X0200Y         S0      
327m0460            R507  -1          A01X+024742Y+032200X0198Y0197     S1      
327m0460            VIA   -    M      A01X+023790Y+032430X0300Y    R270 S1      
327m0460            R509  -1          A01X+023638Y+031940X0198Y0197R180 S1      
327m0460            R508  -2   M      A01X+024358Y+031931X0198Y0197     S1      
327m0461            R397  -2          A12X+006810Y+032792X0198Y0197R090 S2      
327m0461            VIA   -    M      A01X+022830Y+031940X0300Y    R270 S1      
317m0461            VIA   -    MD0100PA00X+006850Y+032510X0200Y         S0      
317m0461            VIA   -    MD0100PA00X+003160Y+037960X0200Y         S0      
327m0461            R518  -2          A01X+004050Y+038542X0198Y0197R270 S1      
327m0461            R509  -2          A01X+023322Y+031940X0198Y0197R180 S1      
317m0461            VIA   -    MD0100PA00X+022610Y+032506X0200Y         S0      
317m0462            J7    -6    D0410PA00X+002382Y+035915X0610Y         S3      
327m0462            R515  -2          A01X+004050Y+037408X0198Y0197R090 S1      
327m0463            R517  -2          A01X+004050Y+040258X0198Y0197R090 S1      
317m0463            J7    -2    D0410PA00X+002382Y+039915X0610Y         S3      
317m0464            J7    -3    D0410PA00X+002382Y+038915X0610Y         S3      
327m0464            R516  -2          A01X+004050Y+039242X0198Y0197R270 S1      
317m0465            VIA   -    MD0100PA00X+003740Y+035990X0200Y         S0      
317m0465            J7    -8    D0410PA00X+002382Y+033915X0610Y         S3      
327m0465            R514  -2          A01X+004050Y+035692X0198Y0197R270 S1      
327m0466            R505  -2          A01X+022665Y+037938X0198Y0197R090 S1      
327m0466            J5    -9          A01X+023855Y+037345X0240Y0650R090 S1      
327m0467            R767  -1          A12X+011937Y+035186X0198Y0197R090 S2      
327m0467            VIA   -    M      A12X+012220Y+035640X0260Y         S2      
317m0467            VIA   -    MD0100PA00X+012120Y+035920X0200Y         S0      
317m0467            VIA   -    MD0100PA00X+022671Y+036482X0200Y         S0      
327m0467            J5    -8          A01X+023855Y+036951X0240Y0650R090 S1      
327m0467            R464  -2   M      A01X+022672Y+037240X0198Y0197     S1      
327m0467            U5    -AC22       A01X+018935Y+022430X0160Y    R180 S1      
317m0467            VIA   -    MD0100PA00X+019094Y+022270X0180Y         S0      
327V_VGAVS_R        VIA   -    M      A01X+021481Y+014270X0300Y         S1      
327V_VGAVS_R        U5    -C14        A01X+021455Y+016130X0160Y    R180 S1      
327V_VGAVS_R        R20   -1          A01X+021276Y+013794X0198Y0197R270 S1      
327V_VGAVS_BUF_R    U26   -4          A12X+016845Y+001974X0240Y0240R270 S2      
327V_VGAVS_BUF_R    VIA   -    M      A12X+016500Y+002450X0260Y         S2      
327V_VGAVS_BUF_R    R84   -1          A12X+016950Y+002442X0198Y0197R270 S2      
327V_VGAVS_BUF      U34   -6   M      A01X+012347Y+010894X0100Y0250R270 S1      
327V_VGAVS_BUF      U34   -5   M      A01X+012653Y+010894X0100Y0250R270 S1      
327V_VGAVS_BUF      C212  -1          A12X+011648Y+010930X0198Y0197     S2      
327V_VGAVS_BUF      VIA   -    M      A12X+016950Y+003200X0260Y         S2      
327V_VGAVS_BUF      R84   -2          A12X+016950Y+002758X0198Y0197R270 S2      
317V_VGAVS_BUF      VIA   -    MD0100PA00X+014110Y+008650X0200Y         S0      
317V_VGAVS_BUF      VIA   -    MD0100PA00X+012072Y+010894X0200Y         S0      
327V_VGAVS_BUF      J8    -7          A01X+013632Y+010087X0240Y0610R270 S1      
327V_VGAVS          U26   -2          A12X+017140Y+001266X0160Y0240R180 S2      
327V_VGAVS          VIA   -    M      A12X+018450Y+001550X0260Y         S2      
327V_VGAVS          R20   -2          A01X+021276Y+013479X0198Y0197R270 S1      
317V_VGAVS          VIA   -    MD0100PA00X+021273Y+012965X0200Y         S0      
317V_VGAVS          VIA   -    MD0100PA00X+017570Y+007624X0200Y         S0      
327V_VGAHS_R        U5    -B14        A01X+021455Y+015816X0160Y    R180 S1      
327V_VGAHS_R        R19   -1          A01X+022128Y+013794X0198Y0197R270 S1      
327V_VGAHS_BUF_R    U33   -4          A12X+014795Y+001974X0240Y0240R270 S2      
327V_VGAHS_BUF_R    VIA   -    M      A12X+015100Y+002492X0260Y         S2      
327V_VGAHS_BUF_R    R85   -1          A12X+015550Y+002492X0198Y0197R270 S2      
327V_VGAHS_BUF      U34   -7          A01X+012347Y+010697X0100Y0250R270 S1      
327V_VGAHS_BUF      U34   -4   M      A01X+012653Y+010697X0100Y0250R270 S1      
327V_VGAHS_BUF      C211  -1   M      A12X+013972Y+007870X0198Y0197R180 S2      
317V_VGAHS_BUF      VIA   -    MD0100PA00X+014240Y+009130X0200Y         S0      
327V_VGAHS_BUF      VIA   -    M      A12X+014620Y+002808X0260Y         S2      
327V_VGAHS_BUF      J8    -9   M      A01X+013632Y+009299X0240Y0610R270 S1      
327V_VGAHS_BUF      R85   -2          A12X+015550Y+002808X0198Y0197R270 S2      
327V_VGAHS          U33   -2          A12X+015090Y+001266X0160Y0240R180 S2      
327V_VGAHS          VIA   -    M      A12X+019050Y+001800X0260Y         S2      
327V_VGAHS          R19   -2          A01X+022128Y+013479X0198Y0197R270 S1      
317V_VGAHS          VIA   -    MD0100PA00X+022128Y+013229X0200Y         S0      
317V_VGAHS          VIA   -    MD0100PA00X+017820Y+007614X0200Y         S0      
327V_DACR_R         U5    -AF21       A01X+019250Y+023374X0160Y    R180 S1      
327V_DACR_R         R26   -1          A01X+018335Y+025920X0198Y0197R090 S1      
327V_DACR_R         R25   -1   M      A01X+018341Y+025329X0198Y0197R270 S1      
327V_DACR_IO        L30   -2   M      A01X+011810Y+012850X0280Y0320R270 S1      
327V_DACR_IO        VIA   -    M      A12X+011899Y+012854X0260Y         S2      
327V_DACR_IO        C208  -1          A12X+012350Y+012808X0198Y0197R090 S2      
317V_DACR_IO        VIA   -    MD0100PA00X+011899Y+013158X0200Y         S0      
327V_DACR_IO        R89   -1          A01X+012342Y+013100X0198Y0197     S1      
327V_DACR_IO        J8    -1          A01X+013632Y+012449X0240Y0610R270 S1      
327V_DACR_IO        U35   -7   M      A01X+012347Y+012447X0100Y0250R270 S1      
327V_DACR_IO        U35   -4   M      A01X+012653Y+012447X0100Y0250R270 S1      
327V_DACR           L30   -1          A01X+011230Y+012850X0280Y0320R270 S1      
317V_DACR           VIA   -    M      A01X+011160Y+026273X0200Y    R090 S2      
017V_DACR           VIA   -    M      A12X+011160Y+026273X0260Y    R090 S2      
017V_DACR                 -    MD0100PA00X+011160Y+026273                       
327V_DACR           R26   -2          A01X+018335Y+026236X0198Y0197R090 S1      
317V_DACR           VIA   -    MD0100PA00X+018420Y+026490X0200Y         S0      
327V_DACR           C205  -1          A12X+011250Y+012908X0198Y0197R090 S2      
317V_DACR           VIA   -    MD0100PA00X+010920Y+012850X0200Y         S0      
327V_DACG_R         VIA   -    M      A01X+018350Y+024550X0300Y         S1      
327V_DACG_R         U5    -AE21       A01X+019250Y+023060X0160Y    R180 S1      
327V_DACG_R         R21   -1          A01X+017817Y+025795X0198Y0197R090 S1      
327V_DACG_R         R23   -1   M      A01X+017741Y+025259X0198Y0197R270 S1      
327V_DACG_IO        L29   -2   M      A01X+011810Y+011850X0280Y0320R270 S1      
327V_DACG_IO        C209  -1          A12X+012550Y+011792X0198Y0197R270 S2      
317V_DACG_IO        VIA   -    M      A01X+012050Y+011552X0200Y         S2      
017V_DACG_IO        VIA   -    M      A12X+012050Y+011552X0260Y         S2      
017V_DACG_IO              -    MD0100PA00X+012050Y+011552                       
327V_DACG_IO        J8    -3          A01X+013632Y+011661X0240Y0610R270 S1      
327V_DACG_IO        R88   -1          A01X+011758Y+012350X0198Y0197R180 S1      
327V_DACG_IO        U35   -9   M      A01X+012347Y+012053X0100Y0250R270 S1      
327V_DACG_IO        U35   -2   M      A01X+012653Y+012053X0100Y0250R270 S1      
327V_DACG           L29   -1          A01X+011230Y+011850X0280Y0320R270 S1      
327V_DACG           R21   -2          A01X+017817Y+026110X0198Y0197R090 S1      
317V_DACG           VIA   -    M      A01X+018046Y+025882X0200Y    R180 S2      
017V_DACG           VIA   -    M      A12X+018046Y+025882X0260Y    R180 S2      
017V_DACG                 -    MD0100PA00X+018046Y+025882                       
317V_DACG           VIA   -    MD0100PA00X+010920Y+011850X0200Y         S0      
327V_DACG           C206  -1          A12X+011160Y+011795X0198Y0197R270 S2      
317V_DACG           VIA   -    MD0100PA00X+010980Y+026493X0200Y         S0      
327V_DACB_R         R22   -1          A12X+017360Y+024252X0198Y0197R270 S2      
327V_DACB_R         U5    -AD21       A01X+019250Y+022745X0160Y    R180 S1      
317V_DACB_R         VIA   -    MD0100PA00X+018779Y+022900X0180Y         S0      
327V_DACB_R         R24   -1   M      A12X+017750Y+024252X0198Y0197R270 S2      
327V_DACB_IO        L28   -2          A01X+011810Y+011230X0280Y0320R270 S1      
327V_DACB_IO        C210  -1          A12X+012950Y+011642X0198Y0197R270 S2      
317V_DACB_IO        VIA   -    M      A01X+012332Y+011100X0200Y         S2      
017V_DACB_IO        VIA   -    M      A12X+012332Y+011100X0260Y         S2      
017V_DACB_IO              -    MD0100PA00X+012332Y+011100                       
327V_DACB_IO        J8    -5          A01X+013632Y+010874X0240Y0610R270 S1      
327V_DACB_IO        R87   -1   M      A01X+012342Y+011400X0198Y0197     S1      
327V_DACB_IO        U35   -10  M      A01X+012347Y+011856X0100Y0250R270 S1      
327V_DACB_IO        U35   -1   M      A01X+012653Y+011856X0100Y0250R270 S1      
327V_DACB           L28   -1          A01X+011230Y+011230X0280Y0320R270 S1      
317V_DACB           VIA   -    MD0100PA00X+010935Y+011550X0200Y         S0      
327V_DACB           C207  -1          A12X+011560Y+011795X0198Y0197R270 S2      
317V_DACB           VIA   -    MD0100PA00X+010720Y+026500X0200Y         S0      
327V_DACB           VIA   -    M      A12X+017975Y+025015X0260Y         S2      
327V_DACB           R24   -2          A12X+017750Y+024568X0198Y0197R270 S2      
317V_DACB           VIA   -    MD0100PA00X+017985Y+025515X0200Y         S0      
327m0468            U34   -9   M      A01X+012347Y+010303X0100Y0250R270 S1      
327m0468            U34   -2   M      A01X+012653Y+010303X0100Y0250R270 S1      
327m0468            VIA   -    M      A01X+010503Y+009630X0300Y         S1      
327m0468            J8    -11         A01X+013632Y+008512X0240Y0610R270 S1      
327m0468            C213  -1   M      A01X+011108Y+010750X0198Y0197R180 S1      
327m0468            R17   -1   M      A01X+011818Y+010760X0198Y0197R180 S1      
327m0468            R29   -2          A01X+010280Y+008808X0198Y0197R090 S1      
327m0469            Q2    -6          A01X+011376Y+007444X0170Y0200R270 S1      
317m0469            VIA   -    M      A01X+010450Y+007350X0200Y         S2      
017m0469            VIA   -    M      A12X+010450Y+007350X0260Y         S2      
017m0469                  -    MD0100PA00X+010450Y+007350                       
327m0469            R29   -1   M      A01X+010280Y+008492X0198Y0197R090 S1      
327m0469            R91   -2          A01X+010680Y+008492X0198Y0197R270 S1      
327m0470            U34   -10  M      A01X+012347Y+010106X0100Y0250R270 S1      
327m0470            U34   -1   M      A01X+012653Y+010106X0100Y0250R270 S1      
327m0470            R28   -2          A12X+013240Y+009148X0198Y0197R270 S2      
317m0470            VIA   -    MD0100PA00X+012950Y+009148X0200Y         S0      
317m0470            VIA   -    M      A01X+011108Y+010460X0200Y         S2      
017m0470            VIA   -    M      A12X+011108Y+010460X0260Y         S2      
017m0470                  -    MD0100PA00X+011108Y+010460                       
327m0470            C214  -1   M      A01X+011108Y+010200X0198Y0197R180 S1      
327m0470            R16   -1   M      A01X+011818Y+010200X0198Y0197R180 S1      
327m0470            J8    -12         A01X+013632Y+008118X0240Y0610R270 S1      
327m0471            Q2    -3          A01X+012124Y+007956X0170Y0200R270 S1      
327m0471            VIA   -    M      A12X+013300Y+007890X0260Y         S2      
327m0471            R28   -1          A12X+013240Y+008832X0198Y0197R270 S2      
327m0471            R92   -2   M      A12X+013232Y+008430X0198Y0197     S2      
317m0471            VIA   -    MD0100PA00X+012374Y+007979X0200Y         S0      
327V_BMC_DDC_SDA    Q2    -1          A01X+012124Y+007444X0170Y0200R270 S1      
317V_BMC_DDC_SDA    VIA   -    M      A01X+014510Y+008740X0200Y         S2      
017V_BMC_DDC_SDA    VIA   -    M      A12X+014510Y+008740X0260Y         S2      
017V_BMC_DDC_SDA          -    MD0100PA00X+014510Y+008740                       
327V_BMC_DDC_SDA    U5    -A8         A01X+023344Y+015500X0160Y    R180 S1      
317V_BMC_DDC_SDA    VIA   -    MD0100PA00X+023500Y+015345X0180Y         S0      
317V_BMC_DDC_SDA    VIA   -    MD0100PA00X+013147Y+008126X0200Y         S0      
327V_BMC_DDC_SDA    R31   -2   M      A01X+012620Y+007942X0198Y0197R270 S1      
327V_BMC_DDC_SCL    Q2    -4   M      A01X+011376Y+007956X0170Y0200R270 S1      
327V_BMC_DDC_SCL    U5    -B8         A01X+023344Y+015816X0160Y    R180 S1      
317V_BMC_DDC_SCL    VIA   -    MD0100PA00X+023500Y+015660X0180Y    R180 S2      
317V_BMC_DDC_SCL    VIA   -    MD0100PA00X+012930Y+008265X0200Y         S0      
327V_BMC_DDC_SCL    R32   -2          A01X+010758Y+008000X0198Y0197     S1      
327m0472            R86   -2          A12X+010604Y+007857X0198Y0197R180 S2      
327m0472            Q2    -5   M      A01X+011376Y+007700X0170Y0200R270 S1      
327m0472            Q2    -2          A01X+012124Y+007700X0170Y0200R270 S1      
317m0472            VIA   -    M      A01X+011100Y+007700X0200Y         S2      
017m0472            VIA   -    M      A12X+011100Y+007700X0260Y         S2      
017m0472                  -    MD0100PA00X+011100Y+007700                       
327m0473            R384  -2          A01X+018292Y+009200X0198Y0197R180 S1      
317m0473            VIA   -    MD0100PA00X+005862Y+040878X0200Y         S0      
317m0473            VIA   -    M      A01X+011920Y+038970X0200Y         S2      
017m0473            VIA   -    M      A12X+011920Y+038970X0260Y         S2      
017m0473                  -    MD0100PA00X+011920Y+038970                       
317m0473            VIA   -    MD0100PA00X+014128Y+025631X0200Y         S0      
327m0473            U5    -AB25       A01X+017990Y+022115X0160Y    R180 S1      
317m0473            VIA   -    MD0100PA00X+017990Y+009130X0200Y         S0      
327m0473            U25   -L16        A01X+006086Y+037633X0160Y    R180 S1      
317m0473            VIA   -    MD0100PA00X+002630Y+037440X0200Y         S0      
327USB_OC0_REAR_N   R384  -1          A01X+018608Y+009200X0198Y0197R180 S1      
327USB_OC0_REAR_N   VIA   -    M      A01X+019110Y+009607X0300Y         S1      
327USB_OC0_REAR_N   U10   -4          A01X+019711Y+009607X0240Y0380R270 S1      
327USB_OC0_REAR_N   R383  -2   M      A01X+018608Y+009600X0198Y0197     S1      
327USB_OC0_ILIM     VIA   -    M      A01X+019091Y+009031X0300Y         S1      
327USB_OC0_ILIM     U10   -5          A01X+019711Y+009233X0240Y0380R270 S1      
327USB_OC0_ILIM     R378  -1          A01X+018608Y+008800X0198Y0197R180 S1      
327USB_OC0_EN       VIA   -    M      A01X+020620Y+010220X0300Y         S1      
327USB_OC0_EN       R376  -2   M      A01X+021434Y+010201X0198Y0197R180 S1      
327USB_OC0_EN       R377  -1          A01X+021434Y+009798X0198Y0197     S1      
327USB_OC0_EN       U10   -3          A01X+020597Y+009607X0240Y0380R270 S1      
317USB_FPNL_DP      VIA   -    MD0100PA00X+008549Y+044808X0200Y         S0      
327USB_FPNL_DP      GF1   -B56        A01X+008955Y+046559X0150Y0680R180 S1      
317USB_FPNL_DP      VIA   -    MD0100PA00X+010219Y+006322X0200Y    R090 S0      
327USB_FPNL_DP      R386  -1   M      A01X+010973Y+006296X0198Y0197     S1      
327USB_FPNL_DP      L23   -1   M      A01X+010797Y+006330X0140Y0360R090 S1      
317USB_FPNL_DN      VIA   -    MD0100PA00X+008199Y+044808X0200Y         S0      
327USB_FPNL_DN      GF1   -B57        A01X+008718Y+046559X0150Y0680R180 S1      
317USB_FPNL_DN      VIA   -    MD0100PA00X+010219Y+006672X0200Y    R090 S0      
327USB_FPNL_DN      L23   -4   M      A01X+010797Y+006665X0140Y0360R090 S1      
327USB_FPNL_DN      R385  -1   M      A01X+010973Y+006696X0198Y0197     S1      
327USB2_01_F_DP     U38   -2   M      A01X+012858Y+006104X0240Y0280     S1      
327USB2_01_F_DP     L23   -2   M      A01X+011466Y+006330X0140Y0360R090 S1      
327USB2_01_F_DP     R386  -2   M      A01X+011288Y+006296X0198Y0197     S1      
317USB2_01_F_DP     J2    -3    D0280PA00X+017292Y+005268X0440Y    R090 S3      
327USB2_01_F_DN     U38   -3   M      A01X+012858Y+006891X0240Y0280     S1      
327USB2_01_F_DN     R385  -2   M      A01X+011288Y+006696X0198Y0197     S1      
327USB2_01_F_DN     L23   -3   M      A01X+011466Y+006665X0140Y0360R090 S1      
317USB2_01_F_DN     J2    -2    D0280PA00X+016505Y+005268X0440Y    R090 S3      
327m0474            VIA   -           A12X+021922Y+030758X0260Y         S2      
327m0474            U30   -14         A12X+020418Y+031096X0140Y0590R270 S2      
327m0475            VIA   -           A12X+021077Y+031352X0260Y         S2      
327m0475            U30   -13         A12X+020418Y+031352X0140Y0590R270 S2      
327m0476            VIA   -           A12X+021850Y+031880X0260Y         S2      
327m0476            U30   -12         A12X+020418Y+031608X0140Y0590R270 S2      
327TP_ID_BUF        VIA   -           A01X+032800Y+006210X0300Y         S1      
327TP_ID_BUF        U32   -1          A01X+032502Y+006794X0140Y0490R270 S1      
327TP_PWR_BUF       U31   -1          A01X+004292Y+004590X0400Y0150R090 S1      
327TP_ESD_VGA_P4    U35   -6          A01X+012347Y+012644X0100Y0250R270 S1      
327SYS_PWRBTN_N     U15   -4          A01X+016056Y+028129X0130Y0460     S1      
327SYS_PWRBTN_N     R44   -2          A12X+009681Y+042090X0198Y0197R270 S2      
327SYS_PWRBTN_N     GF1   -A47        A12X+011081Y+046559X0150Y0680R180 S2      
327SYS_PWRBTN_N     VIA   -    M      A12X+010655Y+043163X0260Y         S2      
317SYS_PWRBTN_N     VIA   -    MD0100PA00X+010550Y+041820X0200Y         S0      
317SYS_PWRBTN_N     VIA   -    MD0100PA00X+013790Y+039950X0200Y         S0      
317SYS_PWRBTN_N     VIA   -    MD0100PA00X+015875Y+028495X0200Y         S0      
327SW_P5V_AUX_SW    PU38  -20         A01X+002661Y+019165X0120Y0790R180 S1      
327SW_P5V_AUX_SW    PC216 -2          A01X+004032Y+018431X0198Y0197     S1      
327SW_P5V_AUX_SW    PL34  -1          A01X+003526Y+017435X1300Y1300R270 S1      
327SW_P5V_AUX_FLT   PU38  -10         A01X+002898Y+020189X0120Y0790R180 S1      
327SW_P5V_AUX_FLT   PU38  -21         A01X+002898Y+019165X0120Y0790R180 S1      
327SW_P5V_AUX_FLT   PL4   -2          A01X+002990Y+022600X0280Y0320R270 S1      
327SW_P5V_AUX_FLT   PC206 -1          A01X+002750Y+021800X0400Y0500     S1      
327SW_P5V_AUX_FLT   PC207 -1          A01X+002750Y+021100X0400Y0500     S1      
327SW_P5V_AUX_FLT   PC210 -1          A01X+002986Y+018425X0198Y0197     S1      
327SW_P5V_AUX_BST   PU38  -1          A01X+003311Y+019008X0354Y0118R180 S1      
327SW_P5V_AUX_BST   PC216 -1          A01X+003717Y+018431X0198Y0197     S1      
327SW_P3V3_AUX_SW   VIA   -           A01X+002310Y+026430X0260Y         S1      
327SW_P3V3_AUX_SW   PC224 -2          A01X+002772Y+026450X0198Y0197R180 S1      
327SW_P3V3_AUX_SW   PL35  -1          A01X+002826Y+027219X0848Y1300R090 S1      
327SW_P3V3_AUX_SW   PU1   -2          A01X+002874Y+025172X0100Y0360R180 S1      
327SW_P3V3_AUX_SW   PU1   -11         A01X+002874Y+025841X0100Y0360R180 S1      
327m0477            VIA   -           A01X+003810Y+023970X0260Y         S1      
327m0477            C265  -1          A12X+003200Y+024050X0400Y0500R180 S2      
317m0477            VIA   -    MD0100PA00X+003560Y+023820X0200Y         S0      
317m0477            VIA   -    MD0100PA00X+003560Y+024120X0200Y         S0      
327m0477            PC219 -1          A01X+003200Y+023350X0400Y0500     S1      
327m0477            PC218 -1          A01X+003200Y+024050X0400Y0500     S1      
327m0477            PU1   -3          A01X+003070Y+025251X0100Y0520R180 S1      
327m0477            PC223 -1          A01X+003024Y+024611X0198Y0197R180 S1      
327m0477            PL19  -2          A01X+003512Y+022596X0280Y0320R090 S1      
327m0478            R415  -2          A01X+003472Y+026450X0198Y0197R180 S1      
327m0478            PC224 -1          A01X+003088Y+026450X0198Y0197R180 S1      
327SW_P1V2_AUX_SW   PU41  -8          A01X+032183Y+028398X0100Y0590     S1      
327SW_P1V2_AUX_SW   PL31  -1          A01X+032460Y+026824X0848Y1300R270 S1      
327SW_P1V2_AUX_SW   PC254 -2          A01X+032130Y+027594X0198Y0197R180 S1      
327m0479            PU41  -1          A01X+032380Y+028831X0100Y0590     S1      
327m0479            VIA   -           A01X+032810Y+029380X0300Y         S1      
327m0479            PL29  -2          A01X+032600Y+031410X0280Y0320R180 S1      
327m0479            PC251 -1          A01X+032561Y+030768X0440Y0540     S1      
327m0479            PC253 -1          A01X+032323Y+029482X0198Y0197R180 S1      
327m0479            PC252 -1          A01X+032561Y+030023X0440Y0540     S1      
327m0480            PU41  -9          A01X+032380Y+028240X0100Y0280     S1      
327m0480            PC254 -1          A01X+032446Y+027594X0198Y0197R180 S1      
327SW_P1V0_AUX_SW   VIA   -           A01X+007159Y+011825X0300Y    R180 S1      
327SW_P1V0_AUX_SW   PL33  -1          A01X+008334Y+011038X0848Y1300R270 S1      
327SW_P1V0_AUX_SW   PC264 -2          A01X+007799Y+011822X0198Y0197R180 S1      
327SW_P1V0_AUX_SW   PU42  -8          A01X+007606Y+012505X0100Y0590     S1      
327m0481            PL32  -2          A01X+008050Y+015560X0280Y0320R180 S1      
327m0481            VIA   -           A01X+008600Y+014770X0300Y    R180 S1      
327m0481            PC261 -1          A01X+007989Y+014160X0440Y0540     S1      
327m0481            PU42  -1          A01X+007803Y+012938X0100Y0590     S1      
327m0481            PC263 -1          A01X+007759Y+013587X0198Y0197R180 S1      
327m0481            PC262 -1          A01X+007989Y+014909X0440Y0540     S1      
327m0482            PU42  -9          A01X+007803Y+012347X0100Y0280     S1      
327m0482            PC264 -1          A01X+008114Y+011822X0198Y0197R180 S1      
327SPI_TPM_CS_N_R   VIA   -    M      A01X+026820Y+039010X0300Y         S1      
327SPI_TPM_CS_N_R   J5    -5          A01X+025516Y+037936X0240Y0650R270 S1      
327SPI_TPM_CS_N_R   R500  -1          A01X+026689Y+038534X0198Y0197     S1      
327m0483            U30   -7          A12X+018118Y+032120X0140Y0590R270 S2      
317m0483            VIA   -    M      A01X+017080Y+031760X0200Y         S2      
017m0483            VIA   -    M      A12X+017080Y+031760X0260Y         S2      
017m0483                  -    MD0100PA00X+017080Y+031760                       
327m0483            R486  -1          A01X+013998Y+035190X0198Y0197R180 S1      
317m0483            VIA   -    MD0100PA00X+014104Y+035531X0200Y         S0      
327m0484            VIA   -    M      A01X+017980Y+042399X0300Y         S1      
327m0484            U21   -4          A12X+018430Y+040168X0140Y0590R090 S2      
327m0484            R483  -1          A01X+017510Y+042648X0198Y0197R270 S1      
317m0484            VIA   -    MD0100PA00X+019184Y+040400X0200Y    R090 S0      
327m0485            U21   -7          A12X+018430Y+039401X0140Y0590R090 S2      
327m0485            R484  -1          A01X+017303Y+034362X0198Y0197R090 S1      
327m0485            VIA   -    M      A01X+017830Y+034860X0300Y         S1      
317m0485            VIA   -    MD0100PA00X+019010Y+039227X0200Y    R090 S0      
317m0486            VIA   -    M      A01X+016210Y+041400X0200Y    R180 S2      
017m0486            VIA   -    M      A12X+016210Y+041400X0260Y    R180 S2      
017m0486                  -    MD0100PA00X+016210Y+041400                       
327m0486            R482  -1          A01X+014966Y+041925X0198Y0197R180 S1      
327m0486            U30   -4          A12X+018118Y+031352X0140Y0590R270 S2      
317m0486            VIA   -    MD0100PA00X+017653Y+031405X0200Y         S0      
327m0487            VIA   -    M      A12X+018950Y+036890X0260Y         S2      
327m0487            U21   -9          A12X+016130Y+039145X0140Y0590R090 S2      
317m0487            VIA   -    MD0100PA00X+015847Y+034407X0200Y    R180 S0      
327m0487            R485  -1          A01X+016103Y+034362X0198Y0197R090 S1      
327m0488            U30   -9          A12X+020418Y+032376X0140Y0590R270 S2      
327m0488            R481  -1          A01X+014300Y+042258X0198Y0197R270 S1      
317m0488            VIA   -    MD0100PA00X+020863Y+032466X0200Y         S0      
317m0488            VIA   -    M      A01X+019760Y+041540X0200Y         S2      
017m0488            VIA   -    M      A12X+019760Y+041540X0260Y         S2      
017m0488                  -    MD0100PA00X+019760Y+041540                       
317m0488            VIA   -    MD0100PA00X+016054Y+041691X0200Y    R180 S0      
327m0489            J40   -1          A01X+013801Y+036657X0200Y0590     S1      
327m0489            VIA   -    M      A01X+013210Y+034660X0300Y         S1      
327m0489            R486  -2          A01X+013682Y+035190X0198Y0197R180 S1      
327m0489            R492  -2   M      A01X+013682Y+034830X0198Y0197R180 S1      
327m0489            U17   -1   M      A01X+013801Y+036520X0170Y0670     S1      
327m0490            J40   -9          A01X+017301Y+040437X0200Y0590     S1      
327m0490            U17   -9   M      A01X+017301Y+040575X0170Y0670     S1      
327m0490            R483  -2          A01X+017510Y+042332X0198Y0197R270 S1      
327m0490            R488  -2   M      A01X+017128Y+042362X0198Y0197R270 S1      
327m0491            J40   -8          A01X+017301Y+036657X0200Y0590     S1      
327m0491            U17   -8   M      A01X+017301Y+036520X0170Y0670     S1      
327m0491            R484  -2          A01X+017303Y+034677X0198Y0197R090 S1      
327m0492            J40   -15         A01X+014301Y+040437X0200Y0590     S1      
327m0492            U17   -15  M      A01X+014301Y+040575X0170Y0670     S1      
327m0492            R482  -2          A01X+014650Y+041925X0198Y0197R180 S1      
327m0493            J40   -7          A01X+016801Y+036657X0200Y0590     S1      
327m0493            U17   -7   M      A01X+016801Y+036520X0170Y0670     S1      
327m0493            R485  -2          A01X+016103Y+034677X0198Y0197R090 S1      
327m0493            R487  -1   M      A01X+016503Y+034677X0198Y0197R270 S1      
327m0493            R490  -2   M      A01X+016903Y+034677X0198Y0197R090 S1      
327m0494            J40   -16         A01X+013801Y+040437X0200Y0590     S1      
327m0494            U17   -16  M      A01X+013801Y+040575X0170Y0670     S1      
327m0494            R481  -2          A01X+014300Y+041942X0198Y0197R270 S1      
327m0495            R585  -2          A01X+028114Y+009326X0198Y0197R180 S1      
327m0495            R752  -1          A01X+008150Y+017048X0198Y0197R270 S1      
317m0495            VIA   -    MD0100PA00X+009595Y+015290X0200Y         S0      
317m0495            VIA   -    M      A01X+011095Y+008205X0200Y         S2      
017m0495            VIA   -    M      A12X+011095Y+008205X0260Y         S2      
017m0495                  -    MD0100PA00X+011095Y+008205                       
317m0495            VIA   -    MD0100PA00X+027830Y+009502X0200Y         S0      
327m0495            U5    -B7         A01X+023659Y+015816X0160Y    R180 S1      
317m0495            VIA   -    MD0100PA00X+023815Y+015660X0180Y         S0      
327m0496            R679  -1          A12X+018332Y+027920X0198Y0197R180 S2      
317m0496            VIA   -    MD0100PA00X+018362Y+027350X0200Y         S0      
327m0496            R179  -1          A12X+021324Y+023882X0198Y0197R270 S2      
327m0496            U5    -AC14       A01X+021455Y+022430X0160Y    R180 S1      
317m0496            VIA   -    MD0100PA00X+021299Y+022274X0180Y    R270 S0      
327m0497            U5    -AB13       A01X+021770Y+022115X0160Y    R180 S1      
327m0497            VIA   -    M      A12X+021700Y+023380X0260Y         S2      
317m0497            VIA   -    MD0100PA00X+021614Y+022270X0180Y         S0      
327m0497            R680  -1   M      A12X+021720Y+024178X0198Y0197R090 S2      
327m0497            R180  -1          A12X+021990Y+025832X0198Y0197R270 S2      
327SPI_BMC_IO3_R    R682  -1          A01X+020950Y+027292X0198Y0197R090 S1      
327SPI_BMC_IO3_R    U5    -AF12       A01X+022085Y+023374X0160Y    R180 S1      
327SPI_BMC_IO3_R    VIA   -    M      A01X+021300Y+025050X0300Y         S1      
327SPI_BMC_IO2_R    R681  -1          A01X+021820Y+024902X0198Y0197R090 S1      
327SPI_BMC_IO2_R    U5    -AE12       A01X+022085Y+023060X0160Y    R180 S1      
327SPI_BMC_CLK_R    R178  -1          A01X+020791Y+025005X0198Y0197R090 S1      
327SPI_BMC_CLK_R    R678  -1   M      A01X+021072Y+024490X0198Y0197R180 S1      
327SPI_BMC_CLK_R    U5    -AF13       A01X+021770Y+023374X0160Y    R180 S1      
327m0498            R140  -2   M      A01X+022850Y+034788X0198Y0197R090 S1      
327m0498            R94   -1          A01X+024250Y+034358X0198Y0197R270 S1      
327m0498            R550  -2          A01X+015838Y+030100X0198Y0197     S1      
317m0498            VIA   -    M      A01X+016085Y+030134X0200Y         S2      
017m0498            VIA   -    M      A12X+016085Y+030134X0260Y         S2      
017m0498                  -    MD0100PA00X+016085Y+030134                       
317m0498            VIA   -    MD0100PA00X+022100Y+034380X0200Y         S0      
327m0498            R179  -2          A12X+021324Y+024198X0198Y0197R270 S2      
317m0498            VIA   -    MD0100PA00X+018270Y+034222X0200Y         S0      
317m0498            VIA   -    MD0100PA00X+021510Y+024410X0200Y         S0      
317m0498            VIA   -    MD0100PA00X+015846Y+034090X0200Y         S0      
327m0498            VIA   -    M      A01X+023750Y+034300X0300Y    R270 S1      
327m0499            R552  -2          A01X+015838Y+029700X0198Y0197     S1      
327m0499            R164  -1          A01X+023850Y+033508X0198Y0197R270 S1      
327m0499            VIA   -    M      A01X+018850Y+027490X0300Y         S1      
327m0499            R753  -2   M      A01X+022850Y+033508X0198Y0197R090 S1      
317m0499            VIA   -    MD0100PA00X+022565Y+033752X0200Y         S0      
327m0499            R180  -2          A12X+021990Y+026148X0198Y0197R270 S2      
317m0499            VIA   -    MD0100PA00X+021990Y+026710X0200Y         S0      
317m0499            VIA   -    MD0100PA00X+019339Y+026914X0200Y         S0      
327m0500            R547  -2          A12X+023222Y+030690X0198Y0197     S2      
317m0500            VIA   -    M      A01X+022880Y+031210X0200Y         S2      
017m0500            VIA   -    M      A12X+022880Y+031210X0260Y         S2      
017m0500                  -    MD0100PA00X+022880Y+031210                       
327m0500            R802  -1          A12X+022712Y+025300X0198Y0197R090 S2      
317m0500            VIA   -    MD0100PA00X+022732Y+025670X0200Y         S0      
327m0501            R553  -2          A01X+016520Y+032058X0198Y0197R090 S1      
327m0501            VIA   -    M      A01X+018175Y+033730X0300Y    R270 S1      
317m0501            VIA   -    MD0100PA00X+018380Y+034540X0200Y         S0      
327m0501            R801  -1          A12X+022327Y+024098X0198Y0197R090 S2      
317m0501            VIA   -    MD0100PA00X+022100Y+024300X0200Y         S0      
327m0502            R549  -2          A01X+015838Y+030510X0198Y0197     S1      
327m0502            VIA   -    M      A01X+019250Y+027800X0300Y         S1      
327m0502            R699  -2   M      A01X+020558Y+027300X0198Y0197     S1      
327m0502            R178  -2          A01X+020791Y+025320X0198Y0197R090 S1      
317m0503            VIA   -    M      A01X+021638Y+031222X0200Y         S2      
017m0503            VIA   -    M      A12X+021638Y+031222X0260Y         S2      
017m0503                  -    MD0100PA00X+021638Y+031222                       
327m0503            R175  -2          A01X+026130Y+025338X0198Y0197R090 S1      
327m0503            U30   -3          A12X+018118Y+031096X0140Y0590R270 S2      
317m0503            VIA   -    MD0100PA00X+017656Y+031092X0200Y         S0      
327m0504            U21   -6          A12X+018430Y+039657X0140Y0590R090 S2      
327m0504            R176  -2          A12X+023510Y+025488X0198Y0197R270 S2      
317m0504            VIA   -    M      A01X+019766Y+039087X0200Y    R090 S2      
017m0504            VIA   -    M      A12X+019766Y+039087X0260Y    R090 S2      
017m0504                  -    MD0100PA00X+019766Y+039087                       
317m0504            VIA   -    MD0100PA00X+024880Y+038570X0200Y         S0      
317m0504            VIA   -    MD0100PA00X+023770Y+025739X0200Y         S0      
327m0505            U30   -10         A12X+020418Y+032120X0140Y0590R270 S2      
327m0505            R174  -2          A01X+023910Y+025378X0198Y0197R090 S1      
317m0505            VIA   -    MD0100PA00X+023669Y+031122X0200Y         S0      
317m0505            VIA   -    M      A01X+023930Y+026880X0200Y         S2      
017m0505            VIA   -    M      A12X+023930Y+026880X0260Y         S2      
017m0505                  -    MD0100PA00X+023930Y+026880                       
327m0506            U5    -AB9        A01X+023030Y+022115X0160Y    R180 S1      
317m0506            VIA   -    MD0100PA00X+022874Y+022270X0180Y    R270 S2      
317m0506            VIA   -    MD0100PA00X+025863Y+024760X0200Y         S0      
327m0506            R175  -1          A01X+026130Y+025022X0198Y0197R090 S1      
327m0507            R176  -1          A12X+023510Y+025172X0198Y0197R270 S2      
327m0507            U5    -AD9        A01X+023030Y+022745X0160Y    R180 S1      
317m0507            VIA   -    MD0100PA00X+023185Y+022900X0180Y    R180 S0      
327m0508            VIA   -    M      A01X+024110Y+024551X0300Y         S1      
327m0508            R174  -1          A01X+023910Y+025062X0198Y0197R090 S1      
327m0508            U5    -AF8        A01X+023344Y+023374X0160Y    R180 S1      
327m0509            R39   -2          A01X+010150Y+025792X0198Y0197R270 S1      
327m0509            U2    -7          A01X+009732Y+025062X0110Y0280     S1      
327m0509            R742  -2   M      A01X+009730Y+025772X0198Y0197R270 S1      
327UART_BMC_1_TXD   U5    -C13        A01X+021770Y+016130X0160Y    R180 S1      
327UART_BMC_1_TXD   VIA   -           A12X+022301Y+015397X0260Y         S2      
317UART_BMC_1_TXD   VIA   -    MD0100PA00X+021925Y+015975X0180Y    R180 S0      
327UART_BMC_1_TXD   R157  -2          A12X+024361Y+012314X0198Y0197R270 S2      
317m0510            VIA   -    M      A01X+009872Y+023698X0200Y    R090 S2      
017m0510            VIA   -    M      A12X+009872Y+023698X0260Y    R090 S2      
017m0510                  -    MD0100PA00X+009872Y+023698                       
327m0510            U2    -3          A01X+009928Y+023998X0110Y0280     S1      
317m0510            VIA   -    MD0100PA00X+024531Y+011391X0200Y         S0      
327m0510            R157  -1          A12X+024361Y+011999X0198Y0197R270 S2      
317m0510            VIA   -    MD0100PA00X+017655Y+012521X0200Y         S0      
327SPA_SIN_SW_BUF   R726  -2          A12X+008060Y+025482X0198Y0197R090 S2      
327SPA_SIN_SW_BUF   R737  -2          A01X+007958Y+025920X0198Y0197     S1      
327SPA_SIN_SW_BUF   U3    -7          A01X+007542Y+025072X0110Y0280     S1      
317SPA_SIN_SW_BUF   VIA   -    MD0100PA00X+007701Y+025664X0200Y    R090 S0      
327m0511            R421  -1          A12X+026854Y+010470X0198Y0197R180 S2      
327m0511            VIA   -    M      A12X+027822Y+010153X0260Y         S2      
327m0511            U19   -5          A12X+028655Y+010309X0170Y0700R090 S2      
327m0512            R420  -1          A12X+026854Y+010823X0198Y0197R180 S2      
327m0512            U19   -6          A12X+028655Y+010565X0170Y0700R090 S2      
327m0512            VIA   -    M      A12X+026826Y+011279X0260Y         S2      
327m0513            R261  -2          A01X+021019Y+012310X0198Y0197R090 S1      
327m0513            GF1   -A30        A12X+016793Y+046559X0150Y0680R180 S2      
327m0513            R582  -2          A01X+021726Y+013479X0198Y0197R270 S1      
317m0513            VIA   -    MD0100PA00X+021726Y+013229X0200Y         S0      
327m0513            VIA   -    M      A12X+017206Y+043310X0260Y         S2      
317m0513            VIA   -    MD0100PA00X+016786Y+042777X0200Y         S0      
327m0514            VIA   -    M      A12X+017483Y+042785X0260Y         S2      
317m0514            VIA   -    MD0100PA00X+021276Y+012706X0200Y         S0      
327m0514            R260  -2          A12X+021137Y+012310X0198Y0197R270 S2      
327m0514            GF1   -A29        A12X+017030Y+046638X0150Y0840R180 S2      
327m0514            R580  -2          A12X+021450Y+013492X0198Y0197R090 S2      
317m0514            VIA   -    MD0100PA00X+017253Y+042095X0200Y         S0      
327m0515            R582  -1          A01X+021726Y+013794X0198Y0197R270 S1      
327m0515            U5    -A14        A01X+021455Y+015500X0160Y    R180 S1      
327m0515            VIA   -    M      A01X+021980Y+014325X0300Y         S1      
327m0516            U5    -D15        A01X+021140Y+016445X0160Y    R180 S1      
327m0516            VIA   -    M      A12X+021130Y+015110X0260Y         S2      
317m0516            VIA   -    MD0100PA00X+020984Y+016290X0180Y         S0      
327m0516            R580  -1          A12X+021450Y+013808X0198Y0197R090 S2      
327m0517            GF1   -A28        A12X+018608Y+046638X0150Y0840R180 S2      
317m0517            VIA   -    MD0100PA00X+018500Y+045150X0200Y         S0      
317m0517            VIA   -    M      A01X+022604Y+010122X0200Y         S2      
017m0517            VIA   -    M      A12X+022604Y+010122X0260Y         S2      
017m0517                  -    MD0100PA00X+022604Y+010122                       
327m0517            R259  -2          A12X+022334Y+012310X0198Y0197R270 S2      
317m0517            VIA   -    MD0100PA00X+022528Y+012929X0200Y         S0      
327m0517            R147  -2          A12X+022650Y+013492X0198Y0197R090 S2      
327m0518            R258  -2          A12X+021931Y+012310X0198Y0197R270 S2      
327m0518            R146  -2          A12X+022250Y+013492X0198Y0197R090 S2      
317m0518            VIA   -    MD0100PA00X+018630Y+044870X0200Y         S0      
317m0518            VIA   -    MD0100PA00X+023232Y+010123X0200Y         S0      
317m0518            VIA   -    M      A01X+022128Y+012929X0200Y         S2      
017m0518            VIA   -    M      A12X+022128Y+012929X0260Y         S2      
017m0518                  -    MD0100PA00X+022128Y+012929                       
327m0518            GF1   -A27        A12X+018844Y+046559X0150Y0680R180 S2      
327m0519            VIA   -    M      A12X+021960Y+014700X0200Y         S2      
327m0519            U5    -E12        A01X+022085Y+016760X0160Y    R180 S1      
317m0519            VIA   -    MD0100PA00X+022240Y+016605X0180Y    R180 S0      
327m0519            R147  -1          A12X+022650Y+013808X0198Y0197R090 S2      
327m0520            U5    -F13        A01X+021770Y+017075X0160Y    R180 S1      
327m0520            VIA   -    M      A12X+022140Y+014260X0260Y         S2      
317m0520            VIA   -    MD0100PA00X+021925Y+016920X0180Y         S0      
327m0520            R146  -1          A12X+022250Y+013808X0198Y0197R090 S2      
327m0521            R570  -2          A12X+025260Y+012622X0198Y0197R090 S2      
317m0521            VIA   -    MD0100PA00X+018286Y+011371X0200Y         S0      
317m0521            VIA   -    M      A01X+018448Y+042937X0200Y         S2      
017m0521            VIA   -    M      A12X+018448Y+042937X0260Y         S2      
017m0521                  -    MD0100PA00X+018448Y+042937                       
317m0521            VIA   -    MD0100PA00X+025310Y+011990X0200Y         S0      
327m0521            GF1   -A26        A12X+019081Y+046559X0150Y0680R180 S2      
317m0522            VIA   -    M      A01X+018672Y+043249X0300Y         S1      
017m0522            VIA   -    M      A12X+018672Y+043249X0200Y         S1      
017m0522                  -    MD0100PA00X+018672Y+043249                       
327m0522            GF1   -A25        A12X+019317Y+046638X0150Y0840R180 S2      
327m0522            R567  -2          A12X+024584Y+013479X0198Y0197R090 S2      
317m0522            VIA   -    MD0100PA00X+024552Y+013060X0200Y         S0      
317m0522            VIA   -    MD0100PA00X+017160Y+011400X0200Y         S0      
327m0523            R257  -2          A12X+025211Y+011321X0198Y0197R270 S2      
327m0523            R570  -1   M      A12X+025260Y+012938X0198Y0197R090 S2      
317m0523            VIA   -    MD0100PA00X+022555Y+016605X0180Y    R180 S2      
327m0523            U5    -E11        A01X+022400Y+016760X0160Y    R180 S1      
327m0524            R256  -2          A12X+024809Y+011321X0198Y0197R270 S2      
327m0524            R567  -1   M      A12X+024584Y+013794X0198Y0197R090 S2      
327m0524            U5    -D11        A01X+022400Y+016445X0160Y    R180 S1      
327m0524            VIA   -    M      A12X+023912Y+014517X0260Y         S2      
317m0524            VIA   -    MD0100PA00X+022555Y+016290X0180Y    R180 S0      
327m0525            R255  -2          A12X+022737Y+012310X0198Y0197R270 S2      
327m0525            GF1   -A24        A12X+019553Y+046559X0150Y0680R180 S2      
327m0525            R143  -2          A12X+023050Y+013492X0198Y0197R090 S2      
317m0525            VIA   -    MD0100PA00X+018984Y+043491X0200Y         S0      
317m0525            VIA   -    M      A01X+022934Y+012924X0200Y         S2      
017m0525            VIA   -    M      A12X+022934Y+012924X0260Y         S2      
017m0525                  -    MD0100PA00X+022934Y+012924                       
327m0526            R254  -2          A12X+023142Y+012310X0198Y0197R270 S2      
327m0526            GF1   -A23        A12X+019789Y+046559X0150Y0680R180 S2      
317m0526            VIA   -    MD0100PA00X+018977Y+043205X0200Y         S0      
317m0526            VIA   -    M      A01X+023351Y+012959X0300Y         S1      
017m0526            VIA   -    M      A12X+023351Y+012959X0200Y         S1      
017m0526                  -    MD0100PA00X+023351Y+012959                       
327m0526            R142  -2          A12X+023450Y+013512X0198Y0197R090 S2      
327m0527            R143  -1          A12X+023050Y+013808X0198Y0197R090 S2      
327m0527            U5    -E13        A01X+021770Y+016760X0160Y    R180 S1      
327m0527            VIA   -    M      A12X+021863Y+015113X0260Y         S2      
317m0527            VIA   -    MD0100PA00X+021925Y+016605X0180Y    R180 S0      
327m0528            R142  -1          A12X+023450Y+013828X0198Y0197R090 S2      
327m0528            U5    -D12        A01X+022085Y+016445X0160Y    R180 S1      
327m0528            VIA   -    M      A12X+022877Y+014254X0260Y         S2      
317m0528            VIA   -    MD0100PA00X+022240Y+016290X0180Y    R180 S0      
317m0529            VIA   -    M      A01X+013535Y+043302X0200Y         S2      
017m0529            VIA   -    M      A12X+013535Y+043302X0260Y         S2      
017m0529                  -    MD0100PA00X+013535Y+043302                       
327m0529            GF1   -A12        A12X+022388Y+046559X0150Y0680R180 S2      
317m0529            VIA   -    MD0100PA00X+022500Y+043310X0200Y         S0      
317m0529            VIA   -    MD0100PA00X+023450Y+011750X0200Y         S0      
327m0529            R93   -2          A12X+023551Y+011995X0198Y0197R090 S2      
317m0530            VIA   -    MD0100PA00X+022683Y+043517X0200Y         S0      
327m0530            GF1   -A11        A12X+022624Y+046559X0150Y0680R180 S2      
317m0530            VIA   -    M      A01X+012887Y+043307X0200Y         S2      
017m0530            VIA   -    M      A12X+012887Y+043307X0260Y         S2      
017m0530                  -    MD0100PA00X+012887Y+043307                       
327m0530            R71   -2          A01X+022940Y+013479X0198Y0197R270 S1      
317m0530            VIA   -    MD0100PA00X+022940Y+013229X0200Y         S0      
327m0531            VIA   -    M      A12X+023588Y+011500X0260Y         S2      
327m0531            R253  -2          A12X+023642Y+010976X0198Y0197     S2      
327m0531            U5    -C11        A01X+022400Y+016130X0160Y    R180 S1      
317m0531            VIA   -    MD0100PA00X+022555Y+015975X0180Y    R180 S0      
317m0531            VIA   -    MD0100PA00X+023490Y+012610X0200Y         S0      
327m0531            R93   -1   M      A12X+023551Y+012310X0198Y0197R090 S2      
327m0532            R252  -2          A01X+023838Y+012310X0198Y0197R090 S1      
327m0532            R71   -1   M      A01X+022940Y+013794X0198Y0197R270 S1      
327m0532            U5    -A11        A01X+022400Y+015500X0160Y    R180 S1      
327m0532            VIA   -    M      A01X+023340Y+012310X0300Y         S1      
327m0533            R139  -2          A12X+017474Y+013479X0198Y0197R090 S2      
327m0533            R251  -2          A12X+017474Y+012290X0198Y0197R270 S2      
317m0533            VIA   -    M      A01X+017455Y+012873X0200Y         S2      
017m0533            VIA   -    M      A12X+017455Y+012873X0260Y         S2      
017m0533                  -    MD0100PA00X+017455Y+012873                       
317m0533            VIA   -    MD0100PA00X+023520Y+044910X0200Y         S0      
327m0533            GF1   -A10        A12X+022860Y+046559X0150Y0680R180 S2      
327m0534            R138  -2          A12X+017882Y+013479X0198Y0197R090 S2      
327m0534            R250  -2          A12X+017876Y+012290X0198Y0197R270 S2      
317m0534            VIA   -    M      A01X+020522Y+042266X0200Y         S2      
017m0534            VIA   -    M      A12X+020522Y+042266X0260Y         S2      
017m0534                  -    MD0100PA00X+020522Y+042266                       
317m0534            VIA   -    MD0100PA00X+017829Y+012882X0200Y         S0      
317m0534            VIA   -    MD0100PA00X+023125Y+044700X0200Y         S0      
327m0534            GF1   -A9         A12X+023096Y+046559X0150Y0680R180 S2      
327m0535            R139  -1          A12X+017474Y+013794X0198Y0197R090 S2      
327m0535            VIA   -    M      A12X+018175Y+014705X0260Y         S2      
327m0535            U5    -D19        A01X+019880Y+016445X0160Y    R180 S1      
317m0535            VIA   -    MD0100PA00X+019724Y+016290X0180Y         S0      
327m0536            R138  -1          A12X+017882Y+013794X0198Y0197R090 S2      
327m0536            VIA   -    M      A12X+018930Y+014840X0200Y         S2      
327m0536            U5    -C20        A01X+019565Y+016130X0160Y    R180 S1      
317m0536            VIA   -    MD0100PA00X+019409Y+015975X0180Y         S0      
317m0537            VIA   -    M      A01X+019994Y+042370X0200Y         S2      
017m0537            VIA   -    M      A12X+019994Y+042370X0260Y         S2      
017m0537                  -    MD0100PA00X+019994Y+042370                       
327m0537            R249  -2          A01X+019606Y+012310X0198Y0197R090 S1      
327m0537            R590  -2          A01X+019598Y+013479X0198Y0197R270 S1      
317m0537            VIA   -    MD0100PA00X+019598Y+013229X0200Y         S0      
317m0537            VIA   -    MD0100PA00X+023540Y+045160X0200Y         S0      
327m0537            GF1   -A8         A12X+023333Y+046559X0150Y0680R180 S2      
317m0538            VIA   -    M      A01X+018744Y+012962X0200Y         S2      
017m0538            VIA   -    M      A12X+018744Y+012962X0260Y         S2      
017m0538                  -    MD0100PA00X+018744Y+012962                       
327m0538            R248  -2          A12X+018743Y+012306X0198Y0197R270 S2      
327m0538            GF1   -A7         A12X+023569Y+046559X0150Y0680R180 S2      
317m0538            VIA   -    MD0100PA00X+023622Y+045440X0200Y         S0      
327m0538            R589  -2          A12X+018700Y+013492X0198Y0197R090 S2      
327m0539            R590  -1          A01X+019598Y+013794X0198Y0197R270 S1      
327m0539            U5    -A19        A01X+019880Y+015500X0160Y    R180 S1      
327m0540            U5    -C19        A01X+019880Y+016130X0160Y    R180 S1      
317m0540            VIA   -    MD0100PA00X+019724Y+015975X0180Y         S2      
327m0540            R589  -1          A12X+018700Y+013808X0198Y0197R090 S2      
327m0541            R247  -2          A12X+017074Y+012290X0198Y0197R270 S2      
327m0541            GF1   -A6         A12X+023805Y+046638X0150Y0840R180 S2      
327m0541            R394  -2          A12X+017074Y+013479X0198Y0197R090 S2      
317m0541            VIA   -    MD0100PA00X+017087Y+012821X0200Y         S0      
317m0541            VIA   -    MD0100PA00X+023950Y+044775X0200Y         S0      
317m0541            VIA   -    MD0100PA00X+006309Y+006576X0200Y         S0      
327m0541            R409  -2          A12X+006450Y+007208X0198Y0197R270 S2      
327m0542            R246  -2          A12X+016673Y+012290X0198Y0197R270 S2      
327m0542            R455  -1   M      A01X+016440Y+011992X0198Y0197R090 S1      
317m0542            VIA   -    M      A01X+016673Y+012870X0200Y         S2      
017m0542            VIA   -    M      A12X+016673Y+012870X0260Y         S2      
017m0542                  -    MD0100PA00X+016673Y+012870                       
327m0542            R165  -2          A12X+016672Y+013479X0198Y0197R090 S2      
317m0542            VIA   -    MD0100PA00X+007250Y+006650X0200Y         S0      
327m0542            R410  -2          A12X+007250Y+006892X0198Y0197R090 S2      
327m0543            U5    -D20        A01X+019565Y+016445X0160Y    R180 S1      
327m0543            VIA   -    M      A12X+017545Y+014370X0260Y         S2      
317m0543            VIA   -    MD0100PA00X+019409Y+016290X0180Y         S0      
327m0543            R394  -1          A12X+017074Y+013794X0198Y0197R090 S2      
327m0544            U5    -E19        A01X+019880Y+016760X0160Y    R180 S1      
327m0544            VIA   -    M      A12X+017540Y+014900X0260Y         S2      
317m0544            VIA   -    MD0100PA00X+019724Y+016605X0180Y         S0      
327m0544            R165  -1          A12X+016672Y+013794X0198Y0197R090 S2      
327m0545            R245  -2   M      A01X+019140Y+012310X0198Y0197R090 S1      
327m0545            R133  -2          A01X+019200Y+013482X0198Y0197R270 S1      
317m0545            VIA   -    M      A01X+019500Y+042254X0300Y         S1      
017m0545            VIA   -    M      A12X+019500Y+042254X0200Y         S1      
017m0545                  -    MD0100PA00X+019500Y+042254                       
317m0545            VIA   -    MD0100PA00X+018707Y+011680X0200Y         S0      
317m0545            VIA   -    MD0100PA00X+024670Y+045150X0200Y         S0      
327m0545            GF1   -A4         A12X+024278Y+046638X0150Y0840R180 S2      
327m0546            R132  -2          A01X+018800Y+013482X0198Y0197R270 S1      
327m0546            R244  -2   M      A01X+017819Y+012280X0198Y0197R090 S1      
317m0546            VIA   -    M      A01X+019037Y+042249X0200Y         S2      
017m0546            VIA   -    M      A12X+019037Y+042249X0260Y         S2      
017m0546                  -    MD0100PA00X+019037Y+042249                       
317m0546            VIA   -    MD0100PA00X+024670Y+045410X0200Y         S0      
327m0546            GF1   -A3         A12X+024514Y+046638X0150Y0840R180 S2      
317m0546            VIA   -    MD0100PA00X+018200Y+011720X0200Y         S0      
327m0547            R133  -1          A01X+019200Y+013798X0198Y0197R270 S1      
327m0547            U5    -A20        A01X+019565Y+015500X0160Y    R180 S1      
327m0547            VIA   -    M      A01X+019219Y+014271X0300Y         S1      
327m0548            VIA   -    M      A01X+018680Y+014280X0300Y         S1      
327m0548            R132  -1          A01X+018800Y+013798X0198Y0197R270 S1      
327m0548            U5    -B20        A01X+019565Y+015816X0160Y    R180 S1      
327m0549            U5    -K24        A01X+018305Y+018335X0160Y    R180 S1      
327m0549            VIA   -    M      A12X+017144Y+018356X0260Y         S2      
317m0549            VIA   -    MD0100PA00X+018150Y+018180X0180Y         S0      
327m0549            R144  -1          A12X+016680Y+018174X0198Y0197     S2      
327m0550            R137  -1          A01X+015882Y+018735X0198Y0197R180 S1      
327m0550            U5    -L26        A01X+017675Y+018650X0160Y    R180 S1      
327m0550            VIA   -    M      A01X+016488Y+018654X0300Y         S1      
327m0551            R521  -2          A01X+021446Y+012310X0198Y0197R090 S1      
327m0551            GF1   -A32        A12X+016321Y+046638X0150Y0840R180 S2      
327m0551            R584  -2          A01X+022528Y+013479X0198Y0197R270 S1      
317m0551            VIA   -    M      A01X+016550Y+043310X0200Y         S2      
017m0551            VIA   -    M      A12X+016550Y+043310X0260Y         S2      
017m0551                  -    MD0100PA00X+016550Y+043310                       
317m0551            VIA   -    MD0100PA00X+022528Y+013229X0200Y         S0      
317m0552            VIA   -    M      A01X+021726Y+012929X0300Y         S1      
017m0552            VIA   -    M      A12X+021726Y+012929X0200Y         S1      
017m0552                  -    MD0100PA00X+021726Y+012929                       
327m0552            R262  -2          A12X+021529Y+012310X0198Y0197R270 S2      
327m0552            GF1   -A31        A12X+016557Y+046559X0150Y0680R180 S2      
327m0552            R583  -2          A12X+021850Y+013492X0198Y0197R090 S2      
317m0552            VIA   -    MD0100PA00X+016701Y+043072X0200Y         S0      
327m0553            R584  -1          A01X+022528Y+013794X0198Y0197R270 S1      
327m0553            U5    -A13        A01X+021770Y+015500X0160Y    R180 S1      
327m0553            VIA   -    M      A01X+022478Y+014260X0300Y         S1      
327m0554            R583  -1          A12X+021850Y+013808X0198Y0197R090 S2      
317m0554            VIA   -    MD0100PA00X+020984Y+016605X0180Y    R180 S2      
327m0554            U5    -E15        A01X+021140Y+016760X0160Y    R180 S1      
327m0555            R454  -1          A01X+004692Y+034000X0198Y0197     S1      
317m0555            VIA   -    MD0100PA00X+008079Y+019081X0200Y         S0      
317m0555            VIA   -    M      A01X+014450Y+016957X0200Y         S2      
017m0555            VIA   -    M      A12X+014450Y+016957X0260Y         S2      
017m0555                  -    MD0100PA00X+014450Y+016957                       
327m0555            R443  -1          A01X+015612Y+016710X0198Y0197     S1      
327m0555            R269  -2   M      A01X+014837Y+017218X0198Y0197R270 S1      
327m0556            R453  -1          A01X+004692Y+033600X0198Y0197     S1      
327m0556            VIA   -    M      A01X+005880Y+026500X0300Y    R090 S1      
317m0556            VIA   -    MD0100PA00X+005985Y+023583X0200Y         S0      
327m0556            R442  -1          A01X+015552Y+016340X0198Y0197     S1      
327m0556            R268  -2   M      A01X+014840Y+016452X0198Y0197R270 S1      
317m0556            VIA   -    MD0100PA00X+007644Y+016691X0200Y         S0      
317m0557            VIA   -    MD0100PA00X+007160Y+020090X0200Y         S0      
317m0557            VIA   -    MD0100PA00X+005740Y+034540X0200Y         S0      
327m0557            U25   -C15        A01X+006401Y+035113X0160Y    R180 S1      
327m0557            U5    -K23        A01X+018620Y+018335X0160Y    R180 S1      
317m0557            VIA   -    MD0100PA00X+018464Y+018180X0180Y    R180 S2      
327m0557            R267  -2          A12X+015878Y+018558X0198Y0197R180 S2      
327SGPIO_PLD_LD_0   R436  -1          A01X+006490Y+033108X0198Y0197R270 S1      
327SGPIO_PLD_LD_0   U25   -B12        A01X+007346Y+034798X0160Y    R180 S1      
327SGPIO_PLD_DO_0   R435  -1          A12X+006000Y+033108X0198Y0197R090 S2      
327SGPIO_PLD_DO_0   VIA   -    M      A12X+006607Y+033978X0260Y         S2      
317SGPIO_PLD_DO_0   VIA   -    MD0100PA00X+007191Y+034957X0180Y         S0      
327SGPIO_PLD_DO_0   U25   -C12        A01X+007346Y+035113X0160Y    R180 S1      
327SGPIO_PLD_DI_0   R437  -1          A01X+005008Y+032400X0198Y0197R180 S1      
327SGPIO_PLD_DI_0   U25   -B14        A01X+006716Y+034798X0160Y    R180 S1      
327m0558            R434  -1          A01X+005580Y+032792X0198Y0197R090 S1      
327m0558            U25   -A14        A01X+006716Y+034483X0160Y    R180 S1      
327SGPIO_LD_1       R73   -2          A12X+015380Y+042038X0198Y0197R270 S2      
327SGPIO_LD_1       R150  -1          A01X+020000Y+011992X0198Y0197R090 S1      
317SGPIO_LD_1       VIA   -    M      A01X+005095Y+031805X0200Y         S2      
017SGPIO_LD_1       VIA   -    M      A12X+005095Y+031805X0260Y         S2      
017SGPIO_LD_1             -    MD0100PA00X+005095Y+031805                       
317SGPIO_LD_1       VIA   -    MD0100PA00X+019074Y+011446X0200Y         S0      
327SGPIO_LD_1       GF1   -B37        A01X+015140Y+046559X0150Y0680R180 S1      
317SGPIO_LD_1       VIA   -    MD0100PA00X+015140Y+044993X0200Y         S0      
327SGPIO_LD_0       R436  -2          A01X+006490Y+032792X0198Y0197R270 S1      
327SGPIO_LD_0       R77   -2          A12X+011740Y+041988X0198Y0197R270 S2      
327SGPIO_LD_0       VIA   -    M      A12X+011790Y+042598X0260Y         S2      
317SGPIO_LD_0       VIA   -    MD0100PA00X+006300Y+032410X0200Y         S0      
327SGPIO_LD_0       GF1   -B32        A01X+016321Y+046638X0150Y0840R180 S1      
317SGPIO_LD_0       VIA   -    MD0100PA00X+011950Y+043360X0200Y         S0      
317SGPIO_LD_0       VIA   -    MD0100PA00X+015940Y+044941X0200Y         S0      
317SGPIO_DO_1       VIA   -    M      A01X+005280Y+032240X0200Y         S2      
017SGPIO_DO_1       VIA   -    M      A12X+005280Y+032240X0260Y         S2      
017SGPIO_DO_1             -    MD0100PA00X+005280Y+032240                       
327SGPIO_DO_1       R75   -2          A01X+015760Y+042942X0198Y0197R270 S1      
327SGPIO_DO_1       GF1   -B34        A01X+015848Y+046559X0150Y0680R180 S1      
317SGPIO_DO_1       VIA   -    MD0100PA00X+015750Y+045339X0200Y         S0      
327SGPIO_DO_1       R151  -1          A12X+019633Y+014384X0198Y0197R270 S2      
317SGPIO_DO_1       VIA   -    MD0100PA00X+019658Y+014118X0200Y         S0      
327SGPIO_DO_0       R435  -2          A12X+006000Y+032792X0198Y0197R090 S2      
327SGPIO_DO_0       VIA   -    M      A12X+017868Y+043017X0260Y         S2      
327SGPIO_DO_0       GF1   -B29        A01X+017030Y+046638X0150Y0840R180 S1      
327SGPIO_DO_0       R79   -2          A12X+018192Y+042280X0198Y0197     S2      
317SGPIO_DO_0       VIA   -    MD0100PA00X+017140Y+045060X0200Y         S0      
317SGPIO_DO_0       VIA   -    MD0100PA00X+005660Y+032430X0200Y         S0      
327SGPIO_DI_1       R433  -1          A01X+019222Y+011130X0198Y0197     S1      
317SGPIO_DI_1       VIA   -    MD0100PA00X+014500Y+009070X0200Y         S0      
317SGPIO_DI_1       VIA   -    M      A01X+018689Y+011399X0200Y         S2      
017SGPIO_DI_1       VIA   -    M      A12X+018689Y+011399X0260Y         S2      
017SGPIO_DI_1             -    MD0100PA00X+018689Y+011399                       
317SGPIO_DI_1       VIA   -    MD0100PA00X+007759Y+041344X0200Y         S0      
317SGPIO_DI_1       VIA   -    MD0100PA00X+014804Y+042670X0200Y         S0      
327SGPIO_DI_1       GF1   -B36        A01X+015376Y+046559X0150Y0680R180 S1      
327SGPIO_DI_1       R74   -2   M      A01X+014520Y+042938X0198Y0197R270 S1      
317SGPIO_DI_1       VIA   -    MD0100PA00X+005951Y+042448X0200Y         S0      
317SGPIO_DI_1       VIA   -    MD0100PA00X+003510Y+038161X0200Y         S0      
327SGPIO_DI_0       R437  -2          A01X+004692Y+032400X0198Y0197R180 S1      
317SGPIO_DI_0       VIA   -    MD0100PA00X+004452Y+032400X0200Y         S0      
317SGPIO_DI_0       VIA   -    MD0100PA00X+007120Y+043170X0200Y         S0      
317SGPIO_DI_0       VIA   -    M      A01X+015610Y+042510X0200Y         S2      
017SGPIO_DI_0       VIA   -    M      A12X+015610Y+042510X0260Y         S2      
017SGPIO_DI_0             -    MD0100PA00X+015610Y+042510                       
327SGPIO_DI_0       R78   -2   M      A01X+016145Y+042942X0198Y0197R270 S1      
327SGPIO_DI_0       GF1   -B31        A01X+016557Y+046559X0150Y0680R180 S1      
317SGPIO_CLK_1      VIA   -    M      A01X+010905Y+042585X0200Y         S2      
017SGPIO_CLK_1      VIA   -    M      A12X+010905Y+042585X0260Y         S2      
017SGPIO_CLK_1            -    MD0100PA00X+010905Y+042585                       
327SGPIO_CLK_1      GF1   -B35        A01X+015612Y+046638X0150Y0840R180 S1      
327SGPIO_CLK_1      R76   -2   M      A01X+015368Y+043260X0198Y0197     S1      
327SGPIO_CLK_1      R63   -1   M      A01X+015358Y+042900X0198Y0197R180 S1      
317SGPIO_CLK_1      VIA   -    MD0100PA00X+015220Y+042310X0200Y         S0      
317SGPIO_CLK_1      VIA   -    MD0100PA00X+019998Y+013229X0200Y         S0      
327SGPIO_CLK_1      R148  -1          A01X+019998Y+013479X0198Y0197R090 S1      
327SGPIO_CLK_0      R434  -2          A01X+005580Y+033108X0198Y0197R090 S1      
317SGPIO_CLK_0      VIA   -    MD0100PA00X+004290Y+041290X0200Y         S0      
317SGPIO_CLK_0      VIA   -    MD0100PA00X+006022Y+033610X0200Y         S0      
327SGPIO_CLK_0      GF1   -B30        A01X+016793Y+046559X0150Y0680R180 S1      
327SGPIO_CLK_0      R82   -2   M      A01X+017758Y+043260X0198Y0197     S1      
327SGPIO_CLK_0      R64   -1          A01X+018140Y+043278X0198Y0197R270 S1      
327SGPIO_CLK_0      VIA   -    M      A01X+016960Y+043267X0300Y         S1      
317SGPIO_CLK_0      VIA   -    MD0100PA00X+016803Y+045666X0200Y         S0      
327m0559            VIA   -    M      A01X+019870Y+014330X0300Y         S1      
327m0559            R150  -2          A01X+020000Y+012308X0198Y0197R090 S1      
327m0559            U5    -B18        A01X+020195Y+015816X0160Y    R180 S1      
327m0560            U5    -C18        A01X+020195Y+016130X0160Y    R180 S1      
317m0560            VIA   -    MD0100PA00X+020039Y+015975X0180Y    R180 S0      
327m0560            R151  -2          A12X+019633Y+014699X0198Y0197R270 S2      
327m0561            VIA   -    M      A01X+020090Y+011080X0300Y         S1      
327m0561            R433  -2          A01X+019538Y+011130X0198Y0197     S1      
327m0561            U5    -A17        A01X+020510Y+015500X0160Y    R180 S1      
327m0562            R148  -2          A01X+019998Y+013794X0198Y0197R090 S1      
327m0562            U5    -A18        A01X+020195Y+015500X0160Y    R180 S1      
327RST_RSMRST_R_N   R160  -2          A01X+020406Y+025021X0198Y0197R270 S1      
327RST_RSMRST_R_N   U5    -AF14       A01X+021455Y+023374X0160Y    R180 S1      
327RST_RSMRST_R_N   VIA   -    M      A01X+020260Y+024550X0300Y         S1      
317RST_RSMRST_N     VIA   -    MD0100PA00X+020068Y+025754X0200Y         S0      
327RST_RSMRST_N     R160  -1          A01X+020406Y+025336X0198Y0197R270 S1      
327RST_RSMRST_N     R625  -2          A12X+010560Y+033378X0198Y0197R270 S2      
317RST_RSMRST_N     VIA   -    MD0100PA00X+009903Y+033837X0200Y         S0      
327RST_RSMRST_N     U25   -A5         A01X+009551Y+034483X0160Y    R180 S1      
317RST_RSMRST_N     VIA   -    M      A01X+011160Y+028400X0200Y         S2      
017RST_RSMRST_N     VIA   -    M      A12X+011160Y+028400X0260Y         S2      
017RST_RSMRST_N           -    MD0100PA00X+011160Y+028400                       
327m0563            VIA   -    M      A01X+026817Y+035984X0300Y         S1      
327m0563            J5    -2          A01X+025516Y+036754X0240Y0650R270 S1      
327m0563            R503  -1          A01X+026689Y+036461X0198Y0197     S1      
327RST_PLTRST_R_N   R168  -2          A12X+016658Y+016950X0198Y0197R180 S2      
327RST_PLTRST_R_N   U5    -H24        A01X+018305Y+017705X0160Y    R180 S1      
327RST_PLTRST_R_N   VIA   -    M      A12X+017168Y+017261X0260Y         S2      
317RST_PLTRST_R_N   VIA   -    MD0100PA00X+018150Y+017550X0180Y         S0      
327RST_PLTRST_N     VIA   -    M      A12X+019420Y+035193X0260Y         S2      
327RST_PLTRST_N     R718  -1   M      A01X+012188Y+034250X0198Y0197R180 S1      
327RST_PLTRST_N     R118  -2          A01X+024220Y+013794X0198Y0197R090 S1      
327RST_PLTRST_N     U5    -A7         A01X+023659Y+015500X0160Y    R180 S1      
317RST_PLTRST_N     VIA   -    MD0100PA00X+024220Y+014100X0200Y         S0      
317RST_PLTRST_N     VIA   -    MD0100PA00X+016242Y+013103X0200Y         S0      
317RST_PLTRST_N     VIA   -    MD0100PA00X+016970Y+010225X0200Y         S0      
317RST_PLTRST_N     VIA   -    MD0100PA00X+013369Y+015810X0200Y         S0      
327RST_PLTRST_N     R168  -1          A12X+016342Y+016950X0198Y0197R180 S2      
317RST_PLTRST_N     VIA   -    MD0100PA00X+027841Y+043372X0200Y         S0      
317RST_PLTRST_N     VIA   -    MD0100PA00X+019142Y+035471X0200Y         S0      
317RST_PLTRST_N     VIA   -    MD0100PA00X+027614Y+036646X0200Y    R180 S0      
327RST_PLTRST_N     R503  -2          A01X+027004Y+036461X0198Y0197     S1      
317RST_PLTRST_N     VIA   -    MD0100PA00X+010670Y+044773X0200Y         S0      
327RST_PLTRST_N     R702  -1          A12X+020068Y+034225X0198Y0197R180 S2      
327RST_PLTRST_N     R34   -2   M      A12X+019380Y+034848X0198Y0197R270 S2      
327RST_PLTRST_N     GF1   -A51        A12X+010136Y+046559X0150Y0680R180 S2      
317RST_PLTRST_N     VIA   -    MD0100PA00X+010300Y+032380X0200Y         S0      
327m0564            R120  -2          A12X+025025Y+028078X0198Y0197     S2      
327m0564            U5    -AD8        A01X+023344Y+022745X0160Y    R180 S1      
317m0564            VIA   -    MD0100PA00X+023189Y+022589X0180Y         S2      
317m0564            VIA   -    MD0100PA00X+024119Y+027935X0200Y         S0      
327m0565            R565  -2          A01X+014560Y+023532X0198Y0197R270 S1      
317m0565            VIA   -    MD0100PA00X+007250Y+021400X0200Y         S0      
317m0565            VIA   -    MD0100PA00X+014550Y+022770X0200Y         S0      
317m0565            VIA   -    M      A01X+014073Y+007260X0200Y         S2      
017m0565            VIA   -    M      A12X+014073Y+007260X0260Y         S2      
017m0565                  -    MD0100PA00X+014073Y+007260                       
317m0565            VIA   -    MD0100PA00X+025780Y+008280X0200Y         S0      
327m0565            U32   -4          A01X+031758Y+007306X0140Y0490R270 S1      
327RST_BMC_SRST_N   R106  -1          A01X+021350Y+037642X0198Y0197R090 S1      
327RST_BMC_SRST_N   R125  -2          A01X+004458Y+041970X0198Y0197     S1      
327RST_BMC_SRST_N   VIA   -    M      A01X+021370Y+036310X0300Y         S1      
327RST_BMC_SRST_N   U5    -E10        A01X+022715Y+016760X0160Y    R180 S1      
317RST_BMC_SRST_N   VIA   -    MD0100PA00X+021349Y+037369X0200Y         S0      
317RST_BMC_SRST_N   VIA   -    MD0100PA00X+020000Y+040704X0200Y         S0      
327RST_BMC_SRST_N   R491  -2          A12X+024750Y+012508X0198Y0197R270 S2      
317RST_BMC_SRST_N   VIA   -    MD0100PA00X+024550Y+012780X0200Y         S0      
317RST_BMC_SRST_N   VIA   -    MD0100PA00X+022870Y+016605X0180Y    R180 S0      
317RST_BMC_SRST_N   VIA   -    MD0100PA00X+023150Y+035250X0200Y         S0      
317RST_BMC_SRST_N   VIA   -    MD0100PA00X+004360Y+042280X0200Y         S0      
317m0566            VIA   -    M      A01X+016350Y+022918X0300Y         S1      
017m0566            VIA   -    M      A12X+016350Y+022918X0200Y         S1      
017m0566                  -    MD0100PA00X+016350Y+022918                       
327m0566            U5    -AA24       A01X+018305Y+021800X0160Y    R180 S1      
327m0566            R566  -1          A12X+016068Y+022873X0198Y0197     S2      
317m0566            VIA   -    MD0100PA00X+018150Y+021955X0180Y         S0      
317m0567            VIA   -    MD0100PA00X+009130Y+025290X0200Y         S0      
327m0567            R717  -2   M      A12X+015515Y+023230X0198Y0197     S2      
327m0567            R566  -2          A12X+015752Y+022873X0198Y0197     S2      
327m0567            VIA   -    M      A12X+015043Y+023100X0260Y         S2      
317m0567            VIA   -    MD0100PA00X+014208Y+023055X0200Y         S0      
327m0567            U25   -C7         A01X+008921Y+035113X0160Y    R180 S1      
317m0567            VIA   -    MD0100PA00X+009077Y+034957X0180Y         S0      
317RMII_OCP_RCLKI   VIA   -    MD0100PA00X+012290Y+017010X0200Y         S0      
317RMII_OCP_RCLKI   VIA   -    MD0100PA00X+014083Y+019253X0200Y         S0      
317RMII_OCP_RCLKI   VIA   -    MD0100PA00X+014558Y+024808X0200Y         S0      
327RMII_OCP_RCLKI   GF1   -B18        A01X+020970Y+046559X0150Y0680R180 S1      
317RMII_OCP_RCLKI   VIA   -    MD0100PA00X+020520Y+044540X0200Y         S0      
317RMII_OCP_RCLKI   VIA   -    MD0100PA00X+025781Y+043510X0200Y         S0      
317RMII_OCP_RCLKI   VIA   -    MD0100PA00X+015620Y+011160X0200Y         S0      
327RMII_OCP_RCLKI   U28   -1          A01X+016188Y+010714X0180Y0520R270 S1      
327RMII_TXEN_R      R171  -1          A12X+016780Y+015729X0198Y0197     S2      
327RMII_TXEN_R      U5    -E23        A01X+018620Y+016760X0160Y    R180 S1      
317RMII_TXEN_R      VIA   -    MD0100PA00X+018464Y+016605X0180Y    R180 S2      
327RMII_TXEN        R171  -2          A12X+016465Y+015729X0198Y0197     S2      
317RMII_TXEN        VIA   -    MD0100PA00X+016220Y+015820X0200Y         S0      
317RMII_TXEN        VIA   -    M      A01X+020856Y+040450X0200Y         S2      
017RMII_TXEN        VIA   -    M      A12X+020856Y+040450X0260Y         S2      
017RMII_TXEN              -    MD0100PA00X+020856Y+040450                       
317RMII_TXEN        VIA   -    MD0100PA00X+019840Y+043480X0200Y         S0      
327RMII_TXEN        R103  -2          A01X+019940Y+043233X0198Y0197R090 S1      
327RMII_TXEN        GF1   -B20        A01X+020498Y+046559X0150Y0680R180 S1      
327RMII_TXD1_R      R173  -1          A01X+015948Y+015308X0198Y0197R180 S1      
327RMII_TXD1_R      U5    -E25        A01X+017990Y+016760X0160Y    R180 S1      
327RMII_TXD1        R173  -2          A01X+015633Y+015308X0198Y0197R180 S1      
327RMII_TXD1        VIA   -    M      A01X+020005Y+041865X0300Y         S1      
327RMII_TXD1        GF1   -B22        A01X+020026Y+046638X0150Y0840R180 S1      
317RMII_TXD1        VIA   -    MD0100PA00X+015648Y+015593X0200Y         S0      
317RMII_TXD1        VIA   -    MD0100PA00X+020754Y+040869X0200Y         S0      
327RMII_TXD0_R      R172  -1          A12X+016692Y+016115X0198Y0197     S2      
327RMII_TXD0_R      U5    -E24        A01X+018305Y+016760X0160Y    R180 S1      
327RMII_TXD0_R      VIA   -    M      A12X+017151Y+016289X0260Y         S2      
317RMII_TXD0_R      VIA   -    MD0100PA00X+018150Y+016605X0180Y    R180 S0      
327RMII_TXD0        R172  -2          A12X+016378Y+016115X0198Y0197     S2      
317RMII_TXD0        VIA   -    M      A01X+015933Y+016085X0200Y         S2      
017RMII_TXD0        VIA   -    M      A12X+015933Y+016085X0260Y         S2      
017RMII_TXD0              -    MD0100PA00X+015933Y+016085                       
327RMII_TXD0        GF1   -B21        A01X+020262Y+046559X0150Y0680R180 S1      
317RMII_TXD0        VIA   -    MD0100PA00X+019900Y+044450X0200Y         S0      
317RMII_TXD0        VIA   -    MD0100PA00X+023690Y+044056X0200Y         S0      
327RMII_RXER        U5    -B24        A01X+018305Y+015816X0160Y    R180 S1      
317RMII_RXER        VIA   -    M      A01X+019530Y+043233X0200Y         S2      
017RMII_RXER        VIA   -    M      A12X+019530Y+043233X0260Y         S2      
017RMII_RXER              -    MD0100PA00X+019530Y+043233                       
317RMII_RXER        VIA   -    MD0100PA00X+022990Y+043660X0200Y         S0      
317RMII_RXER        VIA   -    MD0100PA00X+018150Y+015660X0180Y    R180 S0      
327RMII_RXER        GF1   -B23        A01X+019789Y+046559X0150Y0680R180 S1      
327RMII_RXER        R101  -2   M      A01X+019233Y+043233X0198Y0197R090 S1      
327RMII_RXD1        GF1   -B25        A01X+019317Y+046638X0150Y0840R180 S1      
327RMII_RXD1        U5    -B26        A01X+017675Y+015816X0160Y    R180 S1      
317RMII_RXD1        VIA   -    MD0100PA00X+019178Y+045670X0200Y         S0      
317RMII_RXD1        VIA   -    MD0100PA00X+017520Y+015660X0180Y    R180 S2      
327RMII_RXD0        GF1   -B24        A01X+019553Y+046559X0150Y0680R180 S1      
327RMII_RXD0        U5    -C24        A01X+018305Y+016130X0160Y    R180 S1      
317RMII_RXD0        VIA   -    MD0100PA00X+019178Y+045330X0200Y         S0      
317RMII_RXD0        VIA   -    MD0100PA00X+026170Y+043970X0200Y         S0      
317RMII_RXD0        VIA   -    MD0100PA00X+018150Y+015975X0180Y    R180 S0      
327RMII_CSRDV       R161  -2          A01X+020340Y+043228X0198Y0197R090 S1      
327RMII_CSRDV       U5    -B25        A01X+017990Y+015816X0160Y    R180 S1      
317RMII_CSRDV       VIA   -    MD0100PA00X+020251Y+043480X0200Y         S0      
317RMII_CSRDV       VIA   -    M      A01X+024940Y+041030X0300Y         S1      
017RMII_CSRDV       VIA   -    M      A12X+024940Y+041030X0200Y         S1      
017RMII_CSRDV             -    MD0100PA00X+024940Y+041030                       
317RMII_CSRDV       VIA   -    MD0100PA00X+017835Y+015660X0180Y    R180 S0      
327RMII_CSRDV       GF1   -B19        A01X+020734Y+046638X0150Y0840R180 S1      
327PWR_BTN_BMC_N    U31   -4          A01X+004804Y+005290X0400Y0150R090 S1      
317PWR_BTN_BMC_N    VIA   -    MD0100PA00X+005071Y+005472X0200Y         S0      
317PWR_BTN_BMC_N    VIA   -    MD0100PA00X+014922Y+026774X0200Y         S0      
327PWR_BTN_BMC_N    U15   -2          A01X+015800Y+027371X0130Y0460     S1      
327PWR_BTN_BMC_N    R225  -2          A12X+016346Y+023848X0198Y0197     S2      
317PWR_BTN_BMC_N    VIA   -    MD0100PA00X+013260Y+035009X0200Y         S0      
317PWR_BTN_BMC_N    VIA   -    M      A01X+014986Y+024379X0200Y         S2      
017PWR_BTN_BMC_N    VIA   -    M      A12X+014986Y+024379X0260Y         S2      
017PWR_BTN_BMC_N          -    MD0100PA00X+014986Y+024379                       
317PWR_BTN_BMC_N    VIA   -    MD0100PA00X+005070Y+025040X0200Y         S0      
317PWR_BTN_BMC_N    VIA   -    MD0100PA00X+011470Y+035120X0200Y         S0      
327PWR_BTN_BMC_N    R81   -2          A01X+011872Y+034640X0198Y0197R180 S1      
327PWRGD_P5V_AUX    D23   -1          A12X+004850Y+040572X0260Y0540R180 S2      
327PWRGD_P5V_AUX    U49   -1          A01X+012638Y+024774X0280Y0400R270 S1      
317PWRGD_P5V_AUX    VIA   -    MD0100PA00X+012288Y+024530X0200Y         S0      
327PWRGD_P5V_AUX    VIA   -    M      A01X+006226Y+021110X0300Y         S1      
317PWRGD_P5V_AUX    VIA   -    MD0100PA00X+005882Y+021353X0200Y         S0      
327PWRGD_P5V_AUX    U18   -1          A01X+006226Y+020499X0130Y0460R180 S1      
327PWRGD_P5V_AUX    U42   -1          A01X+004776Y+022608X0280Y0400     S1      
327PWRGD_P5V_AUX    R292  -2          A12X+005010Y+022048X0198Y0197R180 S2      
317PWRGD_P5V_AUX    VIA   -    MD0100PA00X+004802Y+021786X0200Y         S0      
317PWRGD_P5V_AUX    VIA   -    MD0100PA00X+006860Y+015916X0200Y    R180 S0      
327PWRGD_P5V_AUX    U53   -1          A01X+006456Y+014859X0130Y0460R180 S1      
317PWRGD_P5V_AUX    VIA   -    MD0100PA00X+032180Y+006006X0200Y         S0      
327PWRGD_P5V_AUX    U52   -1          A12X+031154Y+027409X0130Y0460R180 S2      
317PWRGD_P5V_AUX    VIA   -    MD0100PA00X+013300Y+005990X0200Y         S0      
317PWRGD_P5V_AUX    VIA   -    MD0100PA00X+004452Y+039165X0200Y         S0      
327PWRGD_P3V3_AUX   R318  -2          A01X+004732Y+039435X0198Y0197R180 S1      
317PWRGD_P3V3_AUX   VIA   -    M      A01X+022400Y+007428X0200Y         S2      
017PWRGD_P3V3_AUX   VIA   -    M      A12X+022400Y+007428X0260Y         S2      
017PWRGD_P3V3_AUX         -    MD0100PA00X+022400Y+007428                       
327PWRGD_P3V3_AUX   R382  -1          A01X+032087Y+011713X0198Y0197R090 S1      
317PWRGD_P3V3_AUX   VIA   -    MD0100PA00X+032076Y+011458X0200Y         S0      
327PWRGD_P3V3_AUX   R293  -2          A01X+005188Y+026460X0198Y0197     S1      
317PWRGD_P3V3_AUX   VIA   -    MD0100PA00X+004452Y+039415X0200Y         S0      
317PWRGD_P3V3_AUX   VIA   -    MD0100PA00X+004622Y+027717X0200Y         S0      
327PWRGD_P2V5_AUX   R320  -2          A12X+004692Y+038800X0198Y0197     S2      
327PWRGD_P2V5_AUX   R873  -2   M      A12X+031020Y+013332X0198Y0197R270 S2      
317PWRGD_P2V5_AUX   VIA   -    MD0100PA00X+013436Y+023007X0200Y         S0      
317PWRGD_P2V5_AUX   VIA   -    MD0100PA00X+005276Y+039020X0200Y         S0      
327PWRGD_P2V5_AUX   VIA   -    M      A12X+025650Y+009850X0260Y         S2      
317PWRGD_P2V5_AUX   VIA   -    MD0100PA00X+022689Y+011730X0200Y         S0      
327PWRGD_P2V5_AUX   R35   -1          A12X+031400Y+013018X0198Y0197R270 S2      
327PWRGD_P1V8_AUX   R321  -2          A12X+007850Y+040308X0198Y0197R270 S2      
327PWRGD_P1V8_AUX   VIA   -           A12X+029910Y+028650X0260Y         S2      
327PWRGD_P1V8_AUX   R529  -1   M      A01X+005182Y+022060X0198Y0197     S1      
327PWRGD_P1V8_AUX   U42   -2          A01X+005150Y+022608X0280Y0400     S1      
317PWRGD_P1V8_AUX   VIA   -    MD0100PA00X+005160Y+024120X0200Y         S0      
317PWRGD_P1V8_AUX   VIA   -    MD0100PA00X+011784Y+024220X0200Y         S0      
327PWRGD_P1V8_AUX   R275  -1          A01X+015350Y+023208X0198Y0197R270 S1      
317PWRGD_P1V8_AUX   VIA   -    MD0100PA00X+015310Y+023480X0200Y         S0      
317PWRGD_P1V8_AUX   VIA   -    MD0100PA00X+014230Y+033670X0200Y    R270 S0      
317PWRGD_P1V8_AUX   VIA   -    MD0100PA00X+027336Y+033000X0200Y         S0      
317PWRGD_P1V8_AUX   VIA   -    MD0100PA00X+030280Y+028620X0200Y         S0      
327PWRGD_P1V8_AUX   R764  -1          A01X+030531Y+028509X0198Y0197     S1      
317PWRGD_P1V8_AUX   VIA   -    MD0100PA00X+007786Y+040868X0200Y         S0      
317PWRGD_P1V8_AUX   VIA   -    MD0100PA00X+013530Y+039990X0200Y         S0      
327PWRGD_P1V2_AUX   R323  -2          A01X+007900Y+040608X0198Y0197R090 S1      
327PWRGD_P1V2_AUX   R276  -2          A01X+033250Y+030338X0198Y0197R090 S1      
317PWRGD_P1V2_AUX   VIA   -    M      A01X+031230Y+034070X0300Y         S1      
017PWRGD_P1V2_AUX   VIA   -    M      A12X+031230Y+034070X0200Y         S1      
017PWRGD_P1V2_AUX         -    MD0100PA00X+031230Y+034070                       
317PWRGD_P1V2_AUX   VIA   -    MD0100PA00X+007860Y+028397X0200Y         S0      
317PWRGD_P1V2_AUX   VIA   -    MD0100PA00X+003550Y+034050X0200Y         S0      
317PWRGD_P1V2_AUX   VIA   -    MD0100PA00X+003953Y+040910X0200Y         S0      
317PWRGD_P1V2_AUX   VIA   -    MD0100PA00X+006896Y+017330X0200Y         S0      
327PWRGD_P1V2_AUX   U53   -2          A01X+006200Y+014859X0130Y0460R180 S1      
327PWRGD_P1V0_AUX   R379  -2          A12X+007050Y+040308X0198Y0197R270 S2      
317PWRGD_P1V0_AUX   VIA   -    MD0100PA00X+010300Y+013180X0200Y         S0      
327PWRGD_P1V0_AUX   R277  -2   M      A01X+010040Y+013508X0198Y0197R090 S1      
327PWRGD_P1V0_AUX   R49   -1          A01X+013752Y+014075X0198Y0197R090 S1      
317PWRGD_P1V0_AUX   VIA   -    MD0100PA00X+007230Y+015940X0200Y         S0      
317PWRGD_P1V0_AUX   VIA   -    MD0100PA00X+006790Y+040052X0200Y         S0      
317PWRGD_P1V0_AUX   VIA   -    MD0100PA00X+003774Y+039120X0200Y         S0      
317PWRGD_P1V0_AUX   VIA   -    M      A01X+005800Y+021770X0200Y         S2      
017PWRGD_P1V0_AUX   VIA   -    M      A12X+005800Y+021770X0260Y         S2      
017PWRGD_P1V0_AUX         -    MD0100PA00X+005800Y+021770                       
317m0568            VIA   -    MD0100PA00X+018500Y+045650X0200Y         S0      
327m0568            GF1   -B28        A01X+018608Y+046638X0150Y0840R180 S1      
327m0568            U5    -AA18       A01X+020195Y+021800X0160Y    R180 S1      
327m0568            C43   -1          A12X+015916Y+022061X0198Y0197R270 S2      
327m0568            C42   -1          A12X+015455Y+022095X0280Y0320R090 S2      
327m0568            VIA   -           A12X+015240Y+022630X0260Y         S2      
317m0568            VIA   -    MD0100PA00X+016220Y+022138X0200Y         S0      
317m0568            VIA   -    MD0100PA00X+020039Y+021955X0180Y         S0      
327PVCCA_AUX_PLD    VIA   -           A12X+005982Y+034103X0260Y         S2      
327PVCCA_AUX_PLD    VIA   -           A12X+005550Y+039560X0260Y         S2      
327PVCCA_AUX_PLD    C269  -1   M      A12X+010496Y+034798X0164Y0164R270 S2      
327PVCCA_AUX_PLD    U25   -A16        A01X+006086Y+034483X0160Y    R180 S1      
317PVCCA_AUX_PLD    VIA   -    MD0100PA00X+006246Y+034642X0180Y         S0      
327PVCCA_AUX_PLD    C190  -1          A12X+006039Y+034769X0198Y0197R225 S2      
327PVCCA_AUX_PLD    U25   -T1         A01X+010811Y+039208X0160Y    R180 S1      
327PVCCA_AUX_PLD    C266  -1          A12X+011010Y+039264X0198Y0197R045 S2      
327PVCCA_AUX_PLD    L19   -2          A12X+010750Y+039860X0280Y0320R180 S2      
327PVCCA_AUX_PLD    C286  -1          A12X+010561Y+039361X0198Y0197R045 S2      
317PVCCA_AUX_PLD    VIA   -    MD0100PA00X+010811Y+039510X0200Y         S0      
327PVCCA_AUX_PLD    C193  -1          A12X+005787Y+039164X0198Y0197R135 S2      
327PVCCA_AUX_PLD    C163  -1          A12X+005995Y+039855X0280Y0320R225 S2      
317PVCCA_AUX_PLD    VIA   -    MD0100PA00X+005950Y+039400X0200Y         S0      
327PVCCA_AUX_PLD    U25   -T16        A01X+006086Y+039208X0160Y    R180 S1      
317PVCCA_AUX_PLD    VIA   -    MD0100PA00X+009077Y+036217X0180Y         S0      
327PVCCA_AUX_PLD    U25   -G7         A01X+008921Y+036373X0160Y    R180 S1      
327PVCCA_AUX_PLD    C263  -1          A12X+009371Y+037453X0164Y0164R180 S2      
317PVCCA_AUX_PLD    VIA   -    MD0100PA00X+009077Y+037473X0180Y         S0      
327PVCCA_AUX_PLD    U25   -K7         A01X+008921Y+037318X0160Y    R180 S1      
327PVCCA_AUX_PLD    C176  -1          A12X+007985Y+036382X0164Y0164R270 S2      
317PVCCA_AUX_PLD    VIA   -    MD0100PA00X+007821Y+036217X0180Y         S0      
327PVCCA_AUX_PLD    U25   -G10        A01X+007976Y+036373X0160Y    R180 S1      
327PVCCA_AUX_PLD    C250  -1          A12X+007666Y+037642X0164Y0164R270 S2      
317PVCCA_AUX_PLD    VIA   -    MD0100PA00X+007821Y+037473X0180Y         S0      
327PVCCA_AUX_PLD    U25   -K10        A01X+007976Y+037318X0160Y    R180 S1      
327PVCCA_AUX_PLD    U25   -A1         A01X+010811Y+034483X0160Y    R180 S1      
317PVCCA_AUX_PLD    VIA   -    MD0100PA00X+010656Y+034640X0180Y         S0      
317m0569            VIA   -    M      A01X+028812Y+012031X0200Y         S2      
017m0569            VIA   -    M      A12X+028812Y+012031X0260Y         S2      
017m0569                  -    MD0100PA00X+028812Y+012031                       
327m0569            R597  -2          A01X+028530Y+012031X0198Y0197R270 S1      
327m0569            D7    -A          A01X+029138Y+012031X0320Y0320R090 S1      
317m0570            VIA   -    M      A01X+028780Y+013154X0200Y         S2      
017m0570            VIA   -    M      A12X+028780Y+013154X0260Y         S2      
017m0570                  -    MD0100PA00X+028780Y+013154                       
327m0570            R598  -2          A01X+028530Y+013154X0198Y0197R090 S1      
327m0570            D6    -A          A01X+029782Y+012801X0320Y0320R270 S1      
327m0571            R599  -2          A01X+031670Y+011982X0198Y0197R270 S1      
327m0571            D5    -A          A01X+030426Y+012031X0320Y0320R090 S1      
327m0572            D4    -A          A01X+031066Y+012801X0320Y0320R270 S1      
327m0572            R600  -2          A01X+031138Y+013430X0198Y0197     S1      
327m0573            D3    -A          A01X+029138Y+010626X0320Y0320R090 S1      
327m0573            VIA   -    M      A01X+028422Y+010330X0300Y         S1      
327m0573            R601  -2          A01X+028892Y+010040X0198Y0197R180 S1      
327m0574            D2    -A          A01X+029782Y+011396X0320Y0320R270 S1      
327m0574            R602  -2          A01X+028530Y+011396X0198Y0197R090 S1      
327m0575            D1    -A          A01X+030426Y+010626X0320Y0320R090 S1      
327m0575            R603  -2          A01X+031607Y+010274X0198Y0197R270 S1      
327m0575            VIA   -    M      A01X+031077Y+010201X0300Y         S1      
327m0576            D0    -A          A01X+031066Y+011396X0320Y0320R270 S1      
327m0576            R604  -2          A01X+031607Y+011396X0198Y0197R090 S1      
327m0577            R212  -2          A01X+021478Y+010877X0198Y0197R270 S1      
327m0577            OSC1  -1          A01X+022056Y+010724X0340Y0460R090 S1      
317m0577            VIA   -    M      A01X+021640Y+010640X0200Y         S2      
017m0577            VIA   -    M      A12X+021640Y+010640X0260Y         S2      
017m0577                  -    MD0100PA00X+021640Y+010640                       
327PECI_BMC_R       R216  -1          A01X+019981Y+025021X0198Y0197R090 S1      
327PECI_BMC_R       U5    -AF16       A01X+020825Y+023374X0160Y    R180 S1      
327PECI_BMC         R209  -1   M      A01X+019708Y+026481X0198Y0197R180 S1      
327PECI_BMC         R216  -2          A01X+019981Y+025336X0198Y0197R090 S1      
317PECI_BMC         VIA   -    M      A01X+029270Y+040370X0200Y         S2      
017PECI_BMC         VIA   -    M      A12X+029270Y+040370X0260Y         S2      
017PECI_BMC               -    MD0100PA00X+029270Y+040370                       
327PECI_BMC         GF1   -B27        A01X+018844Y+046559X0150Y0680R180 S1      
317PECI_BMC         VIA   -    MD0100PA00X+020110Y+026512X0200Y         S0      
317PECI_BMC         VIA   -    MD0100PA00X+018500Y+045400X0200Y         S0      
327PD_SP_ENTEST     U5    -C10        A01X+022715Y+016130X0160Y    R180 S1      
327PD_SP_ENTEST     R210  -2          A12X+025237Y+013794X0198Y0197R270 S2      
327PD_SP_ENTEST     VIA   -           A12X+024755Y+014256X0260Y         S2      
317PD_SP_ENTEST     VIA   -    MD0100PA00X+022870Y+015975X0180Y         S0      
327m0578            U1    -F9         A01X+031280Y+019649X0145Y         S1      
327m0578            R6    -1          A12X+031712Y+019938X0198Y0197R270 S2      
317m0578            VIA   -    MD0100PA00X+031431Y+019799X0180Y         S0      
327m0579            U1    -N9         A01X+031280Y+017444X0145Y         S1      
327m0579            R5    -1          A12X+031783Y+017338X0198Y0197R180 S2      
317m0579            VIA   -    MD0100PA00X+031493Y+017444X0180Y    R045 S0      
327m0580            U1    -T3         A01X+029391Y+016499X0145Y         S1      
327m0580            R4    -1   M      A12X+028862Y+016580X0198Y0197     S2      
327m0580            VIA   -           A12X+028791Y+017032X0260Y         S2      
317m0580            VIA   -    MD0100PA00X+029226Y+016349X0180Y         S0      
317JTAG_SCM_NTRST   VIA   -    M      A01X+025850Y+014640X0200Y         S2      
017JTAG_SCM_NTRST   VIA   -    M      A12X+025850Y+014640X0260Y         S2      
017JTAG_SCM_NTRST         -    MD0100PA00X+025850Y+014640                       
327JTAG_SCM_NTRST   R206  -2          A12X+026186Y+014425X0198Y0197R090 S2      
327JTAG_SCM_NTRST   U5    -F11        A01X+022400Y+017075X0160Y    R180 S1      
317JTAG_SCM_NTRST   VIA   -    MD0100PA00X+022555Y+016920X0180Y    R180 S0      
327PD_FRU_WC_N      R15   -1          A12X+027158Y+011737X0198Y0197     S2      
327PD_FRU_WC_N      U19   -7          A12X+028655Y+010821X0170Y0700R090 S2      
327PD_FRU_WC_N      VIA   -    M      A12X+027839Y+011104X0260Y         S2      
317P5V_USB_REAR     VIA   -    M      A01X+015280Y+007560X0200Y         S2      
017P5V_USB_REAR     VIA   -    M      A12X+015280Y+007560X0260Y         S2      
017P5V_USB_REAR           -    MD0100PA00X+015280Y+007560                       
327P5V_USB_REAR     VIA   -    M      A12X+015280Y+007035X0260Y         S2      
327P5V_USB_REAR     U38   -4          A01X+012110Y+006891X0240Y0280     S1      
317P5V_USB_REAR     J2    -1   MD0280PA00X+015520Y+005268X0440Y0440R090 S3      
327P5V_USB_REAR     C177  -1          A01X+019720Y+008000X0460Y0620R180 S1      
327P5V_USB_REAR     C327  -1          A01X+019720Y+007100X0460Y0620R180 S1      
317P5V_USB_REAR     VIA   -    MD0100PA00X+018940Y+006960X0200Y         S0      
317P5V_USB_REAR     VIA   -    M      A01X+019310Y+006910X0200Y         S2      
017P5V_USB_REAR     VIA   -    M      A12X+019310Y+006910X0260Y         S2      
017P5V_USB_REAR           -    MD0100PA00X+019310Y+006910                       
327P5V_USB_REAR     U10   -6          A01X+019711Y+008859X0240Y0380R270 S1      
327P5V_USB_REAR     C179  -1          A01X+018727Y+007888X0198Y0197R090 S1      
327P5V_USB_REAR     C178  -1          A01X+019131Y+007888X0198Y0197R090 S1      
327P5V_AUX_VCC      PU38  -19         A01X+002228Y+019008X0120Y0320R090 S1      
327P5V_AUX_VCC      VIA   -    M      A12X+004060Y+020300X0260Y         S2      
327P5V_AUX_VCC      PR241 -1          A01X+004556Y+021472X0198Y0197R180 S1      
317P5V_AUX_VCC      VIA   -    MD0100PA00X+004806Y+021482X0200Y    R270 S0      
317P5V_AUX_VCC      VIA   -    M      A01X+001910Y+018742X0200Y         S2      
017P5V_AUX_VCC      VIA   -    M      A12X+001910Y+018742X0260Y         S2      
017P5V_AUX_VCC            -    MD0100PA00X+001910Y+018742                       
327P5V_AUX_VCC      PC208 -1          A01X+001661Y+018736X0198Y0197R090 S1      
327P5V_AUX_REF      PU38  -5          A01X+003331Y+019677X0070Y0320R270 S1      
327P5V_AUX_REF      PC271 -1          A01X+004231Y+019154X0198Y0197     S1      
317P5V_AUX_REF      VIA   -    M      A01X+003941Y+019599X0200Y    R270 S2      
017P5V_AUX_REF      VIA   -    M      A12X+003941Y+019599X0260Y    R270 S2      
017P5V_AUX_REF            -    MD0100PA00X+003941Y+019599                       
327P5V_AUX_FB       PU38  -7          A01X+003331Y+019992X0070Y0320R270 S1      
327P5V_AUX_FB       PC272 -1          A01X+005039Y+019886X0198Y0197R270 S1      
327P5V_AUX_FB       PR527 -1   M      A01X+004639Y+019886X0198Y0197R270 S1      
327P5V_AUX_FB       PR526 -1   M      A01X+004239Y+019886X0198Y0197R270 S1      
327EN_P5V_AUX       PU38  -8          A01X+003331Y+020150X0070Y0320R270 S1      
327EN_P5V_AUX       PR522 -1   M      A01X+004228Y+020318X0198Y0197R090 S1      
327EN_P5V_AUX       PC205 -1   M      A01X+004631Y+020318X0198Y0197R090 S1      
327EN_P5V_AUX       PR521 -2          A01X+005185Y+020318X0198Y0197R270 S1      
327P5V_AUX_CS       PU38  -3          A01X+003331Y+019362X0070Y0320R270 S1      
327P5V_AUX_CS       PR525 -1          A01X+004414Y+018752X0198Y0197     S1      
327P5V_AUX          VIA   -           A12X+002400Y+013850X0260Y         S2      
327P5V_AUX          VIA   -           A12X+001900Y+012950X0260Y         S2      
327P5V_AUX          VIA   -           A12X+002900Y+012950X0260Y         S2      
327P5V_AUX          R814  -1          A12X+005550Y+007892X0198Y0197R270 S2      
327P5V_AUX          R569  -2          A12X+008650Y+006892X0198Y0197R090 S2      
317P5V_AUX          VIA   -    MD0100PA00X+023700Y+004720X0200Y         S0      
327P5V_AUX          R80   -2          A01X+023700Y+004458X0198Y0197R090 S1      
317P5V_AUX          VIA   -    MD0100PA00X+008800Y+006650X0200Y         S0      
327P5V_AUX          D16   -1          A12X+011650Y+007889X0250Y0400R270 S2      
327P5V_AUX          C203  -1          A12X+012450Y+016148X0198Y0197R270 S2      
327P5V_AUX          C202  -1          A12X+012025Y+016148X0198Y0197R270 S2      
327P5V_AUX          U39   -10         A01X+032929Y+012610X0110Y0360R180 S1      
327P5V_AUX          U41   -10         A01X+013826Y+021628X0110Y0360R090 S1      
327P5V_AUX          R787  -1          A12X+022640Y+029396X0198Y0197R180 S2      
317P5V_AUX          VIA   -    MD0100PA00X+022365Y+029396X0200Y         S0      
327P5V_AUX          C292  -1          A01X+013800Y+021108X0198Y0197R270 S1      
317P5V_AUX          VIA   -    MD0100PA00X+013810Y+021360X0200Y         S0      
317P5V_AUX          VIA   -    MD0100PA00X+012216Y+015784X0200Y         S0      
327P5V_AUX          D11   -A          A12X+012216Y+015426X0390Y0480R090 S2      
317P5V_AUX          VIA   -    MD0100PA00X+011300Y+015800X0200Y         S0      
327P5V_AUX          D9    -A          A12X+011300Y+015441X0390Y0480R090 S2      
317P5V_AUX          VIA   -    MD0100PA00X+012650Y+015800X0200Y         S0      
327P5V_AUX          R27   -1          A12X+012980Y+015595X0280Y0320R180 S2      
327P5V_AUX          C287  -1          A01X+033448Y+012550X0198Y0197     S1      
327P5V_AUX          R716  -1          A12X+031158Y+037300X0198Y0197     S2      
317P5V_AUX          VIA   -    MD0100PA00X+031434Y+037330X0200Y         S0      
317P5V_AUX          VIA   -    MD0100PA00X+033174Y+012580X0200Y    R090 S0      
327P5V_AUX          PR275 -1          A01X+033760Y+027898X0198Y0197R270 S1      
317P5V_AUX          VIA   -    MD0100PA00X+034061Y+027897X0200Y         S0      
327P5V_AUX          PC217 -1          A01X+004500Y+012908X0440Y0540R090 S1      
327P5V_AUX          PC215 -1          A01X+001950Y+012908X0440Y0540R090 S1      
327P5V_AUX          PC213 -1          A01X+002800Y+012908X0440Y0540R090 S1      
327P5V_AUX          PC214 -1          A01X+003650Y+012908X0440Y0540R090 S1      
327P5V_AUX          VIA   -           A12X+004500Y+012950X0260Y         S2      
327P5V_AUX          VIA   -           A12X+003650Y+012950X0260Y         S2      
327P5V_AUX          PC212 -1          A01X+005206Y+012677X0198Y0197R270 S1      
327P5V_AUX          PL34  -2          A01X+003526Y+014018X1300Y1300R270 S1      
317P5V_AUX          VIA   -    MD0100PA00X+004924Y+013076X0200Y    R270 S0      
317P5V_AUX          VIA   -    MD0100PA00X+005224Y+012952X0200Y    R270 S0      
317P5V_AUX          VIA   -    MD0100PA00X+004924Y+012776X0200Y    R270 S0      
317P5V_AUX          VIA   -    MD0100PA00X+004074Y+013076X0200Y    R270 S0      
317P5V_AUX          VIA   -    MD0100PA00X+004074Y+012776X0200Y    R270 S0      
317P5V_AUX          VIA   -    MD0100PA00X+003224Y+013076X0200Y    R270 S0      
317P5V_AUX          VIA   -    MD0100PA00X+003224Y+012776X0200Y    R270 S0      
317P5V_AUX          VIA   -    MD0100PA00X+002374Y+013076X0200Y    R270 S0      
317P5V_AUX          VIA   -    MD0100PA00X+002374Y+012776X0200Y    R270 S0      
327P5V_AUX          PC272 -2   M      A01X+005039Y+019571X0198Y0197R270 S1      
327P5V_AUX          PR527 -2          A01X+004639Y+019571X0198Y0197R270 S1      
317P5V_AUX          VIA   -    MD0100PA00X+005288Y+019571X0200Y         S0      
327P5V_AUX          PR205 -1          A01X+009970Y+011902X0198Y0197R090 S1      
317P5V_AUX          VIA   -    MD0100PA00X+010036Y+011650X0200Y    R090 S0      
317P5V_AUX          VIA   -    MD0100PA00X+021990Y+010130X0200Y         S0      
327P5V_AUX          R376  -1          A01X+021750Y+010201X0198Y0197R180 S1      
317P5V_AUX          VIA   -    MD0100PA00X+022130Y+009210X0200Y         S0      
317P5V_AUX          VIA   -    MD0100PA00X+021860Y+009210X0200Y         S0      
327P5V_AUX          C171  -1          A01X+022010Y+008834X0440Y0540R090 S1      
327P5V_AUX          C172  -1          A01X+021450Y+009092X0198Y0197R090 S1      
327P5V_AUX          U10   -1          A01X+020597Y+008859X0240Y0380R270 S1      
317P5V_AUX          VIA   -    MD0100PA00X+011650Y+007400X0200Y         S0      
317P5V_AUX          VIA   -    MD0100PA00X+011850Y+007550X0200Y         S0      
317P5V_AUX          VIA   -    MD0100PA00X+011500Y+004450X0200Y         S0      
327P5V_AUX          R815  -1          A01X+011650Y+004208X0198Y0197R270 S1      
327P5V_AUX          R18   -1          A12X+017940Y+001462X0198Y0197R270 S2      
317P5V_AUX          VIA   -    MD0100PA00X+017690Y+001462X0200Y         S0      
317P5V_AUX          VIA   -    MD0100PA00X+005500Y+007600X0200Y         S0      
327P5V_AUX          R568  -2          A12X+005550Y+007308X0198Y0197R270 S2      
327m0581            VIA   -           A12X+014050Y+013450X0260Y         S2      
327m0581            L9    -2          A12X+013750Y+012890X0280Y0320     S2      
327m0581            L2    -2          A12X+014260Y+012900X0280Y0320R090 S2      
327m0581            U5    -H14        A01X+021455Y+017705X0160Y    R180 S1      
327m0581            C60   -1          A12X+021233Y+017827X0198Y0197     S2      
327m0581            C65   -1          A12X+021550Y+017228X0198Y0197R090 S2      
317m0581            VIA   -    MD0100PA00X+021455Y+017485X0180Y         S0      
317m0581            VIA   -    MD0100PA00X+014289Y+013664X0200Y         S0      
317m0581            VIA   -    MD0100PA00X+014518Y+013421X0200Y         S0      
327m0582            VIA   -           A12X+017060Y+020430X0260Y         S2      
327m0582            U5    -W21 M      A01X+019250Y+021170X0160Y    R180 S1      
327m0582            U5    -V21        A01X+019250Y+020855X0160Y    R180 S1      
317m0582            VIA   -    MD0100PA00X+017262Y+020830X0200Y         S0      
327m0582            C48   -1          A12X+017200Y+021203X0198Y0197     S2      
327m0582            C51   -1          A12X+019342Y+021320X0198Y0197R180 S2      
327m0582            L7    -2          A12X+017162Y+021771X0280Y0320R270 S2      
317m0582            VIA   -    MD0100PA00X+019094Y+021325X0180Y    R180 S0      
317P3V3_RTC_AUX     VIA   -    MD0100PA00X+017423Y+030433X0200Y         S0      
317P3V3_RTC_AUX     VIA   -    MD0100PA00X+018464Y+021010X0180Y    R180 S0      
327P3V3_RTC_AUX     C83   -1          A12X+018154Y+021006X0198Y0197R270 S2      
327P3V3_RTC_AUX     U5    -V23        A01X+018620Y+020855X0160Y    R180 S1      
317P3V3_RTC_AUX     VIA   -    MD0100PA00X+019503Y+030718X0200Y         S0      
317P3V3_RTC_AUX     VIA   -    M      A01X+018730Y+038430X0200Y         S2      
017P3V3_RTC_AUX     VIA   -    M      A12X+018730Y+038430X0260Y         S2      
017P3V3_RTC_AUX           -    MD0100PA00X+018730Y+038430                       
327P3V3_RTC_AUX     C196  -1   M      A12X+018260Y+041802X0198Y0197R090 S2      
317P3V3_RTC_AUX     VIA   -    MD0100PA00X+018524Y+041750X0200Y         S0      
327P3V3_RTC_AUX     U48   -3          A12X+017704Y+041850X0320Y0360R270 S2      
327P3V3_RGM         R86   -1          A12X+010289Y+007857X0198Y0197R180 S2      
327P3V3_RGM         R709  -1          A01X+027718Y+012325X0198Y0197     S1      
317P3V3_RGM         VIA   -    MD0100PA00X+010442Y+008250X0200Y         S0      
327P3V3_RGM         R32   -1          A01X+010442Y+008000X0198Y0197     S1      
327P3V3_RGM         R758  -1          A01X+013278Y+026190X0198Y0197R180 S1      
317P3V3_RGM         VIA   -    MD0100PA00X+014780Y+020079X0200Y         S0      
317P3V3_RGM         VIA   -    M      A01X+014525Y+025689X0200Y         S2      
017P3V3_RGM         VIA   -    M      A12X+014525Y+025689X0260Y         S2      
017P3V3_RGM               -    MD0100PA00X+014525Y+025689                       
327P3V3_RGM         VIA   -    M      A12X+026706Y+012475X0260Y         S2      
327P3V3_RGM         R204  -1          A12X+025610Y+011318X0198Y0197R090 S2      
317P3V3_RGM         VIA   -    MD0100PA00X+022555Y+018180X0180Y    R180 S0      
317P3V3_RGM         VIA   -           A01X+023020Y+026748X0200Y         S2      
017P3V3_RGM         VIA   -           A12X+023020Y+026748X0260Y         S2      
017P3V3_RGM               -     D0100PA00X+023020Y+026748                       
317P3V3_RGM         VIA   -    MD0100PA00X+023351Y+013259X0200Y         S0      
317P3V3_RGM         VIA   -    MD0100PA00X+020820Y+011176X0200Y         S0      
327P3V3_RGM         U14   -1          A01X+027107Y+012752X0220Y0320R180 S1      
327P3V3_RGM         R211  -1   M      A12X+026035Y+011945X0198Y0197R270 S2      
327P3V3_RGM         C37   -1          A01X+021078Y+011192X0198Y0197R270 S1      
327P3V3_RGM         C85   -1          A12X+022335Y+018189X0198Y0197     S2      
317P3V3_RGM         VIA   -    MD0100PA00X+027345Y+012505X0200Y         S0      
327P3V3_RGM         R623  -1   M      A01X+023351Y+013499X0198Y0197R090 S1      
327P3V3_RGM         OSC1  -4          A01X+022056Y+011373X0340Y0460R090 S1      
327P3V3_RGM         R491  -1          A12X+024750Y+012192X0198Y0197R270 S2      
317P3V3_RGM         VIA   -    MD0100PA00X+024720Y+011740X0200Y         S0      
317P3V3_RGM         VIA   -    MD0100PA00X+027596Y+012601X0200Y         S0      
327P3V3_RGM         U5    -K11 M      A01X+022400Y+018335X0160Y    R180 S1      
327P3V3_RGM         U5    -K12        A01X+022085Y+018335X0160Y    R180 S1      
327P3V3_RGM         R834  -1          A01X+024600Y+011992X0198Y0197R090 S1      
327P3V3_RGM         R203  -1          A01X+023766Y+013479X0198Y0197R090 S1      
327P3V3_RGM         R523  -1   M      A12X+025633Y+011995X0198Y0197R270 S2      
327P3V3_RGM         C251  -1          A01X+027705Y+012848X0198Y0197R090 S1      
327P3V3_RGM         R212  -1          A01X+021478Y+011192X0198Y0197R270 S1      
317P3V3_RGM         VIA   -           A01X+029000Y+008200X0200Y         S2      
017P3V3_RGM         VIA   -           A12X+029000Y+008200X0260Y         S2      
017P3V3_RGM               -     D0100PA00X+029000Y+008200                       
317P3V3_RGM         VIA   -    MD0100PA00X+015240Y+028440X0200Y         S0      
327P3V3_RGM         R754  -1          A12X+017800Y+034190X0198Y0197R090 S2      
327P3V3_RGM         R34   -1          A12X+019380Y+034532X0198Y0197R270 S2      
317P3V3_RGM         VIA   -    MD0100PA00X+019762Y+038542X0200Y         S0      
327P3V3_RGM         R287  -1          A01X+019375Y+038542X0198Y0197R090 S1      
327P3V3_RGM         R291  -1          A01X+019375Y+037132X0198Y0197R270 S1      
327P3V3_RGM         R289  -1          A01X+019375Y+037642X0198Y0197R090 S1      
317P3V3_RGM         VIA   -    MD0100PA00X+019500Y+037390X0200Y         S0      
317P3V3_RGM         VIA   -    MD0100PA00X+017110Y+034122X0200Y         S0      
317P3V3_RGM         VIA   -    MD0100PA00X+019060Y+033790X0200Y         S0      
317P3V3_RGM         VIA   -    MD0100PA00X+020456Y+030113X0200Y         S0      
327P3V3_RGM         R31   -1          A01X+012620Y+008258X0198Y0197R270 S1      
317P3V3_RGM         VIA   -    MD0100PA00X+012371Y+008230X0200Y         S0      
327m0583            C30   -1          A01X+015243Y+015014X0198Y0197R090 S1      
327m0583            R155  -2          A01X+014839Y+015014X0198Y0197R270 S1      
327m0583            U5    -M22        A01X+018935Y+018965X0160Y    R180 S1      
327m0583            U5    -L22 M      A01X+018935Y+018650X0160Y    R180 S1      
327m0583            U5    -K21        A01X+019250Y+018335X0160Y    R180 S1      
327m0583            U5    -J21        A01X+019250Y+018020X0160Y    R180 S1      
327m0583            C32   -1          A12X+019728Y+018197X0198Y0197R180 S2      
327m0583            C31   -1          A12X+018760Y+018726X0198Y0197R270 S2      
327m0583            C33   -1          A12X+019334Y+018156X0198Y0197R090 S2      
327m0583            R154  -2          A01X+015643Y+014556X0198Y0197R090 S1      
327m0583            R156  -2          A01X+016046Y+014558X0198Y0197R090 S1      
317m0583            VIA   -    MD0100PA00X+019094Y+018180X0180Y         S0      
317m0583            VIA   -    MD0100PA00X+019094Y+017865X0180Y         S0      
317m0583            VIA   -    MD0100PA00X+018779Y+018494X0180Y         S0      
317m0583            VIA   -    M      A01X+014843Y+014768X0200Y         S2      
017m0583            VIA   -    M      A12X+014843Y+014768X0260Y         S2      
017m0583                  -    MD0100PA00X+014843Y+014768                       
317m0583            VIA   -    MD0100PA00X+015256Y+014768X0200Y         S0      
327m0584            R213  -2          A01X+015553Y+012220X0198Y0197R090 S1      
327m0584            C38   -1          A01X+015912Y+012220X0198Y0197R270 S1      
327m0584            U5    -H19        A01X+019880Y+017705X0160Y    R180 S1      
327m0584            U5    -H18        A01X+020195Y+017705X0160Y    R180 S1      
327m0584            C39   -1          A12X+020022Y+017797X0198Y0197R180 S2      
327m0584            R214  -2          A01X+015650Y+013242X0198Y0197R270 S1      
317m0584            VIA   -           A01X+015629Y+012490X0200Y         S2      
017m0584            VIA   -           A12X+015629Y+012490X0260Y         S2      
017m0584                  -     D0100PA00X+015629Y+012490                       
317m0584            VIA   -    MD0100PA00X+015641Y+012920X0200Y         S0      
317m0584            VIA   -    MD0100PA00X+019724Y+017550X0180Y         S0      
317m0584            VIA   -    MD0100PA00X+020039Y+017550X0180Y         S0      
327m0585            R207  -2          A12X+014847Y+015284X0198Y0197R180 S2      
327m0585            U5    -H21        A01X+019250Y+017705X0160Y    R180 S1      
327m0585            U5    -G21        A01X+019250Y+017390X0160Y    R180 S1      
327m0585            C35   -1          A12X+015652Y+015013X0198Y0197R270 S2      
327m0585            C36   -1          A12X+019355Y+017475X0198Y0197R090 S2      
327m0585            R208  -2          A12X+014988Y+014106X0198Y0197     S2      
327m0585            VIA   -           A12X+014480Y+014170X0260Y         S2      
317m0585            VIA   -    MD0100PA00X+019094Y+017550X0180Y         S0      
317m0585            VIA   -    MD0100PA00X+019094Y+017235X0180Y         S0      
317m0585            VIA   -    MD0100PA00X+015395Y+014509X0200Y         S0      
317m0585            VIA   -    MD0100PA00X+015016Y+014509X0200Y         S0      
327m0586            C53   -1          A01X+014150Y+014042X0198Y0197R090 S1      
327m0586            R232  -2          A01X+014942Y+014200X0198Y0197R180 S1      
327m0586            R231  -2          A01X+014550Y+014042X0198Y0197R270 S1      
327m0586            U5    -F20 M      A01X+019565Y+017075X0160Y    R180 S1      
327m0586            U5    -F19        A01X+019880Y+017075X0160Y    R180 S1      
327m0586            C57   -1          A12X+019746Y+016891X0198Y0197R270 S2      
317m0586            VIA   -    MD0100PA00X+019409Y+016920X0180Y         S0      
317m0586            VIA   -    M      A01X+014980Y+013510X0200Y         S2      
017m0586            VIA   -    M      A12X+014980Y+013510X0260Y         S2      
017m0586                  -    MD0100PA00X+014980Y+013510                       
317m0586            VIA   -    MD0100PA00X+014980Y+013810X0200Y         S0      
327m0587            C44   -1          A12X+027730Y+013740X0280Y0320R270 S2      
327m0587            VIA   -           A12X+027210Y+013740X0260Y         S2      
327m0587            U5    -J10        A01X+022715Y+018020X0160Y    R180 S1      
327m0587            C45   -1          A12X+023088Y+018087X0198Y0197R180 S2      
327m0587            L4    -2          A12X+026657Y+013737X0280Y0320     S2      
317m0587            VIA   -    MD0100PA00X+022870Y+017865X0180Y         S0      
317m0587            VIA   -    MD0100PA00X+026949Y+013860X0200Y         S0      
317P3V3_AUX_VCC     VIA   -           A01X+001706Y+025571X0200Y    R090 S2      
017P3V3_AUX_VCC     VIA   -           A12X+001706Y+025571X0260Y    R090 S2      
017P3V3_AUX_VCC           -     D0100PA00X+001706Y+025571                       
327P3V3_AUX_VCC     PU1   -13         A01X+002500Y+025605X0098Y0276R270 S1      
327P3V3_AUX_VCC     PC221 -1   M      A01X+002020Y+025571X0198Y0197R270 S1      
327P3V3_AUX_FB_RC   PR534 -1          A01X+005244Y+025254X0198Y0197R090 S1      
327P3V3_AUX_FB_RC   PC239 -1   M      A01X+004844Y+025254X0198Y0197R090 S1      
327P3V3_AUX_FB_RC   PU1   -6          A01X+003641Y+025408X0098Y0276R090 S1      
327P3V3_AUX_FB_RC   PR530 -2   M      A01X+004438Y+025254X0198Y0197R270 S1      
327P3V3_AUX         R887  -1          A01X+004050Y+037792X0198Y0197R090 S1      
327P3V3_AUX         U58   -5          A12X+012661Y+037758X0280Y0400R180 S2      
317P3V3_AUX         VIA   -    MD0100PA00X+012118Y+038512X0200Y         S0      
327P3V3_AUX         C337  -1   M      A12X+012118Y+037680X0198Y0197     S2      
317P3V3_AUX         VIA   -    MD0100PA00X+004452Y+038780X0200Y         S0      
327P3V3_AUX         R886  -1          A01X+004692Y+038770X0198Y0197     S1      
327P3V3_AUX         R251  -1   M      A12X+017474Y+011975X0198Y0197R270 S2      
327P3V3_AUX         R250  -1   M      A12X+017876Y+011975X0198Y0197R270 S2      
317P3V3_AUX         VIA   -    MD0100PA00X+005343Y+010656X0200Y         S0      
327P3V3_AUX         C274  -1   M      A12X+006000Y+010342X0198Y0197R270 S2      
327P3V3_AUX         U8    -5          A12X+005856Y+009874X0170Y0240     S2      
317P3V3_AUX         VIA   -    MD0100PA00X+007528Y+007570X0200Y         S0      
327P3V3_AUX         R52   -1          A12X+007792Y+007600X0198Y0197R180 S2      
327P3V3_AUX         R416  -1          A12X+006850Y+006892X0198Y0197R270 S2      
327P3V3_AUX         R418  -1          A12X+009850Y+006942X0198Y0197R270 S2      
317P3V3_AUX         VIA   -    MD0100PA00X+027450Y+005800X0200Y         S0      
327P3V3_AUX         R883  -1          A12X+027158Y+005700X0198Y0197     S2      
317P3V3_AUX         VIA   -    MD0100PA00X+027700Y+005166X0200Y         S0      
327P3V3_AUX         U57   -5          A01X+027150Y+004756X0400Y0150     S1      
327P3V3_AUX         C336  -1   M      A01X+027700Y+004758X0198Y0197R270 S1      
317P3V3_AUX         VIA   -    MD0100PA00X+014398Y+019967X0200Y         S0      
327P3V3_AUX         R400  -1          A01X+015422Y+019570X0198Y0197     S1      
317P3V3_AUX         VIA   -    MD0100PA00X+029000Y+006798X0200Y         S0      
317P3V3_AUX         VIA   -    MD0100PA00X+030042Y+005452X0200Y         S0      
327P3V3_AUX         U16   -5          A01X+029300Y+005706X0400Y0150     S1      
327P3V3_AUX         C29   -1   M      A01X+030042Y+005700X0198Y0197     S1      
327P3V3_AUX         D18   -A          A01X+029737Y+008400X0240Y0280R180 S1      
317P3V3_AUX         VIA   -    MD0100PA00X+030007Y+008400X0200Y         S0      
317P3V3_AUX         VIA   -    MD0100PA00X+030957Y+008400X0200Y         S0      
327P3V3_AUX         D19   -A          A01X+030687Y+008400X0240Y0280R180 S1      
327P3V3_AUX         R462  -1          A12X+015993Y+023604X0198Y0197R270 S2      
327P3V3_AUX         R472  -1          A01X+004732Y+039785X0198Y0197     S1      
317P3V3_AUX         VIA   -    MD0100PA00X+011900Y+004460X0200Y         S0      
327P3V3_AUX         R43   -2          A01X+012050Y+004208X0198Y0197R090 S1      
317P3V3_AUX         VIA   -    MD0100PA00X+017690Y+027010X0200Y         S0      
327P3V3_AUX         R805  -1   M      A01X+017782Y+027280X0198Y0197     S1      
327P3V3_AUX         R167  -1          A01X+017448Y+027280X0198Y0197R180 S1      
317P3V3_AUX         VIA   -    MD0100PA00X+009850Y+006650X0200Y         S0      
317P3V3_AUX         VIA   -    MD0100PA00X+006850Y+006650X0200Y         S0      
317P3V3_AUX         VIA   -    MD0100PA00X+003530Y+005832X0200Y         S0      
327P3V3_AUX         U31   -5          A01X+004292Y+005290X0400Y0150R090 S1      
327P3V3_AUX         C200  -1   M      A01X+004201Y+005832X0198Y0197     S1      
317P3V3_AUX         VIA   -    MD0100PA00X+005898Y+003640X0200Y         S0      
327P3V3_AUX         C191  -1          A01X+005379Y+003850X0198Y0197R180 S1      
317P3V3_AUX         VIA   -    MD0100PA00X+004550Y+004150X0200Y         S0      
327P3V3_AUX         R768  -1          A01X+004392Y+003800X0198Y0197     S1      
327P3V3_AUX         R396  -1          A01X+008992Y+025550X0198Y0197     S1      
327P3V3_AUX         J40   -2          A01X+014301Y+036657X0200Y0590     S1      
317P3V3_AUX         J14   -1   MD0410PA00X+006571Y+004224X0610Y0610     S3      
317P3V3_AUX         VIA   -    MD0100PA00X+004449Y+039785X0200Y         S0      
327P3V3_AUX         Q4    -S   M      A12X+026117Y+039101X0320Y0360R090 S2      
327P3V3_AUX         R592  -1          A01X+018800Y+031782X0198Y0197R090 S1      
327P3V3_AUX         U15   -5          A01X+015544Y+028129X0130Y0460     S1      
327P3V3_AUX         C26   -1   M      A01X+015500Y+028942X0198Y0197R090 S1      
327P3V3_AUX         R140  -1          A01X+022850Y+034472X0198Y0197R090 S1      
327P3V3_AUX         R44   -1          A12X+009681Y+041776X0198Y0197R270 S2      
327P3V3_AUX         R90   -1          A01X+007950Y+027258X0198Y0197R270 S1      
327P3V3_AUX         R558  -1          A01X+015838Y+030970X0198Y0197R180 S1      
327P3V3_AUX         R557  -1   M      A01X+015837Y+031356X0198Y0197R180 S1      
327P3V3_AUX         R181  -1          A01X+018332Y+030020X0198Y0197     S1      
327P3V3_AUX         R630  -1          A12X+025292Y+005150X0198Y0197R180 S2      
327P3V3_AUX         R11   -1          A01X+013300Y+026792X0198Y0197R090 S1      
327P3V3_AUX         R686  -1          A12X+028591Y+027235X0198Y0197R270 S2      
327P3V3_AUX         R687  -1          A12X+028189Y+027235X0198Y0197R270 S2      
317P3V3_AUX         VIA   -    MD0100PA00X+028189Y+026990X0200Y         S0      
317P3V3_AUX         VIA   -    MD0100PA00X+028591Y+026990X0200Y         S0      
317P3V3_AUX         VIA   -    MD0100PA00X+010260Y+026700X0200Y         S0      
327P3V3_AUX         R58   -1   M      A01X+010350Y+026942X0198Y0197R090 S1      
327P3V3_AUX         R404  -1          A01X+009550Y+026942X0198Y0197R090 S1      
327P3V3_AUX         R543  -1   M      A01X+009950Y+026942X0198Y0197R090 S1      
327P3V3_AUX         R207  -1          A12X+014532Y+015284X0198Y0197R180 S2      
327P3V3_AUX         R155  -1          A01X+014839Y+015329X0198Y0197R270 S1      
327P3V3_AUX         R661  -1          A01X+011976Y+026813X0198Y0197R090 S1      
327P3V3_AUX         R662  -1          A01X+011526Y+026813X0198Y0197R090 S1      
317P3V3_AUX         VIA   -    MD0100PA00X+011740Y+026650X0200Y         S0      
327P3V3_AUX         R659  -1   M      A01X+012876Y+026813X0198Y0197R090 S1      
317P3V3_AUX         VIA   -    MD0100PA00X+012876Y+026573X0200Y         S0      
327P3V3_AUX         R660  -1          A01X+012426Y+027613X0198Y0197R090 S1      
317P3V3_AUX         VIA   -    MD0100PA00X+012510Y+027372X0200Y         S0      
327P3V3_AUX         R663  -1          A01X+012192Y+033156X0198Y0197R270 S1      
327P3V3_AUX         R658  -1   M      A01X+012592Y+033156X0198Y0197R270 S1      
317P3V3_AUX         VIA   -    MD0100PA00X+012591Y+033501X0200Y         S0      
317P3V3_AUX         VIA   -    MD0100PA00X+014220Y+033400X0200Y         S0      
327P3V3_AUX         R655  -1          A01X+015392Y+033156X0198Y0197R270 S1      
317P3V3_AUX         VIA   -    MD0100PA00X+014860Y+033630X0200Y         S0      
327P3V3_AUX         R464  -1          A01X+022356Y+037240X0198Y0197     S1      
327P3V3_AUX         R50   -1          A01X+029015Y+036751X0198Y0197     S1      
327P3V3_AUX         R586  -1          A12X+011442Y+035850X0198Y0197R180 S2      
327P3V3_AUX         C304  -1          A01X+006550Y+018072X0198Y0197R090 S1      
327P3V3_AUX         R646  -2          A12X+026231Y+038440X0280Y0320R270 S2      
327P3V3_AUX         R161  -1          A01X+020340Y+042912X0198Y0197R090 S1      
327P3V3_AUX         R103  -1   M      A01X+019940Y+042918X0198Y0197R090 S1      
317P3V3_AUX         VIA   -    MD0100PA00X+019860Y+042660X0200Y         S0      
317P3V3_AUX         VIA   -    MD0100PA00X+018976Y+042918X0200Y         S0      
327P3V3_AUX         R79   -1          A12X+018508Y+042280X0198Y0197     S2      
327P3V3_AUX         R101  -1          A01X+019233Y+042918X0198Y0197R090 S1      
317P3V3_AUX         VIA   -    MD0100PA00X+017253Y+042947X0200Y    R180 S0      
327P3V3_AUX         R488  -1          A01X+017128Y+042677X0198Y0197R270 S1      
327P3V3_AUX         U48   -2          A12X+016916Y+042224X0320Y0360R270 S2      
327P3V3_AUX         R82   -1          A01X+017442Y+043260X0198Y0197     S1      
327P3V3_AUX         R78   -1   M      A01X+016145Y+043258X0198Y0197R270 S1      
317P3V3_AUX         VIA   -    MD0100PA00X+015729Y+043562X0200Y         S0      
327P3V3_AUX         R75   -1          A01X+015760Y+043258X0198Y0197R270 S1      
327P3V3_AUX         R74   -1          A01X+014520Y+043252X0198Y0197R270 S1      
317P3V3_AUX         VIA   -    MD0100PA00X+014810Y+043340X0200Y         S0      
327P3V3_AUX         R76   -1          A01X+015052Y+043260X0198Y0197     S1      
327P3V3_AUX         R68   -1   M      A01X+013618Y+042900X0198Y0197R180 S1      
327P3V3_AUX         R69   -1          A01X+013990Y+042892X0198Y0197R090 S1      
317P3V3_AUX         VIA   -    MD0100PA00X+013623Y+042394X0200Y         S0      
327P3V3_AUX         U13   -5          A01X+005930Y+042121X0160Y0200R090 S1      
317P3V3_AUX         VIA   -    MD0100PA00X+006810Y+042540X0200Y         S0      
327P3V3_AUX         C147  -1   M      A01X+006625Y+042132X0198Y0197R270 S1      
327P3V3_AUX         R124  -1          A01X+004080Y+042658X0198Y0197R270 S1      
317P3V3_AUX         VIA   -    MD0100PA00X+004120Y+042910X0200Y         S0      
327P3V3_AUX         D20   -1          A01X+001861Y+042260X0460Y0690     S1      
317P3V3_AUX         VIA   -    MD0100PA00X+001770Y+042760X0200Y         S0      
317P3V3_AUX         VIA   -    MD0100PA00X+002060Y+042890X0200Y         S0      
327P3V3_AUX         R41   -1          A12X+021580Y+041972X0198Y0197R270 S2      
317P3V3_AUX         VIA   -    MD0100PA00X+021905Y+041885X0200Y         S0      
317P3V3_AUX         VIA   -    MD0100PA00X+015000Y+041475X0200Y         S0      
327P3V3_AUX         R226  -1          A12X+014600Y+041718X0198Y0197R270 S2      
327P3V3_AUX         R227  -1   M      A12X+015000Y+041718X0198Y0197R270 S2      
327P3V3_AUX         R73   -1          A12X+015380Y+041722X0198Y0197R270 S2      
317P3V3_AUX         VIA   -    MD0100PA00X+013970Y+041510X0200Y         S0      
327P3V3_AUX         R230  -1          A12X+013800Y+041718X0198Y0197R270 S2      
317P3V3_AUX         VIA   -    MD0100PA00X+011979Y+041230X0200Y         S0      
327P3V3_AUX         R77   -1          A12X+011740Y+041672X0198Y0197R270 S2      
327P3V3_AUX         R633  -1          A01X+011908Y+041500X0198Y0197R180 S1      
317P3V3_AUX         VIA   -    MD0100PA00X+009810Y+041240X0200Y         S0      
327P3V3_AUX         R828  -1          A12X+008880Y+041772X0198Y0197R270 S2      
317P3V3_AUX         VIA   -    MD0100PA00X+008760Y+041450X0200Y         S0      
317P3V3_AUX         VIA   -    MD0100PA00X+003788Y+037792X0200Y         S0      
327P3V3_AUX         R607  -1          A12X+004098Y+037418X0198Y0197R090 S2      
327P3V3_AUX         R490  -1          A01X+016903Y+034362X0198Y0197R090 S1      
317P3V3_AUX         VIA   -    MD0100PA00X+016856Y+034122X0200Y         S0      
317P3V3_AUX         VIA   -    MD0100PA00X+012440Y+034530X0200Y         S0      
327P3V3_AUX         R81   -1          A01X+012188Y+034640X0198Y0197R180 S1      
327P3V3_AUX         R492  -1          A01X+013998Y+034830X0198Y0197R180 S1      
317P3V3_AUX         VIA   -    MD0100PA00X+013859Y+034571X0200Y    R180 S0      
327P3V3_AUX         R821  -1          A12X+015360Y+033016X0198Y0197R180 S2      
327P3V3_AUX         R430  -1   M      A12X+015360Y+032613X0198Y0197R180 S2      
317P3V3_AUX         VIA   -    MD0100PA00X+015132Y+032270X0200Y    R180 S0      
327P3V3_AUX         R625  -1          A12X+010560Y+033062X0198Y0197R270 S2      
327P3V3_AUX         R169  -1          A01X+010310Y+032812X0198Y0197R090 S1      
317P3V3_AUX         VIA   -    MD0100PA00X+010576Y+032772X0200Y         S0      
317P3V3_AUX         VIA   -    MD0100PA00X+004420Y+033200X0200Y         S0      
327P3V3_AUX         R446  -1          A01X+004692Y+033200X0198Y0197     S1      
327P3V3_AUX         C255  -1   M      A12X+021060Y+030512X0198Y0197R270 S2      
317P3V3_AUX         VIA   -    MD0100PA00X+021440Y+030400X0200Y         S0      
327P3V3_AUX         R55   -1          A12X+020208Y+030040X0198Y0197     S2      
327P3V3_AUX         U30   -16  M      A12X+020418Y+030585X0140Y0590R270 S2      
317P3V3_AUX         VIA   -    MD0100PA00X+019245Y+030831X0200Y    R180 S0      
317P3V3_AUX         VIA   -    MD0100PA00X+016216Y+031356X0200Y         S0      
327P3V3_AUX         U6    -5          A01X+003574Y+032500X0170Y0240R270 S1      
327P3V3_AUX         C34   -1   M      A01X+002828Y+031690X0198Y0197R180 S1      
317P3V3_AUX         VIA   -    MD0100PA00X+003070Y+031550X0200Y         S0      
317P3V3_AUX         VIA   -    MD0100PA00X+018762Y+029748X0200Y         S0      
327P3V3_AUX         U54   -8          A01X+019701Y+029656X0200Y0340R090 S1      
327P3V3_AUX         C312  -1   M      A01X+018768Y+029450X0198Y0197R180 S1      
317P3V3_AUX         VIA   -    MD0100PA00X+015250Y+028942X0200Y         S0      
327P3V3_AUX         J4    -72         A01X+013878Y+028882X0110Y0630     S1      
327P3V3_AUX         J4    -74         A01X+014075Y+028882X0110Y0630     S1      
317P3V3_AUX         VIA   -    MD0100PA00X+013532Y+027981X0200Y         S0      
327P3V3_AUX         C231  -1   M      A12X+013408Y+027700X0198Y0197     S2      
327P3V3_AUX         C228  -1          A01X+014230Y+027878X0198Y0197R270 S1      
327P3V3_AUX         U20   -5          A12X+013450Y+026944X0140Y0440     S2      
327P3V3_AUX         R867  -1          A01X+011110Y+027612X0198Y0197R090 S1      
317P3V3_AUX         VIA   -    MD0100PA00X+011110Y+027370X0200Y         S0      
327P3V3_AUX         C11   -1   M      A12X+012242Y+027700X0198Y0197R180 S2      
327P3V3_AUX         U7    -5          A12X+012200Y+026944X0140Y0440     S2      
317P3V3_AUX         VIA   -    MD0100PA00X+022380Y+025480X0200Y         S0      
317P3V3_AUX         VIA   -    MD0100PA00X+021750Y+026400X0200Y         S0      
317P3V3_AUX         VIA   -    MD0100PA00X+023230Y+026120X0200Y         S0      
317P3V3_AUX         VIA   -    MD0100PA00X+020550Y+025830X0200Y         S0      
327P3V3_AUX         R452  -1   M      A12X+021410Y+025878X0198Y0197R090 S2      
327P3V3_AUX         R844  -1   M      A12X+020046Y+025334X0198Y0197R090 S2      
327P3V3_AUX         R848  -1          A12X+019069Y+024613X0198Y0197R090 S2      
327P3V3_AUX         R239  -1          A12X+022310Y+025238X0198Y0197R090 S2      
327P3V3_AUX         R240  -1   M      A12X+022536Y+025852X0198Y0197R270 S2      
327P3V3_AUX         R241  -1   M      A12X+022926Y+025885X0198Y0197R270 S2      
327P3V3_AUX         R683  -1          A01X+022962Y+025820X0198Y0197     S1      
327P3V3_AUX         R846  -1   M      A12X+019473Y+024613X0198Y0197R090 S2      
327P3V3_AUX         R38   -1   M      A12X+020850Y+025882X0198Y0197R270 S2      
327P3V3_AUX         R640  -1          A12X+017258Y+026700X0198Y0197     S2      
327P3V3_AUX         R699  -1          A01X+020242Y+027300X0198Y0197     S1      
317P3V3_AUX         VIA   -    MD0100PA00X+019090Y+027170X0200Y    R180 S0      
317P3V3_AUX         VIA   -    MD0100PA00X+019537Y+027330X0200Y         S0      
327P3V3_AUX         R789  -1          A12X+019779Y+027479X0198Y0197R090 S2      
327P3V3_AUX         R842  -1          A12X+018712Y+026700X0198Y0197R180 S2      
327P3V3_AUX         R843  -1          A12X+018707Y+026248X0198Y0197R090 S2      
327P3V3_AUX         R774  -1          A01X+019652Y+026870X0198Y0197     S1      
327P3V3_AUX         R319  -1          A01X+019008Y+026700X0198Y0197R180 S1      
317P3V3_AUX         VIA   -    MD0100PA00X+011140Y+025468X0200Y         S0      
327P3V3_AUX         R67   -1   M      A01X+011080Y+025712X0198Y0197R090 S1      
327P3V3_AUX         U47   -5          A01X+011280Y+024954X0170Y0240     S1      
327P3V3_AUX         C268  -1   M      A01X+011480Y+025772X0198Y0197R090 S1      
327P3V3_AUX         R231  -1          A01X+014550Y+014358X0198Y0197R270 S1      
317P3V3_AUX         VIA   -    MD0100PA00X+014327Y+015046X0200Y         S0      
317P3V3_AUX         VIA   -    MD0100PA00X+018779Y+019751X0180Y    R180 S0      
317P3V3_AUX         VIA   -    MD0100PA00X+018779Y+020066X0180Y    R180 S0      
317P3V3_AUX         VIA   -    MD0100PA00X+020984Y+017550X0180Y         S0      
317P3V3_AUX         VIA   -    MD0100PA00X+020669Y+017550X0180Y         S0      
317P3V3_AUX         VIA   -    MD0100PA00X+020354Y+017550X0180Y    R180 S0      
317P3V3_AUX         VIA   -    MD0100PA00X+020354Y+021325X0200Y         S0      
317P3V3_AUX         VIA   -    MD0100PA00X+020039Y+021325X0180Y    R180 S0      
327P3V3_AUX         C115  -1          A12X+019937Y+021721X0198Y0197     S2      
327P3V3_AUX         C94   -1          A12X+020325Y+021627X0198Y0197R180 S2      
327P3V3_AUX         C110  -1          A12X+020842Y+017229X0198Y0197R180 S2      
327P3V3_AUX         C101  -1          A12X+020456Y+017230X0198Y0197     S2      
327P3V3_AUX         C88   -1          A12X+018796Y+019434X0198Y0197     S2      
327P3V3_AUX         U5    -H15        A01X+021140Y+017705X0160Y    R180 S1      
327P3V3_AUX         U5    -H16        A01X+020825Y+017705X0160Y    R180 S1      
327P3V3_AUX         U5    -H17        A01X+020510Y+017705X0160Y    R180 S1      
327P3V3_AUX         U5    -N22        A01X+018935Y+019280X0160Y    R180 S1      
327P3V3_AUX         U5    -P22 M      A01X+018935Y+019595X0160Y    R180 S1      
327P3V3_AUX         U5    -R22        A01X+018935Y+019910X0160Y    R180 S1      
327P3V3_AUX         U5    -T22        A01X+018935Y+020225X0160Y    R180 S1      
327P3V3_AUX         U5    -W16        A01X+020825Y+021170X0160Y    R180 S1      
327P3V3_AUX         U5    -W17 M      A01X+020510Y+021170X0160Y    R180 S1      
327P3V3_AUX         U5    -W18        A01X+020195Y+021170X0160Y    R180 S1      
327P3V3_AUX         U5    -W19        A01X+019880Y+021170X0160Y    R180 S1      
327P3V3_AUX         R61   -1          A12X+018850Y+020372X0198Y0197R270 S2      
327P3V3_AUX         R269  -1          A01X+014837Y+017532X0198Y0197R270 S1      
317P3V3_AUX         VIA   -    MD0100PA00X+014055Y+017169X0200Y         S0      
327P3V3_AUX         R268  -1          A01X+014840Y+016768X0198Y0197R270 S1      
327P3V3_AUX         R710  -1   M      A01X+014358Y+017520X0198Y0197R180 S1      
317P3V3_AUX         VIA   -    MD0100PA00X+015320Y+017099X0200Y         S0      
327P3V3_AUX         R266  -1          A01X+015562Y+017100X0198Y0197     S1      
327P3V3_AUX         R267  -1          A12X+015563Y+018558X0198Y0197R180 S2      
327P3V3_AUX         R149  -1   M      A12X+015563Y+018157X0198Y0197R180 S2      
327P3V3_AUX         R422  -1   M      A12X+015660Y+017572X0198Y0197     S2      
317P3V3_AUX         VIA   -    MD0100PA00X+016124Y+017782X0200Y         S0      
327P3V3_AUX         R429  -1   M      A12X+014751Y+019260X0198Y0197R180 S2      
327P3V3_AUX         R438  -1          A01X+014215Y+018715X0198Y0197R270 S1      
327P3V3_AUX         R145  -1          A01X+014750Y+018735X0198Y0197     S1      
317P3V3_AUX         VIA   -    MD0100PA00X+014530Y+018884X0200Y         S0      
327P3V3_AUX         R428  -1          A12X+014812Y+018211X0198Y0197R180 S2      
317P3V3_AUX         VIA   -    MD0100PA00X+014055Y+016889X0200Y         S0      
317P3V3_AUX         VIA   -    MD0100PA00X+012650Y+017400X0200Y         S0      
327P3V3_AUX         U43   -6          A01X+012976Y+016362X0240Y0420     S1      
327P3V3_AUX         C253  -1   M      A01X+012900Y+017342X0198Y0197R090 S1      
327P3V3_AUX         PR193 -1          A01X+009580Y+011902X0198Y0197R090 S1      
317P3V3_AUX         VIA   -    MD0100PA00X+009250Y+011620X0200Y         S0      
317P3V3_AUX         VIA   -    MD0100PA00X+008926Y+013506X0200Y         S0      
327P3V3_AUX         PR500 -1   M      A01X+009240Y+013506X0198Y0197R270 S1      
327P3V3_AUX         R751  -1          A01X+013350Y+014092X0198Y0197R090 S1      
317P3V3_AUX         VIA   -    MD0100PA00X+013283Y+013840X0200Y         S0      
317P3V3_AUX         VIA   -    MD0100PA00X+033991Y+011261X0200Y         S0      
327P3V3_AUX         R12   -1          A12X+033749Y+011271X0198Y0197     S2      
327P3V3_AUX         C125  -1          A12X+032720Y+012025X0280Y0320R270 S2      
327P3V3_AUX         C120  -1          A12X+032600Y+012610X0280Y0320     S2      
317P3V3_AUX         VIA   -    MD0100PA00X+032402Y+011564X0200Y         S0      
317P3V3_AUX         VIA   -    MD0100PA00X+032402Y+012194X0200Y         S0      
317P3V3_AUX         VIA   -    MD0100PA00X+032401Y+011884X0200Y         S0      
327P3V3_AUX         C288  -1          A01X+032776Y+011850X0440Y0540R180 S1      
327P3V3_AUX         U39   -7          A01X+032338Y+012610X0110Y0360R180 S1      
327P3V3_AUX         U39   -8          A01X+032535Y+012610X0110Y0360R180 S1      
327P3V3_AUX         U39   -9          A01X+032732Y+012610X0110Y0360R180 S1      
327P3V3_AUX         R252  -1          A01X+023838Y+011995X0198Y0197R090 S1      
317P3V3_AUX         VIA   -    MD0100PA00X+023890Y+011480X0200Y         S0      
327P3V3_AUX         R255  -1   M      A12X+022737Y+011995X0198Y0197R270 S2      
327P3V3_AUX         R254  -1          A12X+023142Y+011995X0198Y0197R270 S2      
327P3V3_AUX         R258  -1   M      A12X+021931Y+011995X0198Y0197R270 S2      
327P3V3_AUX         R259  -1   M      A12X+022334Y+011995X0198Y0197R270 S2      
327P3V3_AUX         R262  -1   M      A12X+021529Y+011995X0198Y0197R270 S2      
317P3V3_AUX         VIA   -    MD0100PA00X+021529Y+011709X0200Y         S0      
327P3V3_AUX         R261  -1   M      A01X+021019Y+011995X0198Y0197R090 S1      
327P3V3_AUX         R521  -1          A01X+021446Y+011995X0198Y0197R090 S1      
327P3V3_AUX         R260  -1   M      A12X+021137Y+011994X0198Y0197R270 S2      
317P3V3_AUX         VIA   -    MD0100PA00X+021137Y+011700X0200Y         S0      
327P3V3_AUX         R816  -1          A12X+020780Y+011992X0198Y0197R270 S2      
327P3V3_AUX         R692  -1          A01X+020400Y+011992X0198Y0197R090 S1      
317P3V3_AUX         VIA   -    MD0100PA00X+019994Y+011750X0200Y         S0      
327P3V3_AUX         R264  -1          A12X+019950Y+011992X0198Y0197R270 S2      
317P3V3_AUX         VIA   -    MD0100PA00X+019310Y+011560X0200Y         S0      
327P3V3_AUX         R245  -1          A01X+019140Y+011995X0198Y0197R090 S1      
327P3V3_AUX         R249  -1   M      A01X+019606Y+011995X0198Y0197R090 S1      
327P3V3_AUX         R265  -1          A12X+019550Y+011992X0198Y0197R270 S2      
327P3V3_AUX         R610  -1   M      A12X+019143Y+011991X0198Y0197R270 S2      
327P3V3_AUX         R248  -1          A12X+018743Y+011991X0198Y0197R270 S2      
317P3V3_AUX         VIA   -    MD0100PA00X+019080Y+011720X0200Y         S0      
327P3V3_AUX         R244  -1   M      A01X+017819Y+011965X0198Y0197R090 S1      
327P3V3_AUX         R247  -1          A12X+017074Y+011975X0198Y0197R270 S2      
317P3V3_AUX         VIA   -    MD0100PA00X+017950Y+011680X0200Y         S0      
327P3V3_AUX         R62   -1   M      A01X+017263Y+011995X0198Y0197R090 S1      
327P3V3_AUX         R706  -1          A01X+016862Y+011995X0198Y0197R090 S1      
327P3V3_AUX         R213  -1          A01X+015553Y+011904X0198Y0197R090 S1      
317P3V3_AUX         VIA   -    MD0100PA00X+015553Y+011664X0200Y         S0      
317P3V3_AUX         VIA   -    MD0100PA00X+014122Y+012307X0200Y         S0      
327P3V3_AUX         L9    -1          A12X+013750Y+012310X0280Y0320     S2      
317P3V3_AUX         VIA   -    MD0100PA00X+014340Y+012170X0200Y         S0      
317P3V3_AUX         VIA   -    MD0100PA00X+002520Y+011630X0200Y    R270 S0      
327P3V3_AUX         R765  -1          A12X+001988Y+011620X0198Y0197     S2      
317P3V3_AUX         VIA   -    MD0100PA00X+004850Y+011256X0200Y    R180 S0      
327P3V3_AUX         R741  -1          A12X+004848Y+010620X0198Y0197     S2      
317P3V3_AUX         VIA   -    MD0100PA00X+033991Y+010859X0200Y         S0      
327P3V3_AUX         R13   -1          A12X+033749Y+010869X0198Y0197     S2      
317P3V3_AUX         VIA   -    MD0100PA00X+033991Y+010458X0200Y         S0      
327P3V3_AUX         R14   -1          A12X+033749Y+010468X0198Y0197     S2      
317P3V3_AUX         VIA   -    MD0100PA00X+027130Y+013290X0200Y         S0      
317P3V3_AUX         VIA   -    MD0100PA00X+026956Y+013099X0200Y         S0      
317P3V3_AUX         VIA   -    MD0100PA00X+028350Y+012600X0200Y         S0      
317P3V3_AUX         VIA   -    MD0100PA00X+031590Y+012590X0200Y         S0      
317P3V3_AUX         VIA   -    MD0100PA00X+031607Y+010841X0200Y         S0      
317P3V3_AUX         VIA   -    MD0100PA00X+027160Y+012140X0200Y         S0      
327P3V3_AUX         U14   -5          A01X+027107Y+011808X0220Y0320R180 S1      
327P3V3_AUX         L4    -1          A12X+026657Y+013157X0280Y0320     S2      
327P3V3_AUX         U19   -8          A12X+028655Y+011077X0170Y0700R090 S2      
327P3V3_AUX         C192  -1   M      A12X+028138Y+011739X0198Y0197     S2      
327P3V3_AUX         C240  -1          A12X+027401Y+012140X0198Y0197R180 S2      
327P3V3_AUX         R403  -1          A12X+031800Y+013018X0198Y0197R270 S2      
327P3V3_AUX         R193  -1          A12X+024170Y+009708X0198Y0197R090 S2      
317P3V3_AUX         VIA   -    MD0100PA00X+024071Y+009957X0200Y         S0      
327P3V3_AUX         R256  -1   M      A12X+024809Y+011006X0198Y0197R270 S2      
327P3V3_AUX         R257  -1          A12X+025211Y+011006X0198Y0197R270 S2      
327P3V3_AUX         R851  -1   M      A12X+024408Y+011132X0198Y0197R090 S2      
327P3V3_AUX         R253  -1   M      A12X+023958Y+010976X0198Y0197     S2      
317P3V3_AUX         VIA   -    MD0100PA00X+024016Y+010700X0200Y         S0      
327P3V3_AUX         R383  -1          A01X+018292Y+009600X0198Y0197     S1      
317P3V3_AUX         VIA   -    MD0100PA00X+018480Y+010030X0200Y         S0      
327P3V3_AUX         R246  -1          A12X+016673Y+011975X0198Y0197R270 S2      
327P3V3_AUX         R295  -1          A12X+018196Y+009652X0198Y0197R090 S2      
317P3V3_AUX         VIA   -    MD0100PA00X+018196Y+009926X0200Y         S0      
327P3V3_AUX         C148  -1   M      A12X+023350Y+009392X0198Y0197R270 S2      
327P3V3_AUX         U29   -5          A12X+023345Y+008654X0240Y0240R270 S2      
317P3V3_AUX         VIA   -    MD0100PA00X+023060Y+009170X0200Y         S0      
327P3V3_AUX         C157  -1   M      A12X+019483Y+007998X0198Y0197R270 S2      
327P3V3_AUX         U23   -5          A12X+018780Y+007997X0220Y0320R270 S2      
317P3V3_AUX         VIA   -    MD0100PA00X+020190Y+008330X0200Y         S0      
317P3V3_AUX         VIA   -    MD0100PA00X+030650Y+030150X0200Y         S0      
327P3V3_AUX         R615  -1          A01X+029200Y+029408X0198Y0197R270 S1      
327P3V3_AUX         R881  -1   M      A01X+029900Y+029458X0198Y0197R270 S1      
327P3V3_AUX         U51   -5          A01X+006330Y+024924X0140Y0440     S1      
327P3V3_AUX         U50   -5          A01X+008750Y+024924X0140Y0440     S1      
327P3V3_AUX         U41   -9          A01X+013826Y+021825X0110Y0360R090 S1      
327P3V3_AUX         U41   -8          A01X+013826Y+022022X0110Y0360R090 S1      
327P3V3_AUX         U41   -7          A01X+013826Y+022219X0110Y0360R090 S1      
327P3V3_AUX         R308  -1          A12X+010120Y+037172X0198Y0197R270 S2      
327P3V3_AUX         R72   -1          A01X+012033Y+024308X0198Y0197R270 S1      
317P3V3_AUX         VIA   -    MD0100PA00X+012288Y+024280X0200Y         S0      
327P3V3_AUX         C293  -1          A01X+013100Y+021774X0440Y0540R090 S1      
327P3V3_AUX         R406  -1          A01X+015958Y+022400X0198Y0197R180 S1      
317P3V3_AUX         VIA   -    MD0100PA00X+013250Y+022190X0200Y    R270 S0      
317P3V3_AUX         VIA   -    MD0100PA00X+013500Y+022120X0200Y    R270 S0      
317P3V3_AUX         VIA   -    MD0100PA00X+015964Y+022648X0200Y    R180 S0      
327P3V3_AUX         L7    -1          A12X+016582Y+021771X0280Y0320R270 S2      
317P3V3_AUX         VIA   -    MD0100PA00X+016265Y+021884X0200Y         S0      
317P3V3_AUX         VIA   -    MD0100PA00X+016120Y+023360X0200Y         S0      
327P3V3_AUX         L12   -1          A12X+016430Y+023310X0280Y0320R270 S2      
327P3V3_AUX         R717  -1   M      A12X+015830Y+023230X0198Y0197     S2      
317P3V3_AUX         VIA   -    MD0100PA00X+007090Y+024150X0200Y         S0      
327P3V3_AUX         U37   -1          A12X+006934Y+024770X0140Y0590     S2      
327P3V3_AUX         C158  -1   M      A12X+006950Y+023908X0198Y0197R090 S2      
317P3V3_AUX         VIA   -    MD0100PA00X+007500Y+021400X0200Y         S0      
327P3V3_AUX         R538  -1          A01X+008150Y+021962X0198Y0197R090 S1      
317P3V3_AUX         VIA   -    MD0100PA00X+007530Y+018388X0200Y         S0      
327P3V3_AUX         R563  -1          A01X+007280Y+018388X0198Y0197R270 S1      
327P3V3_AUX         U44   -5   M      A01X+006625Y+017254X0160Y0360     S1      
317P3V3_AUX         VIA   -    MD0100PA00X+006733Y+016927X0200Y         S0      
327P3V3_AUX         PR242 -1          A01X+005188Y+026080X0198Y0197R180 S1      
327P3V3_AUX         R238  -1          A01X+026940Y+028458X0198Y0197R270 S1      
317P3V3_AUX         VIA   -    MD0100PA00X+025292Y+005400X0200Y         S0      
327P3V3_AUX         U2    -8          A01X+009535Y+025062X0110Y0280     S1      
327P3V3_AUX         R183  -1          A12X+013058Y+036150X0198Y0197     S2      
317P3V3_AUX         VIA   -    MD0100PA00X+013300Y+036150X0200Y         S0      
317P3V3_AUX         VIA   -    MD0100PA00X+019867Y+031818X0200Y         S0      
327P3V3_AUX         R753  -1          A01X+022850Y+033192X0198Y0197R090 S1      
327P3V3_AUX         C19   -1   M      A01X+009350Y+025892X0198Y0197R090 S1      
327P3V3_AUX         R742  -1          A01X+009730Y+026088X0198Y0197R270 S1      
327P3V3_AUX         J4    -2          A01X+006988Y+028882X0110Y0630     S1      
327P3V3_AUX         J4    -4          A01X+007185Y+028882X0110Y0630     S1      
327P3V3_AUX         C234  -1          A01X+006975Y+027690X0280Y0320R180 S1      
327P3V3_AUX         C235  -1          A01X+007450Y+027708X0198Y0197R270 S1      
317P3V3_AUX         VIA   -    MD0100PA00X+007000Y+028000X0200Y         S0      
327P3V3_AUX         R163  -1          A12X+006410Y+032792X0198Y0197R270 S2      
317P3V3_AUX         VIA   -    MD0100PA00X+005660Y+032050X0200Y         S0      
327P3V3_AUX         OSC2  -4          A12X+007776Y+030190X0340Y0460R090 S2      
327P3V3_AUX         C318  -1   M      A12X+007572Y+029670X0198Y0197R180 S2      
327P3V3_AUX         R806  -1          A12X+007190Y+030692X0198Y0197R270 S2      
317P3V3_AUX         VIA   -    MD0100PA00X+007270Y+030120X0200Y         S0      
317P3V3_AUX         VIA   -    MD0100PA00X+022587Y+034503X0200Y         S0      
327P3V3_AUX         R508  -1          A01X+024043Y+031931X0198Y0197     S1      
327P3V3_AUX         R624  -1          A01X+024043Y+031351X0198Y0197     S1      
317P3V3_AUX         VIA   -    MD0100PA00X+024050Y+031658X0200Y         S0      
317P3V3_AUX         VIA   -    MD0100PA00X+009718Y+026332X0200Y    R090 S0      
317P3V3_AUX         VIA   -    MD0100PA00X+009080Y+025822X0200Y    R090 S0      
327P3V3_AUX         C500  -1   M      A01X+008650Y+025872X0198Y0197R090 S1      
327P3V3_AUX         C501  -1   M      A01X+006330Y+025772X0198Y0197R090 S1      
317P3V3_AUX         VIA   -    MD0100PA00X+006899Y+025700X0200Y    R090 S0      
317P3V3_AUX         VIA   -    MD0100PA00X+001920Y+010270X0200Y         S0      
327P3V3_AUX         C175  -1   M      A12X+002018Y+010550X0198Y0197     S2      
327P3V3_AUX         U24   -5          A12X+002766Y+010920X0170Y0240R090 S2      
317P3V3_AUX         VIA   -    MD0100PA00X+025500Y+008270X0200Y         S0      
327P3V3_AUX         C145  -1          A12X+011642Y+039700X0198Y0197R180 S2      
327P3V3_AUX         C194  -1          A12X+011510Y+040200X0280Y0320R270 S2      
327P3V3_AUX         R627  -1          A12X+010250Y+039992X0198Y0197R270 S2      
327P3V3_AUX         L19   -1          A12X+010750Y+040440X0280Y0320R180 S2      
327P3V3_AUX         R307  -1          A12X+010008Y+036400X0198Y0197     S2      
327P3V3_AUX         R301  -1          A12X+010400Y+036408X0198Y0197R090 S2      
327P3V3_AUX         R305  -1          A12X+010008Y+036000X0198Y0197     S2      
317P3V3_AUX         VIA   -    MD0100PA00X+032992Y+035602X0200Y         S0      
327P3V3_AUX         R408  -1          A01X+032992Y+035850X0198Y0197     S1      
317P3V3_AUX         VIA   -    MD0100PA00X+012642Y+005700X0200Y         S0      
327P3V3_AUX         U9    -5          A01X+011822Y+005524X0280Y0400R270 S1      
327P3V3_AUX         C276  -1   M      A01X+012642Y+005430X0198Y0197     S1      
317P3V3_AUX         VIA   -    MD0100PA00X+014832Y+035909X0200Y         S0      
327P3V3_AUX         U22   -10         A12X+015484Y+036318X0110Y0260R270 S2      
327P3V3_AUX         C236  -1   M      A12X+014805Y+036162X0198Y0197R270 S2      
327P3V3_AUX         U36   -5   M      A12X+024795Y+008654X0240Y0240R270 S2      
327P3V3_AUX         C149  -1          A12X+024800Y+009392X0198Y0197R270 S2      
317P3V3_AUX         VIA   -    MD0100PA00X+023454Y+007464X0200Y         S0      
327P3V3_AUX         R730  -1          A12X+023408Y+007100X0198Y0197     S2      
317P3V3_AUX         VIA   -    MD0100PA00X+033990Y+006910X0200Y         S0      
327P3V3_AUX         R504  -1          A01X+033738Y+007000X0198Y0197R180 S1      
317P3V3_AUX         VIA   -    MD0100PA00X+031602Y+006020X0200Y         S0      
327P3V3_AUX         C201  -1   M      A01X+031602Y+006270X0198Y0197     S1      
327P3V3_AUX         U32   -5          A01X+031758Y+006794X0140Y0490R270 S1      
327P3V3_AUX         R835  -1          A12X+005662Y+037630X0198Y0197R180 S2      
317P3V3_AUX         VIA   -    MD0100PA00X+024620Y+007460X0200Y         S0      
327P3V3_AUX         R274  -1          A12X+024518Y+007190X0198Y0197     S2      
317P3V3_AUX         VIA   -    MD0100PA00X+005260Y+037660X0200Y         S0      
327P3V3_AUX         R608  -1          A12X+005008Y+037600X0198Y0197     S2      
317P3V3_AUX         VIA   -    MD0100PA00X+007790Y+027470X0200Y         S0      
327P3V3_AUX         U37   -8          A12X+006934Y+026530X0140Y0590     S2      
327P3V3_AUX         C159  -1   M      A12X+007430Y+027452X0198Y0197R270 S2      
327P3V3_AUX         R299  -1          A12X+006600Y+027758X0198Y0197R090 S2      
327P3V3_AUX         R298  -1   M      A12X+007000Y+027758X0198Y0197R090 S2      
327P3V3_AUX         R304  -1          A12X+007500Y+039008X0198Y0197R090 S2      
317P3V3_AUX         VIA   -    MD0100PA00X+007100Y+039440X0200Y         S0      
327P3V3_AUX         R525  -1          A12X+006900Y+039008X0198Y0197R090 S2      
317P3V3_AUX         VIA   -    MD0100PA00X+011920Y+040618X0200Y         S0      
327P3V3_AUX         R45   -1          A01X+011650Y+040618X0198Y0197R270 S1      
317P3V3_AUX         VIA   -    MD0100PA00X+008250Y+039760X0200Y         S0      
327P3V3_AUX         R749  -1          A12X+008250Y+039992X0198Y0197R270 S2      
327P3V3_AUX         R621  -1          A12X+009450Y+039992X0198Y0197R270 S2      
317P3V3_AUX         VIA   -    MD0100PA00X+009050Y+039760X0200Y         S0      
327P3V3_AUX         R414  -1          A01X+032992Y+038100X0198Y0197     S1      
327P3V3_AUX         U21   -16         A12X+016130Y+040936X0140Y0590R090 S2      
327P3V3_AUX         C246  -1          A01X+014790Y+035168X0198Y0197R270 S1      
327P3V3_AUX         R496  -1          A01X+016108Y+035050X0198Y0197R180 S1      
317P3V3_AUX         VIA   -    MD0100PA00X+018060Y+036020X0200Y         S0      
327P3V3_AUX         U22   -1          A12X+017138Y+036318X0110Y0260R270 S2      
327P3V3_AUX         C237  -1   M      A12X+018140Y+036272X0198Y0197R270 S2      
327P3V3_AUX         C219  -1   M      A12X+017750Y+036272X0198Y0197R270 S2      
317P3V3_AUX         VIA   -    MD0100PA00X+005290Y+036000X0200Y         S0      
327P3V3_AUX         PC229 -1          A01X+004324Y+030428X0440Y0540R270 S1      
327P3V3_AUX         R870  -1          A12X+014568Y+040175X0198Y0197R180 S2      
327P3V3_AUX         R740  -1   M      A12X+025338Y+035520X0198Y0197     S2      
327P3V3_AUX         R739  -1          A12X+025338Y+035910X0198Y0197     S2      
327P3V3_AUX         R738  -1   M      A12X+022392Y+037348X0198Y0197R270 S2      
327P3V3_AUX         R42   -1          A12X+029416Y+036598X0198Y0197R270 S2      
327P3V3_AUX         C248  -1          A12X+033092Y+039070X0198Y0197R180 S2      
327P3V3_AUX         C143  -1   M      A01X+029330Y+035851X0198Y0197R180 S1      
317P3V3_AUX         VIA   -    MD0100PA00X+027570Y+040350X0200Y         S0      
327P3V3_AUX         R126  -2          A01X+027308Y+039950X0198Y0197     S1      
317P3V3_AUX         VIA   -    MD0100PA00X+033970Y+029300X0200Y         S0      
327P3V3_AUX         PR498 -1          A01X+033690Y+029208X0198Y0197R180 S1      
327P3V3_AUX         C146  -1   M      A12X+014882Y+040800X0198Y0197     S2      
317P3V3_AUX         VIA   -    MD0100PA00X+014960Y+041050X0200Y    R090 S0      
317P3V3_AUX         VIA   -    MD0100PA00X+014152Y+039970X0200Y    R090 S0      
317P3V3_AUX         VIA   -    MD0100PA00X+026532Y+039229X0200Y         S0      
327P3V3_AUX         R736  -1          A12X+024325Y+039582X0198Y0197R090 S2      
317P3V3_AUX         VIA   -    MD0100PA00X+023975Y+039497X0200Y         S0      
317P3V3_AUX         VIA   -    MD0100PA00X+022052Y+038490X0200Y         S0      
317P3V3_AUX         VIA   -    MD0100PA00X+028750Y+037690X0200Y    R180 S0      
327P3V3_AUX         R59   -1          A01X+028448Y+037508X0198Y0197R270 S1      
317P3V3_AUX         VIA   -    MD0100PA00X+028776Y+036620X0200Y    R180 S0      
327P3V3_AUX         J10   -7          A01X+030351Y+036558X0240Y0650R090 S1      
317P3V3_AUX         VIA   -    MD0100PA00X+029550Y+035492X0200Y    R180 S0      
327P3V3_AUX         C144  -1   M      A01X+029330Y+036301X0198Y0197R180 S1      
327P3V3_AUX         C300  -1   M      A12X+021688Y+037213X0198Y0197R180 S2      
327P3V3_AUX         R735  -1          A12X+020018Y+035975X0198Y0197R180 S2      
327P3V3_AUX         R667  -1          A12X+025030Y+037088X0198Y0197R090 S2      
317P3V3_AUX         VIA   -    MD0100PA00X+024375Y+036973X0200Y         S0      
327P3V3_AUX         J5    -7          A01X+023855Y+036558X0240Y0650R090 S1      
317P3V3_AUX         VIA   -    MD0100PA00X+022570Y+036250X0200Y         S0      
317P3V3_AUX         VIA   -    MD0100PA00X+022463Y+036982X0200Y         S0      
317P3V3_AUX         VIA   -    MD0100PA00X+019605Y+035877X0200Y         S0      
317P3V3_AUX         VIA   -    MD0100PA00X+016130Y+035460X0200Y         S0      
317P3V3_AUX         VIA   -    MD0100PA00X+030891Y+036264X0200Y         S0      
327P3V3_AUX         PR274 -1          A01X+032982Y+027897X0198Y0197R270 S1      
317P3V3_AUX         VIA   -    MD0100PA00X+032716Y+027897X0200Y         S0      
317P3V3_AUX         VIA   -    MD0100PA00X+033150Y+038330X0200Y         S0      
317P3V3_AUX         VIA   -    MD0100PA00X+026625Y+029790X0200Y         S0      
317P3V3_AUX         VIA   -    MD0100PA00X+014394Y+035415X0200Y    R180 S0      
317P3V3_AUX         VIA   -    M      A01X+005150Y+025820X0200Y         S2      
017P3V3_AUX         VIA   -    M      A12X+005150Y+025820X0260Y         S2      
017P3V3_AUX               -    MD0100PA00X+005150Y+025820                       
327P3V3_AUX         PC225 -1   M      A01X+004994Y+030572X0198Y0197R090 S1      
327P3V3_AUX         PL35  -2          A01X+002826Y+029522X0848Y1300R090 S1      
327P3V3_AUX         PC227 -1          A01X+002644Y+030410X0440Y0540R270 S1      
327P3V3_AUX         PC228 -1          A01X+003484Y+030407X0440Y0540R270 S1      
327P3V3_AUX         PC226 -1          A01X+001804Y+030412X0440Y0540R270 S1      
317P3V3_AUX         VIA   -    MD0100PA00X+027110Y+034658X0200Y         S0      
317P3V3_AUX         VIA   -    MD0100PA00X+003064Y+030121X0200Y    R090 S0      
317P3V3_AUX         VIA   -    MD0100PA00X+002224Y+030124X0200Y    R090 S0      
317P3V3_AUX         VIA   -    M      A01X+003064Y+030460X0200Y    R090 S2      
017P3V3_AUX         VIA   -    M      A12X+003064Y+030460X0260Y    R090 S2      
017P3V3_AUX               -    MD0100PA00X+003064Y+030460                       
317P3V3_AUX         VIA   -    M      A01X+002224Y+030463X0200Y    R090 S2      
017P3V3_AUX         VIA   -    M      A12X+002224Y+030463X0260Y    R090 S2      
017P3V3_AUX               -    MD0100PA00X+002224Y+030463                       
317P3V3_AUX         VIA   -    MD0100PA00X+001374Y+029989X0200Y    R090 S0      
317P3V3_AUX         VIA   -    MD0100PA00X+001374Y+030328X0200Y    R090 S0      
317P3V3_AUX         VIA   -    MD0100PA00X+004744Y+030134X0200Y    R090 S0      
317P3V3_AUX         VIA   -    M      A01X+003904Y+030130X0200Y    R090 S2      
017P3V3_AUX         VIA   -    M      A12X+003904Y+030130X0260Y    R090 S2      
017P3V3_AUX               -    MD0100PA00X+003904Y+030130                       
317P3V3_AUX         VIA   -    M      A01X+004744Y+030422X0200Y    R090 S2      
017P3V3_AUX         VIA   -    M      A12X+004744Y+030422X0260Y    R090 S2      
017P3V3_AUX               -    MD0100PA00X+004744Y+030422                       
317P3V3_AUX         VIA   -    MD0100PA00X+003904Y+030428X0200Y    R090 S0      
327P3V3_AUX         C244  -1   M      A01X+014394Y+035172X0198Y0197R270 S1      
327P3V3_AUX         C249  -1   M      A12X+033092Y+038664X0198Y0197R180 S2      
327P3V3_AUX         U40   -24         A12X+021542Y+036730X0140Y0590R090 S2      
327P3V3_AUX         R497  -1          A01X+022280Y+037935X0198Y0197R270 S1      
327P3V3_AUX         R136  -1   M      A01X+022356Y+038326X0198Y0197     S1      
327P3V3_AUX         U22   -6          A12X+016213Y+035984X0110Y0260     S2      
327P3V3_AUX         R712  -1          A12X+017670Y+034682X0198Y0197R270 S2      
327P3V3_AUX         U17   -2   M      A01X+014301Y+036520X0170Y0670     S1      
327P3V3_AUX         R737  -1          A01X+007642Y+025920X0198Y0197     S1      
327P3V3_AUX         U3    -8          A01X+007345Y+025072X0110Y0280     S1      
327P3V3_AUX         C20   -1   M      A01X+007250Y+025842X0198Y0197R090 S1      
327P3V3_AUX         PC239 -2          A01X+004844Y+025568X0198Y0197R090 S1      
327P3V3_AUX         PR534 -2   M      A01X+005244Y+025568X0198Y0197R090 S1      
327P3V3_AUX         R657  -1          A01X+013792Y+033156X0198Y0197R270 S1      
327P3V3_AUX         R656  -1   M      A01X+014192Y+033156X0198Y0197R270 S1      
327P3V3_AUX         R554  -1          A01X+022060Y+032788X0198Y0197R270 S1      
327P3V3_AUX         C313  -1   M      A01X+019228Y+031110X0198Y0197R180 S1      
327P3V3_AUX         U55   -5          A01X+020321Y+031104X0130Y0460R090 S1      
317P3V3_AUX         VIA   -    MD0100PA00X+016670Y+013236X0200Y         S0      
327P3V3_AUX         R56   -1          A01X+016800Y+013492X0198Y0197R090 S1      
327P3V3_AUX         R641  -1          A12X+005000Y+035608X0198Y0197R090 S2      
327P3V3_AUX         R391  -1          A01X+029000Y+006558X0198Y0197R270 S1      
327P3V3_AUX         R593  -1          A01X+004750Y+035508X0198Y0197R270 S1      
327P3V3_AUX         R595  -1          A01X+005008Y+036400X0198Y0197R180 S1      
327P3V3_AUX         R888  -1   M      A01X+005008Y+036000X0180Y0200     S1      
327P2V5_AUX         U39   -1          A01X+032929Y+013831X0110Y0360R180 S1      
327P2V5_AUX         U39   -3          A01X+032535Y+013831X0110Y0360R180 S1      
327P2V5_AUX         U39   -2          A01X+032732Y+013831X0110Y0360R180 S1      
327P2V5_AUX         R791  -1          A12X+021381Y+027882X0198Y0197R090 S2      
327P2V5_AUX         R780  -1          A12X+021786Y+027881X0198Y0197R090 S2      
327P2V5_AUX         R779  -1          A12X+021683Y+028276X0198Y0197     S2      
317P2V5_AUX         VIA   -    MD0100PA00X+021936Y+028158X0200Y         S0      
317P2V5_AUX         VIA   -    MD0100PA00X+021934Y+028414X0200Y         S0      
327P2V5_AUX         U1    -B1         A01X+028761Y+020908X0145Y         S1      
327P2V5_AUX         C6    -1          A12X+028124Y+020951X0198Y0197     S2      
317P2V5_AUX         VIA   -    M      A01X+028611Y+021059X0180Y         S2      
017P2V5_AUX         VIA   -    M      A12X+028611Y+021059X0260Y         S2      
017P2V5_AUX               -    MD0100PA00X+028611Y+021059                       
327P2V5_AUX         U1    -R9         A01X+031280Y+016814X0145Y         S1      
327P2V5_AUX         C8    -1          A12X+031783Y+016938X0198Y0197R180 S2      
317P2V5_AUX         VIA   -    MD0100PA00X+031493Y+016814X0180Y    R045 S0      
327P2V5_AUX         R156  -1          A01X+016046Y+014243X0198Y0197R090 S1      
317P2V5_AUX         VIA   -    MD0100PA00X+015900Y+013500X0200Y         S0      
327P2V5_AUX         VIA   -           A12X+033770Y+014430X0260Y         S2      
327P2V5_AUX         C289  -1          A01X+033650Y+013974X0440Y0540R090 S1      
327P2V5_AUX         C291  -1          A01X+033328Y+014529X0198Y0197R090 S1      
327P2V5_AUX         R829  -1          A01X+032920Y+014442X0198Y0197R180 S1      
317P2V5_AUX         VIA   -    M      A01X+033164Y+014174X0200Y         S2      
017P2V5_AUX         VIA   -    M      A12X+033164Y+014174X0260Y         S2      
017P2V5_AUX               -    MD0100PA00X+033164Y+014174                       
317P2V5_AUX         VIA   -    MD0100PA00X+033174Y+013824X0200Y         S0      
317P2V5_AUX         VIA   -    MD0100PA00X+032809Y+014161X0200Y         S0      
327P2E_PCH_TX_DP    U5    -AE4        A01X+024604Y+023060X0160Y    R180 S1      
317P2E_PCH_TX_DP    VIA   -    MD0100PA00X+024760Y+023215X0180Y         S0      
327P2E_PCH_TX_DP    C24   -1          A12X+024643Y+024246X0198Y0197R270 S2      
327P2E_PCH_TX_DN    U5    -AE5        A01X+024289Y+023060X0160Y    R180 S1      
317P2E_PCH_TX_DN    VIA   -    MD0100PA00X+024445Y+023215X0180Y         S0      
327P2E_PCH_TX_DN    C25   -1          A12X+024243Y+024246X0198Y0197R270 S2      
327m0588            U5    -V10        A01X+022715Y+020855X0160Y    R180 S1      
327m0588            C81   -1          A12X+022592Y+021014X0198Y0197     S2      
327m0588            C80   -1          A01X+027204Y+024853X0198Y0197R270 S1      
327m0588            L14   -2          A12X+027206Y+025460X0280Y0320R180 S2      
327m0588            VIA   -           A12X+026665Y+025264X0260Y         S2      
317m0588            VIA   -    MD0100PA00X+022870Y+021010X0180Y    R180 S0      
317m0588            VIA   -    MD0100PA00X+027230Y+025100X0200Y         S0      
317m0589            VIA   -    MD0100PA00X+023185Y+021010X0180Y    R180 S0      
327m0589            C69   -1          A12X+023102Y+021266X0198Y0197R270 S2      
327m0589            U5    -V9         A01X+023030Y+020855X0160Y    R180 S1      
327m0589            C61   -1          A01X+027958Y+024873X0198Y0197R270 S1      
327m0589            L10   -2          A12X+027815Y+025460X0280Y0320R180 S2      
327m0589            VIA   -           A12X+027803Y+024911X0260Y         S2      
317m0589            VIA   -    MD0100PA00X+028008Y+025133X0200Y         S0      
317m0589            VIA   -    MD0100PA00X+027620Y+025150X0200Y         S0      
327m0590            U5    -V8         A01X+023344Y+020855X0160Y    R180 S1      
327m0590            C130  -1          A12X+023506Y+021266X0198Y0197R270 S2      
327m0590            C128  -1          A12X+028338Y+024873X0198Y0197R090 S2      
327m0590            L16   -2          A12X+028399Y+025460X0280Y0320R180 S2      
327m0590            VIA   -           A12X+028970Y+025568X0260Y         S2      
317m0590            VIA   -    MD0100PA00X+028680Y+025140X0200Y         S0      
317m0590            VIA   -    MD0100PA00X+028397Y+025137X0200Y         S0      
317m0590            VIA   -    MD0100PA00X+023500Y+021010X0180Y    R180 S0      
327m0591            U5    -N5         A01X+024289Y+019280X0160Y    R180 S1      
327m0591            C49   -1          A12X+024303Y+019415X0198Y0197     S2      
327m0591            C46   -1          A12X+026587Y+014418X0198Y0197R270 S2      
327m0591            L5    -2          A12X+027231Y+014298X0280Y0320R180 S2      
317m0591            VIA   -    MD0100PA00X+024445Y+019124X0180Y    R180 S0      
317m0591            VIA   -    MD0100PA00X+026900Y+014195X0200Y    R090 S0      
317m0591            VIA   -    MD0100PA00X+026900Y+014445X0200Y    R090 S0      
327m0592            VIA   -           A12X+028600Y+015700X0260Y         S2      
327m0592            C40   -1          A12X+028100Y+016010X0280Y0320     S2      
327m0592            U5    -K10        A01X+022715Y+018335X0160Y    R180 S1      
327m0592            C41   -1          A12X+022827Y+018494X0198Y0197R180 S2      
327m0592            L3    -2          A12X+027761Y+015466X0280Y0320R270 S2      
317m0592            VIA   -    MD0100PA00X+022870Y+018180X0180Y    R180 S0      
317m0592            VIA   -    MD0100PA00X+028340Y+015354X0200Y         S0      
317m0592            VIA   -    MD0100PA00X+028590Y+015354X0200Y         S0      
327P1V8_AUX         R854  -1          A01X+028500Y+007592X0198Y0197R090 S1      
317P1V8_AUX         VIA   -    MD0100PA00X+022784Y+027577X0200Y         S0      
327P1V8_AUX         R783  -1          A12X+022544Y+027577X0198Y0197     S2      
327P1V8_AUX         R856  -1   M      A01X+028100Y+007592X0198Y0197R090 S1      
327P1V8_AUX         R858  -1   M      A01X+027700Y+007592X0198Y0197R090 S1      
317P1V8_AUX         VIA   -    MD0100PA00X+027980Y+007270X0200Y         S0      
327P1V8_AUX         Q5    -4          A12X+026399Y+036858X0280Y0400     S2      
317P1V8_AUX         VIA   -    MD0100PA00X+027199Y+036236X0200Y         S0      
317P1V8_AUX         VIA   -    MD0100PA00X+028586Y+033613X0200Y         S0      
327P1V8_AUX         R645  -1          A12X+027020Y+037200X0280Y0320R180 S2      
327P1V8_AUX         U41   -1          A01X+015047Y+021628X0110Y0360R090 S1      
327P1V8_AUX         U41   -3          A01X+015047Y+022022X0110Y0360R090 S1      
327P1V8_AUX         U41   -2          A01X+015047Y+021825X0110Y0360R090 S1      
327P1V8_AUX         R781  -1          A12X+020666Y+028678X0198Y0197R180 S2      
327P1V8_AUX         R793  -1          A12X+020181Y+028678X0198Y0197     S2      
327P1V8_AUX         VIA   -           A12X+020040Y+029153X0260Y         S2      
317P1V8_AUX         VIA   -    MD0100PA00X+020426Y+028669X0200Y         S0      
317P1V8_AUX         VIA   -    MD0100PA00X+026902Y+026699X0200Y         S0      
317P1V8_AUX         VIA   -    MD0100PA00X+026710Y+026500X0200Y         S0      
317P1V8_AUX         VIA   -    MD0100PA00X+028436Y+026403X0200Y    R180 S0      
317P1V8_AUX         VIA   -    M      A01X+028436Y+026703X0200Y    R180 S2      
017P1V8_AUX         VIA   -    M      A12X+028436Y+026703X0260Y    R180 S2      
017P1V8_AUX               -    MD0100PA00X+028436Y+026703                       
317P1V8_AUX         VIA   -    MD0100PA00X+028003Y+026410X0200Y    R180 S0      
317P1V8_AUX         VIA   -    MD0100PA00X+028003Y+026710X0200Y    R180 S0      
327P1V8_AUX         L14   -1          A12X+027206Y+026040X0280Y0320R180 S2      
327P1V8_AUX         L10   -1          A12X+027815Y+026040X0280Y0320R180 S2      
327P1V8_AUX         L16   -1          A12X+028399Y+026040X0280Y0320R180 S2      
317P1V8_AUX         VIA   -    MD0100PA00X+029150Y+028517X0200Y         S0      
317P1V8_AUX         VIA   -    MD0100PA00X+029150Y+028767X0200Y         S0      
327P1V8_AUX         C87   -1          A12X+024450Y+021342X0198Y0197R270 S2      
327P1V8_AUX         U5    -V6  M      A01X+023974Y+020855X0160Y    R180 S1      
327P1V8_AUX         U5    -U6         A01X+023974Y+020540X0160Y    R180 S1      
317P1V8_AUX         VIA   -    MD0100PA00X+024130Y+021010X0180Y         S0      
327P1V8_AUX         C142  -1          A01X+015174Y+020900X0440Y0540     S1      
327P1V8_AUX         C294  -1          A01X+015678Y+021257X0198Y0197     S1      
317P1V8_AUX         VIA   -    MD0100PA00X+015380Y+021490X0200Y         S0      
317P1V8_AUX         VIA   -    MD0100PA00X+015374Y+021744X0200Y         S0      
327P1V8_AUX         R831  -1          A01X+015603Y+021664X0198Y0197R090 S1      
317P1V8_AUX         VIA   -    MD0100PA00X+015190Y+021320X0200Y         S0      
327P1V8_AUX         U5    -M13        A01X+021770Y+018965X0160Y    R180 S1      
327P1V8_AUX         U5    -L13        A01X+021770Y+018650X0160Y    R180 S1      
327P1V8_AUX         C89   -1          A12X+021626Y+018297X0198Y0197R090 S2      
327P1V8_AUX         C116  -1          A12X+021686Y+018684X0198Y0197R270 S2      
317P1V8_AUX         VIA   -    MD0100PA00X+021925Y+018810X0180Y    R180 S0      
327P1V8_AUX         U5    -J8         A01X+023344Y+018020X0160Y    R180 S1      
327P1V8_AUX         U5    -H8         A01X+023344Y+017705X0160Y    R180 S1      
327P1V8_AUX         C105  -1          A12X+023795Y+017571X0198Y0197R270 S2      
317P1V8_AUX         VIA   -    MD0100PA00X+023500Y+017550X0180Y         S0      
317P1V8_AUX         VIA   -    MD0100PA00X+023500Y+017865X0180Y         S0      
327P1V8_AUX         U5    -J12        A01X+022085Y+018020X0160Y    R180 S1      
327P1V8_AUX         U5    -H12        A01X+022085Y+017705X0160Y    R180 S1      
327P1V8_AUX         C95   -1          A12X+022306Y+017635X0198Y0197     S2      
327P1V8_AUX         C100  -1          A12X+022306Y+017234X0198Y0197     S2      
317P1V8_AUX         VIA   -    MD0100PA00X+022240Y+017865X0180Y    R180 S0      
327P1V8_AUX         R208  -1          A12X+015304Y+014106X0198Y0197     S2      
327P1V8_AUX         R154  -1          A01X+015643Y+014241X0198Y0197R090 S1      
327P1V8_AUX         R232  -1          A01X+015258Y+014200X0198Y0197R180 S1      
327P1V8_AUX         R214  -1          A01X+015650Y+013558X0198Y0197R270 S1      
317P1V8_AUX         VIA   -    MD0100PA00X+015532Y+013944X0200Y    R090 S0      
317P1V8_AUX         VIA   -    MD0100PA00X+015405Y+013710X0200Y    R090 S0      
327P1V8_AUX         L5    -1          A12X+027231Y+014878X0280Y0320R180 S2      
327P1V8_AUX         L3    -1          A12X+027181Y+015466X0280Y0320R270 S2      
327P1V8_AUX         C126  -1          A12X+027773Y+014878X0280Y0320R180 S2      
317P1V8_AUX         VIA   -    MD0100PA00X+026844Y+015080X0200Y         S0      
317P1V8_AUX         VIA   -    MD0100PA00X+026594Y+015080X0200Y         S0      
317P1V8_AUX         VIA   -    MD0100PA00X+026594Y+015330X0200Y         S0      
317P1V8_AUX         VIA   -    MD0100PA00X+026844Y+015330X0200Y         S0      
327P1V8_AUX         C124  -1          A01X+029138Y+013830X0280Y0320R270 S1      
327P1V8_AUX         C114  -1          A01X+027803Y+013724X0198Y0197R090 S1      
327P1V8_AUX         C119  -1          A01X+027270Y+013725X0198Y0197R090 S1      
317P1V8_AUX         VIA   -    MD0100PA00X+021925Y+020380X0180Y    R180 S0      
317P1V8_AUX         VIA   -    MD0100PA00X+021925Y+021325X0180Y    R180 S0      
317P1V8_AUX         VIA   -    MD0100PA00X+021925Y+021010X0180Y    R180 S0      
317P1V8_AUX         VIA   -    MD0100PA00X+021925Y+020696X0180Y    R180 S0      
317P1V8_AUX         VIA   -    MD0100PA00X+021299Y+021325X0180Y    R180 S0      
317P1V8_AUX         VIA   -    MD0100PA00X+022240Y+019751X0180Y    R180 S0      
317P1V8_AUX         VIA   -    MD0100PA00X+021925Y+019751X0180Y    R180 S0      
317P1V8_AUX         VIA   -    MD0100PA00X+021925Y+020066X0180Y    R180 S0      
317P1V8_AUX         VIA   -    MD0100PA00X+022240Y+019124X0180Y         S0      
327P1V8_AUX         C121  -1          A12X+021607Y+021132X0280Y0320R180 S2      
327P1V8_AUX         C111  -1          A12X+021596Y+019785X0198Y0197R270 S2      
327P1V8_AUX         C106  -1          A12X+021860Y+021603X0198Y0197     S2      
327P1V8_AUX         C102  -1          A12X+022246Y+021614X0198Y0197R180 S2      
327P1V8_AUX         C109  -1          A12X+022479Y+019388X0198Y0197     S2      
327P1V8_AUX         C93   -1          A12X+022871Y+019350X0198Y0197R270 S2      
327P1V8_AUX         U5    -N12        A01X+022085Y+019280X0160Y    R180 S1      
327P1V8_AUX         U5    -N13        A01X+021770Y+019280X0160Y    R180 S1      
327P1V8_AUX         U5    -P12        A01X+022085Y+019595X0160Y    R180 S1      
327P1V8_AUX         U5    -P13 M      A01X+021770Y+019595X0160Y    R180 S1      
327P1V8_AUX         U5    -R12        A01X+022085Y+019910X0160Y    R180 S1      
327P1V8_AUX         U5    -R13        A01X+021770Y+019910X0160Y    R180 S1      
327P1V8_AUX         U5    -T13        A01X+021770Y+020225X0160Y    R180 S1      
327P1V8_AUX         U5    -U13        A01X+021770Y+020540X0160Y    R180 S1      
327P1V8_AUX         U5    -V13        A01X+021770Y+020855X0160Y    R180 S1      
327P1V8_AUX         U5    -W13        A01X+021770Y+021170X0160Y    R180 S1      
327P1V8_AUX         U5    -W14        A01X+021455Y+021170X0160Y    R180 S1      
317P1V8_AUX         VIA   -    MD0100PA00X+025900Y+004750X0200Y         S0      
327P1V8_AUX         R885  -1          A12X+026142Y+004900X0198Y0197R180 S2      
327m0593            VIA   -           A12X+026420Y+017230X0260Y         S2      
327m0593            U5    -M6         A01X+023974Y+018965X0160Y    R180 S1      
327m0593            C73   -1          A12X+024697Y+019477X0198Y0197R180 S2      
327m0593            C67   -1          A12X+026390Y+016250X0198Y0197R090 S2      
327m0593            C63   -1          A12X+026890Y+016250X0198Y0197R090 S2      
327m0593            C71   -1          A12X+023802Y+018994X0198Y0197R090 S2      
327m0593            L11   -2          A12X+027010Y+017050X0280Y0320R090 S2      
317m0593            VIA   -    MD0100PA00X+024130Y+018810X0180Y    R180 S0      
327m0593            VIA   -           A12X+025920Y+016360X0260Y         S2      
327m0593            VIA   -           A12X+025850Y+016900X0260Y         S2      
317m0593            VIA   -    MD0100PA00X+026523Y+016498X0200Y    R270 S0      
317m0593            VIA   -    MD0100PA00X+026913Y+016498X0200Y    R270 S0      
327m0594            VIA   -           A12X+016900Y+019900X0260Y         S2      
317m0594            VIA   -    MD0100PA00X+016538Y+020127X0200Y         S0      
327m0594            U5    -U21        A01X+019250Y+020540X0160Y    R180 S1      
327m0594            C140  -1          A12X+019332Y+020620X0198Y0197R180 S2      
317m0594            VIA   -    MD0100PA00X+019094Y+020380X0180Y    R180 S0      
327m0594            R280  -2          A12X+016256Y+020230X0198Y0197R180 S2      
327m0594            R281  -2          A12X+016356Y+020630X0198Y0197R180 S2      
327m0594            VIA   -           A12X+016400Y+019770X0260Y         S2      
317m0594            VIA   -    MD0100PA00X+016614Y+020596X0200Y         S0      
327m0595            VIA   -           A12X+015750Y+021470X0260Y         S2      
327m0595            R189  -1          A12X+015670Y+025740X0198Y0197R270 S2      
327m0595            R188  -1   M      A12X+016076Y+025739X0198Y0197R270 S2      
327m0595            R196  -1          A12X+015696Y+024944X0198Y0197R270 S2      
327m0595            R195  -1   M      A12X+016097Y+024944X0198Y0197R270 S2      
327m0595            R197  -1   M      A12X+016501Y+024944X0198Y0197R270 S2      
327m0595            R194  -1   M      A12X+016480Y+025739X0198Y0197R270 S2      
327m0595            R191  -1   M      A12X+016993Y+025726X0198Y0197R270 S2      
327m0595            R190  -1   M      A12X+017399Y+025726X0198Y0197R270 S2      
327m0595            U5    -V22        A01X+018935Y+020855X0160Y    R180 S1      
327m0595            VIA   -    M      A12X+016952Y+025281X0260Y         S2      
317m0595            VIA   -    MD0100PA00X+016259Y+021008X0200Y         S0      
327m0595            R278  -2          A12X+015245Y+020937X0198Y0197R270 S2      
327m0595            R279  -2          A12X+015647Y+020937X0198Y0197R270 S2      
317m0595            VIA   -    MD0100PA00X+016259Y+021258X0200Y         S0      
317m0595            VIA   -    MD0100PA00X+019094Y+021010X0180Y    R180 S0      
317m0595            VIA   -    MD0100PA00X+017440Y+025474X0200Y         S0      
327m0595            C139  -1          A12X+019332Y+020970X0198Y0197R180 S2      
327P1V2_AUX_VCC     PU41  -10         A01X+032754Y+028319X0100Y0280R270 S1      
327P1V2_AUX_VCC     PU41  -6          A01X+031612Y+028319X0100Y0280R270 S1      
317P1V2_AUX_VCC     VIA   -    MD0100PA00X+033646Y+028320X0200Y         S0      
327P1V2_AUX_VCC     PR539 -2          A01X+033384Y+027897X0198Y0197R090 S1      
327P1V2_AUX_VCC     PC250 -1   M      A01X+033383Y+028320X0198Y0197R090 S1      
317P1V2_AUX_VCC     VIA   -    M      A01X+031227Y+028211X0200Y         S2      
017P1V2_AUX_VCC     VIA   -    M      A12X+031227Y+028211X0260Y         S2      
017P1V2_AUX_VCC           -    MD0100PA00X+031227Y+028211                       
327P1V2_AUX_MODE    PU41  -7          A01X+031986Y+028240X0100Y0280     S1      
327P1V2_AUX_MODE    PR496 -1          A01X+030846Y+027326X0198Y0197R180 S1      
327P1V2_AUX_MODE    VIA   -    M      A01X+031376Y+027476X0300Y         S1      
317P1V2_AUX         VIA   -    MD0100PA00X+021972Y+028673X0200Y         S0      
327P1V2_AUX         R795  -1          A12X+021712Y+029072X0198Y0197R270 S2      
327P1V2_AUX         R782  -1          A12X+021683Y+028678X0198Y0197     S2      
327P1V2_AUX         R784  -1          A12X+022229Y+028686X0198Y0197R090 S2      
317P1V2_AUX         VIA   -    MD0100PA00X+031431Y+021374X0180Y         S0      
327P1V2_AUX         C221  -1          A12X+031488Y+021614X0198Y0197     S2      
327P1V2_AUX         U1    -A9         A01X+031280Y+021223X0145Y         S1      
317P1V2_AUX         VIA   -    MD0100PA00X+028610Y+021372X0180Y         S0      
327P1V2_AUX         C3    -1          A12X+028124Y+021353X0198Y0197     S2      
327P1V2_AUX         U1    -A1         A01X+028761Y+021223X0145Y         S1      
317P1V2_AUX         VIA   -    MD0100PA00X+031431Y+021059X0180Y         S0      
327P1V2_AUX         C9    -1          A12X+031711Y+021158X0198Y0197R090 S2      
327P1V2_AUX         U1    -B9         A01X+031280Y+020908X0145Y         S1      
317P1V2_AUX         VIA   -    MD0100PA00X+031431Y+020429X0180Y         S0      
327P1V2_AUX         R324  -1          A12X+032169Y+020366X0198Y0197R180 S2      
327P1V2_AUX         C169  -1   M      A12X+032169Y+020766X0198Y0197R180 S2      
327P1V2_AUX         U1    -D9         A01X+031280Y+020278X0145Y         S1      
317P1V2_AUX         VIA   -    MD0100PA00X+029541Y+021059X0180Y    R270 S0      
327P1V2_AUX         C4    -1          A12X+029828Y+020585X0198Y0197R180 S2      
327P1V2_AUX         U1    -B3         A01X+029391Y+020908X0145Y         S1      
317P1V2_AUX         VIA   -    MD0100PA00X+028610Y+020429X0180Y         S0      
327P1V2_AUX         C5    -1          A12X+028219Y+020485X0198Y0197R090 S2      
327P1V2_AUX         U1    -D1         A01X+028761Y+020278X0145Y         S1      
327P1V2_AUX         U1    -C1         A01X+028761Y+020594X0145Y         S1      
317P1V2_AUX         VIA   -    MD0100PA00X+015194Y+020371X0200Y         S0      
327P1V2_AUX         R278  -1          A12X+015245Y+020622X0198Y0197R270 S2      
327P1V2_AUX         R280  -1          A12X+015941Y+020230X0198Y0197R180 S2      
317P1V2_AUX         VIA   -    MD0100PA00X+031431Y+019484X0180Y         S0      
327P1V2_AUX         C2    -1          A12X+031698Y+019552X0198Y0197R090 S2      
327P1V2_AUX         U1    -G9         A01X+031280Y+019334X0145Y         S1      
317P1V2_AUX         VIA   -    MD0100PA00X+031116Y+019799X0180Y         S0      
327P1V2_AUX         U1    -F8         A01X+030966Y+019649X0145Y         S1      
317P1V2_AUX         VIA   -    MD0100PA00X+030801Y+019484X0180Y         S0      
327P1V2_AUX         C229  -2          A12X+030551Y+019304X0198Y0197R270 S2      
327P1V2_AUX         U1    -G7         A01X+030650Y+019334X0145Y         S1      
317P1V2_AUX         VIA   -    MD0100PA00X+031116Y+018854X0180Y    R090 S0      
327P1V2_AUX         U1    -J8         A01X+030966Y+018704X0145Y         S1      
317P1V2_AUX         VIA   -    MD0100PA00X+031431Y+018553X0180Y         S0      
327P1V2_AUX         R367  -2          A12X+032160Y+019050X0198Y0197R270 S2      
327P1V2_AUX         C222  -1   M      A12X+031661Y+018837X0198Y0197     S2      
327P1V2_AUX         U1    -J9         A01X+031280Y+018704X0145Y         S1      
317P1V2_AUX         VIA   -    MD0100PA00X+028925Y+019799X0180Y         S0      
327P1V2_AUX         U1    -F2         A01X+029076Y+019649X0145Y         S1      
317P1V2_AUX         VIA   -    MD0100PA00X+028925Y+018553X0180Y         S0      
327P1V2_AUX         C16   -1          A12X+029101Y+018791X0198Y0197     S2      
327P1V2_AUX         U1    -J2         A01X+029076Y+018704X0145Y         S1      
317P1V2_AUX         VIA   -    MD0100PA00X+028610Y+019484X0180Y         S0      
327P1V2_AUX         C7    -1          A12X+028224Y+019468X0198Y0197R270 S2      
327P1V2_AUX         U1    -G1         A01X+028761Y+019334X0145Y         S1      
317P1V2_AUX         VIA   -    MD0100PA00X+028610Y+018553X0180Y         S0      
327P1V2_AUX         R374  -2          A12X+028291Y+018703X0198Y0197R270 S2      
327P1V2_AUX         U1    -J1         A01X+028761Y+018704X0145Y         S1      
317P1V2_AUX         VIA   -    MD0100PA00X+021299Y+020066X0180Y    R180 S0      
317P1V2_AUX         VIA   -    MD0100PA00X+021299Y+019751X0180Y    R180 S0      
317P1V2_AUX         VIA   -    MD0100PA00X+020039Y+020696X0180Y    R180 S0      
317P1V2_AUX         VIA   -    MD0100PA00X+020984Y+020696X0180Y    R180 S0      
317P1V2_AUX         VIA   -    MD0100PA00X+020669Y+020696X0180Y    R180 S0      
317P1V2_AUX         VIA   -    MD0100PA00X+021299Y+020380X0180Y    R180 S0      
317P1V2_AUX         VIA   -    MD0100PA00X+020354Y+020696X0180Y    R180 S0      
327P1V2_AUX         C117  -1          A12X+021026Y+019445X0198Y0197     S2      
327P1V2_AUX         C107  -1          A12X+021149Y+019021X0198Y0197R090 S2      
327P1V2_AUX         C66   -1          A12X+020667Y+020931X0198Y0197R270 S2      
327P1V2_AUX         C84   -1          A12X+021464Y+019392X0198Y0197R180 S2      
327P1V2_AUX         C82   -1          A12X+021040Y+020353X0198Y0197     S2      
327P1V2_AUX         C112  -1          A12X+020042Y+020351X0198Y0197R180 S2      
327P1V2_AUX         U5    -N14        A01X+021455Y+019280X0160Y    R180 S1      
327P1V2_AUX         U5    -P14 M      A01X+021455Y+019595X0160Y    R180 S1      
327P1V2_AUX         U5    -R14        A01X+021455Y+019910X0160Y    R180 S1      
327P1V2_AUX         U5    -T14        A01X+021455Y+020225X0160Y    R180 S1      
327P1V2_AUX         U5    -U15        A01X+021140Y+020540X0160Y    R180 S1      
327P1V2_AUX         U5    -U16        A01X+020825Y+020540X0160Y    R180 S1      
327P1V2_AUX         U5    -U17        A01X+020510Y+020540X0160Y    R180 S1      
327P1V2_AUX         U5    -U18        A01X+020195Y+020540X0160Y    R180 S1      
317P1V2_AUX         VIA   -    MD0100PA00X+021299Y+018494X0180Y    R180 S0      
327P1V2_AUX         U5    -L14 M      A01X+021455Y+018650X0160Y    R180 S1      
327P1V2_AUX         U5    -M14        A01X+021455Y+018965X0160Y    R180 S1      
317P1V2_AUX         VIA   -    MD0100PA00X+031493Y+018074X0180Y    R045 S0      
327P1V2_AUX         R375  -2          A12X+031886Y+018341X0198Y0197     S2      
327P1V2_AUX         U1    -L9         A01X+031280Y+018074X0145Y         S1      
317P1V2_AUX         VIA   -    MD0100PA00X+028911Y+017924X0180Y    R090 S0      
327P1V2_AUX         U1    -L1         A01X+028761Y+018074X0145Y         S1      
317P1V2_AUX         VIA   -    MD0100PA00X+024130Y+017235X0180Y    R180 S0      
317P1V2_AUX         VIA   -    MD0100PA00X+024130Y+017865X0180Y    R180 S0      
317P1V2_AUX         VIA   -    MD0100PA00X+024130Y+017550X0180Y    R180 S0      
317P1V2_AUX         VIA   -    MD0100PA00X+024130Y+019751X0180Y    R180 S0      
317P1V2_AUX         VIA   -    MD0100PA00X+024130Y+020066X0180Y    R180 S0      
317P1V2_AUX         VIA   -    MD0100PA00X+024130Y+018494X0180Y    R180 S0      
327P1V2_AUX         C74   -1          A12X+023834Y+020123X0198Y0197R090 S2      
327P1V2_AUX         C76   -1          A12X+024198Y+018278X0198Y0197     S2      
327P1V2_AUX         U5    -G6         A01X+023974Y+017390X0160Y    R180 S1      
327P1V2_AUX         U5    -H6         A01X+023974Y+017705X0160Y    R180 S1      
327P1V2_AUX         U5    -J6  M      A01X+023974Y+018020X0160Y    R180 S1      
327P1V2_AUX         U5    -K6         A01X+023974Y+018335X0160Y    R180 S1      
327P1V2_AUX         U5    -L6  M      A01X+023974Y+018650X0160Y    R180 S1      
327P1V2_AUX         U5    -P6  M      A01X+023974Y+019595X0160Y    R180 S1      
327P1V2_AUX         U5    -R6         A01X+023974Y+019910X0160Y    R180 S1      
327P1V2_AUX         U5    -T6         A01X+023974Y+020225X0160Y    R180 S1      
317P1V2_AUX         VIA   -    MD0100PA00X+020669Y+018180X0180Y    R180 S0      
317P1V2_AUX         VIA   -    MD0100PA00X+019094Y+019124X0180Y    R180 S0      
317P1V2_AUX         VIA   -    MD0100PA00X+019094Y+018810X0180Y    R180 S0      
317P1V2_AUX         VIA   -    MD0100PA00X+019094Y+018494X0180Y         S0      
317P1V2_AUX         VIA   -    MD0100PA00X+019094Y+020066X0180Y    R180 S0      
317P1V2_AUX         VIA   -    MD0100PA00X+019094Y+019751X0180Y    R180 S0      
327P1V2_AUX         C103  -1          A12X+019911Y+019442X0198Y0197R180 S2      
327P1V2_AUX         C91   -1          A12X+020749Y+018589X0198Y0197R270 S2      
327P1V2_AUX         C98   -1          A12X+019946Y+018592X0198Y0197R270 S2      
327P1V2_AUX         C72   -1          A12X+019372Y+018610X0198Y0197R270 S2      
327P1V2_AUX         C122  -1          A12X+020348Y+018589X0198Y0197R270 S2      
327P1V2_AUX         C70   -1          A12X+019457Y+019452X0198Y0197R270 S2      
317P1V2_AUX         VIA   -    MD0100PA00X+019724Y+018494X0180Y         S0      
327P1V2_AUX         U5    -K16        A01X+020825Y+018335X0160Y    R180 S1      
327P1V2_AUX         U5    -K17        A01X+020510Y+018335X0160Y    R180 S1      
327P1V2_AUX         U5    -K18        A01X+020195Y+018335X0160Y    R180 S1      
327P1V2_AUX         U5    -K19 M      A01X+019880Y+018335X0160Y    R180 S1      
327P1V2_AUX         U5    -L21        A01X+019250Y+018650X0160Y    R180 S1      
327P1V2_AUX         U5    -M21        A01X+019250Y+018965X0160Y    R180 S1      
327P1V2_AUX         U5    -N21        A01X+019250Y+019280X0160Y    R180 S1      
327P1V2_AUX         U5    -P21        A01X+019250Y+019595X0160Y    R180 S1      
327P1V2_AUX         U5    -R21        A01X+019250Y+019910X0160Y    R180 S1      
327P1V2_AUX         U5    -T21        A01X+019250Y+020225X0160Y    R180 S1      
327P1V2_AUX         VIA   -           A12X+031970Y+024860X0260Y         S2      
327P1V2_AUX         VIA   -           A01X+030200Y+024290X0300Y         S1      
327P1V2_AUX         VIA   -           A01X+030710Y+024910X0300Y         S1      
327P1V2_AUX         PU41  -12         A01X+032754Y+028713X0100Y0280R270 S1      
327P1V2_AUX         C132  -1          A12X+033050Y+023410X0280Y0320R180 S2      
327P1V2_AUX         C131  -1          A12X+032200Y+023540X0280Y0320R180 S2      
327P1V2_AUX         R9    -2          A12X+032900Y+017141X0198Y0197R180 S2      
317P1V2_AUX         VIA   -    MD0100PA00X+030112Y+023876X0200Y    R270 S0      
317P1V2_AUX         VIA   -    MD0100PA00X+033747Y+023698X0200Y    R270 S0      
327P1V2_AUX         C13   -1          A12X+033740Y+018696X0198Y0197     S2      
327P1V2_AUX         C14   -1          A12X+033425Y+016691X0198Y0197R180 S2      
327P1V2_AUX         PC255 -1   M      A01X+033722Y+023363X0198Y0197R270 S1      
327P1V2_AUX         R369  -2          A12X+032900Y+016341X0198Y0197R180 S2      
327P1V2_AUX         R354  -2   M      A12X+032900Y+016741X0198Y0197R180 S2      
327P1V2_AUX         R366  -2   M      A12X+033740Y+019096X0198Y0197R180 S2      
327P1V2_AUX         R358  -2   M      A12X+033733Y+017491X0198Y0197R180 S2      
327P1V2_AUX         R356  -2          A12X+033740Y+017891X0198Y0197R180 S2      
327P1V2_AUX         R363  -2          A12X+032900Y+017541X0198Y0197R180 S2      
327P1V2_AUX         R372  -2   M      A12X+033740Y+018293X0198Y0197R180 S2      
327P1V2_AUX         R360  -2          A12X+033733Y+017091X0198Y0197R180 S2      
327P1V2_AUX         R364  -2   M      A12X+033740Y+016291X0198Y0197R180 S2      
327P1V2_AUX         R352  -2          A12X+033740Y+015891X0198Y0197R180 S2      
327P1V2_AUX         PL31  -2          A01X+032460Y+024521X0848Y1300R270 S1      
327P1V2_AUX         C1    -1          A12X+032361Y+019649X0280Y0320R270 S2      
327P1V2_AUX         PC256 -1          A01X+033052Y+023621X0440Y0540R090 S1      
327P1V2_AUX         PC257 -1          A01X+032212Y+023624X0440Y0540R090 S1      
327P1V2_AUX         PC258 -1          A01X+031372Y+023626X0440Y0540R090 S1      
327P1V2_AUX         PC259 -1          A01X+030532Y+023628X0440Y0540R090 S1      
317P1V2_AUX         VIA   -    MD0100PA00X+033140Y+016741X0200Y         S0      
317P1V2_AUX         VIA   -    MD0100PA00X+033994Y+016291X0200Y         S0      
317P1V2_AUX         VIA   -    MD0100PA00X+033980Y+018293X0200Y         S0      
317P1V2_AUX         VIA   -    MD0100PA00X+033740Y+019345X0200Y         S0      
317P1V2_AUX         VIA   -    MD0100PA00X+033981Y+017338X0200Y         S0      
317P1V2_AUX         VIA   -    MD0100PA00X+030952Y+023874X0200Y    R270 S0      
317P1V2_AUX         VIA   -    MD0100PA00X+033472Y+023528X0200Y    R270 S0      
317P1V2_AUX         VIA   -    MD0100PA00X+033472Y+023867X0200Y    R270 S0      
317P1V2_AUX         VIA   -    MD0100PA00X+032632Y+023869X0200Y    R270 S0      
317P1V2_AUX         VIA   -    MD0100PA00X+032632Y+023530X0200Y    R270 S0      
317P1V2_AUX         VIA   -    MD0100PA00X+031792Y+023533X0200Y    R270 S0      
317P1V2_AUX         VIA   -    MD0100PA00X+031792Y+023872X0200Y    R270 S0      
317P1V2_AUX         VIA   -    M      A01X+030952Y+023535X0200Y    R270 S2      
017P1V2_AUX         VIA   -    M      A12X+030952Y+023535X0260Y    R270 S2      
017P1V2_AUX               -    MD0100PA00X+030952Y+023535                       
317P1V2_AUX         VIA   -    MD0100PA00X+030112Y+023563X0200Y    R270 S0      
317P1V2_AUX         VIA   -    MD0100PA00X+032005Y+019866X0200Y         S0      
317P1V2_AUX         VIA   -    MD0100PA00X+032005Y+019516X0200Y         S0      
317P1V2_AUX         VIA   -    MD0100PA00X+033140Y+017241X0200Y         S0      
317P1V2_AUX         VIA   -    MD0100PA00X+031431Y+016349X0180Y         S0      
327P1V2_AUX         U1    -T9         A01X+031280Y+016499X0145Y         S1      
327P1V2_AUX         C225  -1          A12X+027600Y+016558X0198Y0197R090 S2      
317P1V2_AUX         VIA   -    MD0100PA00X+028548Y+016810X0180Y    R315 S0      
327P1V2_AUX         L11   -1          A12X+027590Y+017050X0280Y0320R090 S2      
327P1V2_AUX         U1    -R1         A01X+028761Y+016814X0145Y         S1      
317P1V2_AUX         VIA   -    MD0100PA00X+027946Y+017132X0200Y    R270 S0      
317P1V2_AUX         VIA   -    MD0100PA00X+033937Y+015195X0200Y         S0      
327P1V2_AUX         R368  -2          A12X+033740Y+015491X0198Y0197R180 S2      
317P1V2_AUX         VIA   -    MD0100PA00X+032900Y+015266X0200Y         S0      
327P1V2_AUX         R365  -2          A12X+032900Y+015541X0198Y0197R180 S2      
317P1V2_AUX         VIA   -    MD0100PA00X+032351Y+015338X0200Y         S0      
327P1V2_AUX         R370  -2          A12X+032111Y+015338X0198Y0197R180 S2      
327P1V2_AUX         C15   -1          A12X+032527Y+015014X0198Y0197R180 S2      
317P1V2_AUX         VIA   -    MD0100PA00X+031794Y+014390X0200Y         S0      
327P1V2_AUX         R351  -2          A12X+031794Y+014630X0198Y0197R090 S2      
327P1V2_AUX         C18   -1          A01X+031794Y+014630X0198Y0197R090 S1      
317P1V2_AUX         VIA   -    MD0100PA00X+031394Y+014390X0200Y         S0      
327P1V2_AUX         R373  -2          A01X+031394Y+014630X0198Y0197R270 S1      
327P1V2_AUX         R371  -2          A12X+031394Y+014630X0198Y0197R090 S2      
317P1V2_AUX         VIA   -    MD0100PA00X+030994Y+014390X0200Y         S0      
327P1V2_AUX         R361  -2          A01X+030994Y+014630X0198Y0197R270 S1      
327P1V2_AUX         R359  -2          A12X+030994Y+014630X0198Y0197R090 S2      
317P1V2_AUX         VIA   -    MD0100PA00X+030594Y+014390X0200Y         S0      
327P1V2_AUX         R355  -2          A01X+030594Y+014630X0198Y0197R270 S1      
327P1V2_AUX         R357  -2          A12X+030594Y+014630X0198Y0197R090 S2      
317P1V2_AUX         VIA   -    MD0100PA00X+030194Y+014390X0200Y         S0      
327P1V2_AUX         R353  -2          A01X+030194Y+014630X0198Y0197R270 S1      
327P1V2_AUX         R362  -2          A12X+030194Y+014630X0198Y0197R090 S2      
327P1V2_AUX         C17   -1          A01X+029784Y+014291X0198Y0197R180 S1      
317P1V2_AUX         VIA   -    MD0100PA00X+014882Y+012570X0200Y         S0      
317P1V2_AUX         VIA   -    MD0100PA00X+014882Y+012320X0200Y         S0      
327P1V2_AUX         L2    -1          A12X+014840Y+012900X0280Y0320R090 S2      
317P1V2_AUX         VIA   -    MD0100PA00X+029220Y+014261X0200Y         S0      
317P1V2_AUX         VIA   -    MD0100PA00X+028756Y+014242X0200Y         S0      
327P1V2_AUX         C55   -1          A12X+029149Y+013787X0280Y0320R270 S2      
327P1V2_AUX         C62   -1          A12X+028645Y+014516X0198Y0197R270 S2      
327P1V2_AUX         C58   -1          A12X+029049Y+014516X0198Y0197R270 S2      
327P1V2_AUX         C127  -1          A12X+028244Y+014516X0198Y0197R270 S2      
327P1V2_AUX         C129  -1          A01X+028613Y+013840X0198Y0197R180 S1      
317m0596            VIA   -    MD0100PA00X+026834Y+022213X0200Y         S0      
327m0596            VIA   -           A12X+026635Y+021938X0260Y         S2      
327m0596            L6    -2          A12X+027611Y+021863X0280Y0320R090 S2      
327m0596            C47   -1          A12X+027147Y+021950X0198Y0197R090 S2      
327m0596            U5    -T10        A01X+022715Y+020225X0160Y    R180 S1      
327m0596            C50   -1          A12X+022578Y+020456X0198Y0197     S2      
317m0596            VIA   -    MD0100PA00X+022870Y+020380X0180Y         S0      
327m0597            C59   -1          A12X+023504Y+017177X0198Y0197R180 S2      
327m0597            C68   -1          A12X+024120Y+016532X0198Y0197R270 S2      
327m0597            U5    -F7         A01X+023659Y+017075X0160Y    R180 S1      
317m0597            VIA   -    MD0100PA00X+023500Y+016920X0180Y    R180 S0      
327m0597            U5    -J9         A01X+023030Y+018020X0160Y    R180 S1      
327m0597            U5    -F9         A01X+023030Y+017075X0160Y    R180 S1      
327m0597            U5    -E9  M      A01X+023030Y+016760X0160Y    R180 S1      
327m0597            U5    -E7  M      A01X+023659Y+016760X0160Y    R180 S1      
327m0597            C64   -1          A12X+022706Y+017328X0198Y0197R270 S2      
327m0597            C56   -1          A01X+027568Y+014838X0198Y0197R270 S1      
327m0597            C54   -1          A12X+023111Y+017325X0198Y0197R270 S2      
327m0597            C52   -1          A01X+027167Y+014838X0198Y0197R270 S1      
327m0597            L8    -2          A01X+028821Y+014773X0280Y0320R090 S1      
317m0597            VIA   -    MD0100PA00X+028362Y+015097X0200Y         S0      
317m0597            VIA   -    MD0100PA00X+028062Y+015097X0200Y         S0      
317m0597            VIA   -    MD0100PA00X+023185Y+017865X0180Y         S0      
317m0597            VIA   -    MD0100PA00X+023815Y+016605X0180Y         S0      
317m0597            VIA   -    MD0100PA00X+023185Y+016605X0180Y         S2      
317m0597            VIA   -    MD0100PA00X+023185Y+016920X0180Y    R180 S0      
327m0598            U5    -T9         A01X+023030Y+020225X0160Y    R180 S1      
327m0598            C79   -1          A12X+023271Y+020124X0198Y0197R090 S2      
327m0598            C78   -1          A12X+028358Y+023795X0198Y0197R270 S2      
327m0598            L13   -2          A12X+028348Y+023145X0280Y0320     S2      
327m0598            VIA   -           A12X+028819Y+023770X0260Y         S2      
317m0598            VIA   -    MD0100PA00X+028248Y+023525X0200Y         S0      
317m0598            VIA   -    MD0100PA00X+027998Y+023525X0200Y         S0      
317m0598            VIA   -    MD0100PA00X+023185Y+020380X0180Y         S0      
327m0599            U5    -T8         A01X+023344Y+020225X0160Y    R180 S1      
327m0599            C90   -1          A12X+029736Y+023629X0198Y0197R090 S2      
327m0599            C97   -1          A12X+023278Y+020704X0198Y0197     S2      
327m0599            L15   -2          A12X+028910Y+023140X0280Y0320     S2      
327m0599            VIA   -           A12X+030392Y+024325X0260Y         S2      
327m0599            VIA   -           A12X+030369Y+023703X0260Y         S2      
317m0599            VIA   -    MD0100PA00X+028809Y+023484X0200Y         S0      
317m0599            VIA   -    MD0100PA00X+029059Y+023484X0200Y         S0      
317m0599            VIA   -    MD0100PA00X+023500Y+020380X0180Y         S0      
327P1V0_AUX_VCC     PU42  -3          A01X+007035Y+013017X0100Y0280R270 S1      
327P1V0_AUX_VCC     PU42  -6          A01X+007035Y+012426X0100Y0280R270 S1      
327P1V0_AUX_VCC     PU42  -10         A01X+008177Y+012426X0100Y0280R270 S1      
327P1V0_AUX_VCC     PC260 -1   M      A01X+008808Y+012190X0198Y0197R090 S1      
327P1V0_AUX_VCC     VIA   -    M      A12X+007658Y+012190X0260Y    R180 S2      
317P1V0_AUX_VCC     VIA   -    MD0100PA00X+006683Y+012233X0200Y         S0      
317P1V0_AUX_VCC     VIA   -    MD0100PA00X+008670Y+011910X0200Y         S0      
317P1V0_AUX_VCC     VIA   -    MD0100PA00X+006687Y+013059X0200Y    R180 S0      
327P1V0_AUX_VCC     PR541 -2          A01X+009192Y+011902X0198Y0197R270 S1      
327P1V0_AUX_MODE    PR543 -1          A01X+006655Y+011645X0198Y0197R180 S1      
327P1V0_AUX_MODE    PU42  -7          A01X+007410Y+012347X0100Y0280     S1      
327P1V0_AUX         VIA   -           A12X+030570Y+021630X0260Y         S2      
327P1V0_AUX         VIA   -           A12X+029070Y+022160X0260Y         S2      
327P1V0_AUX         PC267 -1          A12X+009570Y+009076X0440Y0540R090 S2      
327P1V0_AUX         PC270 -1          A12X+008650Y+009076X0440Y0540R090 S2      
327P1V0_AUX         PC269 -1          A12X+007900Y+009076X0440Y0540R090 S2      
327P1V0_AUX         PC268 -1          A12X+007050Y+009076X0440Y0540R090 S2      
327P1V0_AUX         PU42  -12         A01X+008177Y+012820X0100Y0280R270 S1      
327P1V0_AUX         PC266 -1   M      A01X+010000Y+009292X0198Y0197R090 S1      
317P1V0_AUX         VIA   -    M      A01X+009136Y+008374X0200Y    R270 S2      
017P1V0_AUX         VIA   -    M      A12X+009136Y+008374X0260Y    R270 S2      
017P1V0_AUX               -    MD0100PA00X+009136Y+008374                       
317P1V0_AUX         VIA   -    M      A01X+007476Y+008374X0200Y    R270 S2      
017P1V0_AUX         VIA   -    M      A12X+007476Y+008374X0260Y    R270 S2      
017P1V0_AUX               -    MD0100PA00X+007476Y+008374                       
317P1V0_AUX         VIA   -    MD0100PA00X+009136Y+008674X0200Y    R270 S0      
317P1V0_AUX         VIA   -    MD0100PA00X+007476Y+008674X0200Y    R270 S0      
317P1V0_AUX         VIA   -    MD0100PA00X+015647Y+020350X0200Y         S0      
327P1V0_AUX         R281  -1          A12X+016041Y+020630X0198Y0197R180 S2      
327P1V0_AUX         R279  -1   M      A12X+015647Y+020622X0198Y0197R270 S2      
327P1V0_AUX         U43   -5          A01X+013350Y+016362X0240Y0420     S1      
317P1V0_AUX         VIA   -    M      A01X+013250Y+016730X0200Y         S2      
017P1V0_AUX         VIA   -    M      A12X+013250Y+016730X0260Y         S2      
017P1V0_AUX               -    MD0100PA00X+013250Y+016730                       
317P1V0_AUX         VIA   -    MD0100PA00X+011540Y+015950X0200Y         S0      
317P1V0_AUX         VIA   -    MD0100PA00X+009136Y+009274X0200Y    R270 S0      
317P1V0_AUX         VIA   -    MD0100PA00X+007476Y+009274X0200Y    R270 S0      
317P1V0_AUX         VIA   -    MD0100PA00X+007476Y+008974X0200Y    R270 S0      
317P1V0_AUX         VIA   -    MD0100PA00X+009136Y+008974X0200Y    R270 S0      
327P1V0_AUX         PL33  -2          A01X+008334Y+008735X0848Y1300R270 S1      
327P1V0_AUX         C113  -1          A12X+027790Y+022450X0280Y0320R090 S2      
327P1V0_AUX         U5    -R10        A01X+022715Y+019910X0160Y    R180 S1      
327P1V0_AUX         U5    -R9         A01X+023030Y+019910X0160Y    R180 S1      
327P1V0_AUX         U5    -P11        A01X+022400Y+019595X0160Y    R180 S1      
327P1V0_AUX         U5    -P8         A01X+023344Y+019595X0160Y    R180 S1      
327P1V0_AUX         U5    -N11 M      A01X+022400Y+019280X0160Y    R180 S1      
327P1V0_AUX         U5    -N8         A01X+023344Y+019280X0160Y    R180 S1      
327P1V0_AUX         U5    -M11        A01X+022400Y+018965X0160Y    R180 S1      
327P1V0_AUX         U5    -M8         A01X+023344Y+018965X0160Y    R180 S1      
327P1V0_AUX         U5    -L10 M      A01X+022715Y+018650X0160Y    R180 S1      
327P1V0_AUX         U5    -L9         A01X+023030Y+018650X0160Y    R180 S1      
317P1V0_AUX         VIA   -    MD0100PA00X+031045Y+021862X0200Y         S0      
317P1V0_AUX         VIA   -    MD0100PA00X+030499Y+021950X0200Y         S0      
317P1V0_AUX         VIA   -    MD0100PA00X+030749Y+021950X0200Y         S0      
317P1V0_AUX         VIA   -    MD0100PA00X+029673Y+021608X0200Y         S0      
327P1V0_AUX         C123  -1          A12X+030016Y+021716X0280Y0320     S2      
327P1V0_AUX         C118  -1          A12X+029453Y+022126X0280Y0320     S2      
327P1V0_AUX         L15   -1          A12X+028910Y+022560X0280Y0320     S2      
327P1V0_AUX         L13   -1          A12X+028348Y+022565X0280Y0320     S2      
327P1V0_AUX         L6    -1          A12X+028191Y+021863X0280Y0320R090 S2      
327P1V0_AUX         C108  -1          A12X+028661Y+021968X0198Y0197R090 S2      
327P1V0_AUX         L8    -1          A01X+029401Y+014773X0280Y0320R090 S1      
317P1V0_AUX         VIA   -    MD0100PA00X+029800Y+014612X0200Y         S0      
317P1V0_AUX         VIA   -    MD0100PA00X+029800Y+014862X0200Y         S0      
317P1V0_AUX         VIA   -    MD0100PA00X+029800Y+015112X0200Y         S0      
327P1V0_AUX         R796  -1          A12X+019800Y+026108X0198Y0197R270 S2      
327P1V0_AUX         C104  -1          A12X+023167Y+018894X0198Y0197     S2      
327P1V0_AUX         C99   -1          A12X+022219Y+018900X0198Y0197R090 S2      
327P1V0_AUX         C86   -1          A12X+023603Y+019415X0198Y0197     S2      
327P1V0_AUX         C92   -1          A12X+022616Y+020056X0198Y0197     S2      
317P1V0_AUX         VIA   -    MD0100PA00X+023500Y+019751X0180Y    R180 S0      
317P1V0_AUX         VIA   -    MD0100PA00X+022870Y+020066X0180Y         S0      
317P1V0_AUX         VIA   -    MD0100PA00X+019624Y+025343X0200Y         S0      
317P1V0_AUX         VIA   -    MD0100PA00X+022555Y+018810X0180Y    R180 S0      
317P1V0_AUX         VIA   -    MD0100PA00X+022555Y+019124X0180Y    R180 S0      
317P1V0_AUX         VIA   -    MD0100PA00X+023500Y+019124X0180Y    R180 S0      
317P1V0_AUX         VIA   -    MD0100PA00X+023500Y+018810X0180Y    R180 S0      
327P12V_AUX         VIA   -           A12X+034750Y+035000X0260Y         S2      
327P12V_AUX         VIA   -           A12X+034750Y+038800X0260Y         S2      
317P12V_AUX         VIA   -    MD0100PA00X+013153Y+011427X0200Y         S0      
317P12V_AUX         VIA   -    MD0100PA00X+021431Y+006223X0200Y         S0      
327P12V_AUX         R389  -2          A01X+021900Y+004408X0198Y0197R090 S1      
327P12V_AUX         GF1   -OB1        A01X+029787Y+046638X0150Y0840R180 S1      
327P12V_AUX         GF1   -OB2        A01X+029551Y+046638X0150Y0840R180 S1      
327P12V_AUX         GF1   -OA1        A12X+029787Y+046638X0150Y0840R180 S2      
327P12V_AUX         GF1   -OA2        A12X+029551Y+046559X0150Y0680R180 S2      
317P12V_AUX         VIA   -    MD0100PA00X+008352Y+015852X0200Y         S0      
317P12V_AUX         VIA   -    MD0100PA00X+008610Y+015839X0200Y         S0      
317P12V_AUX         VIA   -    MD0100PA00X+008341Y+016102X0200Y         S0      
317P12V_AUX         VIA   -    MD0100PA00X+008610Y+015584X0200Y         S0      
327P12V_AUX         C280  -1          A01X+007550Y+015808X0198Y0197R270 S1      
327P12V_AUX         PL32  -1          A01X+008050Y+016140X0280Y0320R180 S1      
317P12V_AUX         VIA   -    MD0100PA00X+008610Y+015334X0200Y         S0      
327P12V_AUX         C278  -1          A01X+033090Y+032048X0198Y0197R270 S1      
327P12V_AUX         PL29  -1          A01X+032600Y+031990X0280Y0320R180 S1      
327P12V_AUX         U56   -1          A01X+030524Y+033062X0280Y0400R180 S1      
327P12V_AUX         C226  -1          A01X+031100Y+032658X0198Y0197R270 S1      
327P12V_AUX         U56   -3          A01X+029776Y+033062X0280Y0400R180 S1      
327P12V_AUX         VIA   -           A12X+032110Y+041040X0260Y         S2      
317P12V_AUX         VIA   -    MD0100PA00X+032209Y+040650X0200Y         S0      
327P12V_AUX         C329  -1          A12X+032000Y+040300X0400Y0500R270 S2      
327P12V_AUX         C330  -1          A12X+032700Y+040300X0400Y0500R270 S2      
327P12V_AUX         VIA   -           A12X+033330Y+040340X0260Y         S2      
317P12V_AUX         VIA   -    MD0100PA00X+029774Y+045542X0200Y         S0      
317P12V_AUX         VIA   -    MD0100PA00X+029774Y+045842X0200Y         S0      
317P12V_AUX         VIA   -    MD0100PA00X+029774Y+045242X0200Y         S0      
317P12V_AUX         VIA   -    MD0100PA00X+029573Y+045991X0200Y         S0      
317P12V_AUX         VIA   -    MD0100PA00X+029573Y+045691X0200Y         S0      
317P12V_AUX         VIA   -    MD0100PA00X+029573Y+045391X0200Y         S0      
317P12V_AUX         VIA   -    MD0100PA00X+031859Y+040650X0200Y         S0      
317P12V_AUX         VIA   -    MD0100PA00X+032909Y+040650X0200Y         S0      
317P12V_AUX         VIA   -    MD0100PA00X+032559Y+040650X0200Y         S0      
317P12V_AUX         VIA   -    MD0100PA00X+032770Y+032354X0200Y    R090 S0      
317P12V_AUX         VIA   -    MD0100PA00X+032501Y+032351X0200Y    R090 S0      
317P12V_AUX         VIA   -    MD0100PA00X+032770Y+032604X0200Y    R090 S0      
317P12V_AUX         VIA   -    MD0100PA00X+032770Y+032864X0200Y    R090 S0      
317P12V_AUX         VIA   -    MD0100PA00X+032501Y+032601X0200Y    R090 S0      
317P12V_AUX         VIA   -    MD0100PA00X+032501Y+032861X0200Y    R090 S0      
327P12V_AUX         PL4   -1          A01X+002410Y+022600X0280Y0320R270 S1      
327P12V_AUX         C241  -1          A01X+001800Y+023002X0198Y0197R090 S1      
317P12V_AUX         VIA   -    MD0100PA00X+001842Y+022717X0200Y    R090 S0      
317P12V_AUX         VIA   -    MD0100PA00X+001842Y+022457X0200Y    R090 S0      
317P12V_AUX         VIA   -    MD0100PA00X+002100Y+022450X0200Y    R090 S0      
317P12V_AUX         VIA   -    MD0100PA00X+002100Y+022700X0200Y    R090 S0      
317P12V_AUX         VIA   -    MD0100PA00X+001592Y+022717X0200Y    R090 S0      
317P12V_AUX         VIA   -    MD0100PA00X+001592Y+022457X0200Y    R090 S0      
327P12V_AUX         R785  -1          A12X+012755Y+022815X0198Y0197R270 S2      
317P12V_AUX         VIA   -    MD0100PA00X+012379Y+022766X0200Y         S0      
317P12V_AUX         VIA   -    MD0100PA00X+012369Y+023016X0200Y         S0      
327P12V_AUX         VIA   -           A12X+012720Y+022370X0260Y         S2      
317P12V_AUX         VIA   -    MD0100PA00X+005205Y+020876X0200Y         S0      
327P12V_AUX         PR521 -1          A01X+005185Y+020633X0198Y0197R270 S1      
327P12V_AUX         C262  -1          A01X+004050Y+023092X0198Y0197R090 S1      
327P12V_AUX         PL19  -1          A01X+004092Y+022596X0280Y0320R090 S1      
317P12V_AUX         VIA   -    MD0100PA00X+004415Y+022473X0200Y    R270 S0      
317P12V_AUX         VIA   -    MD0100PA00X+004199Y+022033X0200Y    R270 S0      
317P12V_AUX         VIA   -    MD0100PA00X+003949Y+022033X0200Y    R270 S0      
317P12V_AUX         VIA   -    MD0100PA00X+004415Y+022733X0200Y    R270 S0      
317P12V_AUX         VIA   -    MD0100PA00X+004199Y+022293X0200Y    R270 S0      
317P12V_AUX         VIA   -    MD0100PA00X+003949Y+022293X0200Y    R270 S0      
327m0600            C22   -1          A12X+024450Y+020642X0198Y0197R270 S2      
327m0600            U5    -U5         A01X+024289Y+020540X0160Y    R180 S1      
327m0600            U5    -T5         A01X+024289Y+020225X0160Y    R180 S1      
327m0600            U1    -M1         A01X+028761Y+017759X0145Y         S1      
327m0600            C10   -1          A12X+028370Y+017564X0198Y0197     S2      
327m0600            C168  -1          A12X+032948Y+020629X0198Y0197R180 S2      
327m0600            C170  -1          A12X+032948Y+020229X0198Y0197R180 S2      
327m0600            C169  -2          A12X+032484Y+020766X0198Y0197R180 S2      
327m0600            C21   -1          A12X+023906Y+020919X0198Y0197R270 S2      
327m0600            C23   -1   M      A12X+024041Y+020526X0198Y0197     S2      
327m0600            R325  -1          A12X+032948Y+021029X0198Y0197R180 S2      
327m0600            R324  -2          A12X+032484Y+020366X0198Y0197R180 S2      
327m0600            VIA   -           A12X+032380Y+021636X0260Y         S2      
327m0600            VIA   -           A12X+032880Y+021636X0260Y         S2      
317m0600            VIA   -    MD0100PA00X+024445Y+020380X0180Y         S0      
317m0600            VIA   -    MD0100PA00X+032673Y+020148X0200Y         S0      
317m0600            VIA   -    MD0100PA00X+030760Y+025230X0200Y         S0      
317m0600            VIA   -    MD0100PA00X+030500Y+025240X0200Y         S0      
317m0600            VIA   -    MD0100PA00X+032093Y+021539X0200Y         S0      
317m0600            VIA   -    MD0100PA00X+032094Y+021284X0200Y         S0      
317m0600            VIA   -    MD0100PA00X+032673Y+021365X0200Y         S0      
317m0600            VIA   -    MD0100PA00X+032104Y+021026X0200Y         S0      
317m0600            VIA   -    MD0100PA00X+032673Y+020988X0200Y         S0      
317m0600            VIA   -    MD0100PA00X+032693Y+020568X0200Y         S0      
317m0600            VIA   -    MD0100PA00X+028610Y+017608X0180Y         S0      
327M_BMC_DDR4_ZQU   U1    -E9         A01X+031280Y+019964X0145Y         S1      
327M_BMC_DDR4_ZQU   R3    -1          A12X+030560Y+020079X0198Y0197R180 S2      
317M_BMC_DDR4_ZQU   VIA   -    MD0100PA00X+031431Y+020114X0180Y         S0      
327m0601            U5    -L3         A01X+024919Y+018650X0160Y    R180 S1      
317m0601            VIA   -    MD0100PA00X+025075Y+018494X0180Y    R180 S2      
327m0601            U1    -P1         A01X+028761Y+017129X0145Y         S1      
317m0601            VIA   -    MD0100PA00X+028298Y+017298X0180Y         S0      
317m0602            VIA   -    MD0100PA00X+024445Y+017235X0180Y    R180 S0      
327m0602            U5    -G5         A01X+024289Y+017390X0160Y    R180 S1      
327m0602            U1    -L2         A01X+029076Y+018074X0145Y         S1      
327m0602            R340  -2   M      A12X+032586Y+015941X0198Y0197     S2      
327m0602            R365  -1          A12X+032586Y+015541X0198Y0197R180 S2      
317m0602            VIA   -    MD0100PA00X+029226Y+017924X0180Y    R090 S0      
327m0603            U5    -J5         A01X+024289Y+018020X0160Y    R180 S1      
317m0603            VIA   -    MD0100PA00X+024445Y+017865X0180Y    R180 S0      
327m0603            U1    -L8         A01X+030966Y+018074X0145Y         S1      
327m0603            R367  -1   M      A12X+032160Y+018734X0198Y0197R270 S2      
327m0603            R342  -2          A12X+032586Y+019141X0198Y0197     S2      
327m0603            VIA   -    M      A12X+031087Y+017967X0260Y         S2      
317m0603            VIA   -    MD0100PA00X+030815Y+017924X0180Y    R270 S0      
327m0604            R373  -1   M      A01X+031394Y+014945X0198Y0197R270 S1      
327m0604            R348  -2          A01X+031394Y+014145X0198Y0197R090 S1      
317m0604            VIA   -    M      A01X+027121Y+017752X0180Y         S2      
017m0604            VIA   -    M      A12X+027121Y+017752X0260Y         S2      
017m0604                  -    MD0100PA00X+027121Y+017752                       
327m0604            U5    -J1         A01X+025549Y+018020X0160Y    R180 S1      
327m0604            U1    -K3         A01X+029391Y+018389X0145Y         S1      
317m0604            VIA   -    MD0100PA00X+029541Y+018553X0180Y         S0      
327m0605            U5    -R5         A01X+024289Y+019910X0160Y    R180 S1      
317m0605            VIA   -    MD0100PA00X+024445Y+020066X0180Y         S2      
317m0605            VIA   -    MD0100PA00X+028925Y+020114X0180Y         S0      
327m0605            U1    -E2         A01X+029076Y+019964X0145Y         S1      
327m0606            U5    -N3         A01X+024919Y+019280X0160Y    R180 S1      
317m0606            VIA   -    MD0100PA00X+025075Y+019124X0180Y         S0      
317m0606            VIA   -    MD0100PA00X+030801Y+019813X0180Y         S0      
327m0606            U1    -E7         A01X+030650Y+019964X0145Y         S1      
327m0607            U1    -L7         A01X+030650Y+018074X0145Y         S1      
327m0607            R368  -1          A12X+033425Y+015491X0198Y0197R180 S2      
327m0607            R343  -2          A01X+033425Y+015491X0198Y0197R180 S1      
317m0607            VIA   -    MD0100PA00X+030500Y+017924X0180Y         S0      
317m0607            VIA   -    MD0100PA00X+033140Y+015491X0200Y         S0      
317m0607            VIA   -    MD0100PA00X+025390Y+017550X0180Y    R180 S2      
327m0607            U5    -H2         A01X+025234Y+017705X0160Y    R180 S1      
327m0608            U1    -K7         A01X+030650Y+018389X0145Y         S1      
327m0608            R8    -1          A12X+030466Y+018588X0198Y0197     S2      
317m0608            VIA   -    MD0100PA00X+030801Y+018539X0180Y    R090 S0      
327m0608            U5    -K2         A01X+025234Y+018335X0160Y    R180 S1      
317m0608            VIA   -    MD0100PA00X+026422Y+017679X0180Y         S0      
327m0609            U1    -K8         A01X+030966Y+018389X0145Y         S1      
327m0609            R7    -1          A12X+030466Y+018188X0198Y0197     S2      
317m0609            VIA   -    MD0100PA00X+030815Y+018238X0180Y    R270 S0      
327m0609            U5    -K1         A01X+025549Y+018335X0160Y    R180 S1      
317m0609            VIA   -    MD0100PA00X+026772Y+017679X0180Y         S0      
327m0610            C12   -1   M      A12X+030151Y+018988X0198Y0197R270 S2      
327m0610            C229  -1          A12X+030551Y+018988X0198Y0197R270 S2      
327m0610            R8    -2   M      A12X+030151Y+018588X0198Y0197     S2      
327m0610            R7    -2          A12X+030151Y+018188X0198Y0197     S2      
317m0611            VIA   -    MD0100PA00X+024445Y+018494X0180Y    R180 S0      
327m0611            U5    -L5         A01X+024289Y+018650X0160Y    R180 S1      
327m0611            U1    -K2         A01X+029076Y+018389X0145Y         S1      
327m0611            R374  -1   M      A12X+028291Y+018388X0198Y0197R270 S2      
327m0611            R349  -2          A12X+027887Y+018388X0198Y0197R090 S2      
317m0611            VIA   -    MD0100PA00X+028925Y+018238X0180Y         S0      
327m0612            U1    -M8  M      A01X+030966Y+017759X0145Y         S1      
327m0612            R366  -1          A12X+033425Y+019096X0198Y0197R180 S2      
327m0612            R341  -2          A01X+033425Y+018991X0198Y0197R180 S1      
327m0612            VIA   -    M      A01X+032826Y+018704X0300Y         S1      
317m0612            VIA   -    MD0100PA00X+033140Y+018991X0200Y         S0      
317m0612            VIA   -    MD0100PA00X+030815Y+017608X0180Y    R270 S0      
317m0612            VIA   -    MD0100PA00X+024760Y+017865X0180Y    R180 S0      
327m0612            U5    -J4         A01X+024604Y+018020X0160Y    R180 S1      
327m0613            U5    -M3         A01X+024919Y+018965X0160Y    R180 S1      
327m0613            VIA   -    M      A12X+026791Y+018510X0260Y         S2      
317m0613            VIA   -    MD0100PA00X+025075Y+018810X0180Y    R180 S0      
327m0613            R375  -1   M      A12X+032200Y+018341X0198Y0197     S2      
327m0613            R350  -2          A12X+032586Y+018741X0198Y0197     S2      
327m0613            R1    -2   M      A12X+032586Y+018341X0198Y0197     S2      
317m0614            VIA   -    MD0100PA00X+025075Y+017235X0180Y    R180 S0      
327m0614            U5    -G3         A01X+024919Y+017390X0160Y    R180 S1      
327m0614            VIA   -    M      A12X+031127Y+015916X0260Y         S2      
327m0614            U1    -M2         A01X+029076Y+017759X0145Y         S1      
327m0614            R370  -1          A12X+031796Y+015338X0198Y0197R180 S2      
327m0614            R345  -2   M      A12X+031783Y+015738X0198Y0197     S2      
317m0614            VIA   -    MD0100PA00X+028925Y+017608X0180Y         S0      
327m0615            U5    -H5         A01X+024289Y+017705X0160Y    R180 S1      
317m0615            VIA   -    MD0100PA00X+024445Y+017550X0180Y         S0      
327m0615            U1    -N8  M      A01X+030966Y+017444X0145Y         S1      
327m0615            R372  -1          A12X+033425Y+018293X0198Y0197R180 S2      
327m0615            R347  -2          A01X+033425Y+018393X0198Y0197R180 S1      
317m0615            VIA   -    MD0100PA00X+033140Y+018293X0200Y         S0      
327m0615            VIA   -    M      A01X+032478Y+018204X0300Y         S1      
317m0615            VIA   -    MD0100PA00X+030815Y+017294X0180Y    R270 S0      
317m0616            VIA   -    MD0100PA00X+024760Y+017235X0180Y    R180 S0      
327m0616            U5    -G4         A01X+024604Y+017390X0160Y    R180 S1      
327m0616            VIA   -    M      A12X+030939Y+015399X0260Y         S2      
327m0616            U1    -N2         A01X+029076Y+017444X0145Y         S1      
327m0616            R371  -1   M      A12X+031394Y+014945X0198Y0197R090 S2      
327m0616            R346  -2          A12X+031394Y+014150X0198Y0197R270 S2      
317m0616            VIA   -    MD0100PA00X+029238Y+017294X0180Y    R090 S0      
317m0617            VIA   -    MD0100PA00X+027364Y+017427X0180Y         S0      
327m0617            VIA   -    M      A01X+027553Y+016381X0300Y         S1      
327m0617            U5    -H1         A01X+025549Y+017705X0160Y    R180 S1      
327m0617            U1    -L3         A01X+029391Y+018074X0145Y         S1      
327m0617            R369  -1          A12X+032586Y+016341X0198Y0197R180 S2      
327m0617            R344  -2   M      A12X+031783Y+016138X0198Y0197     S2      
317m0617            VIA   -    MD0100PA00X+029541Y+017924X0180Y    R090 S0      
317m0618            VIA   -    MD0100PA00X+025705Y+019124X0180Y         S2      
327m0618            U5    -N1         A01X+025549Y+019280X0160Y    R180 S1      
327m0618            U1    -R7         A01X+030650Y+016814X0145Y         S1      
327m0618            R360  -1          A12X+033418Y+017091X0198Y0197R180 S2      
327m0618            R335  -2          A01X+033425Y+016991X0198Y0197R180 S1      
317m0618            VIA   -    MD0100PA00X+033140Y+016991X0200Y         S0      
317m0618            VIA   -    MD0100PA00X+030801Y+016664X0180Y         S0      
327m0619            U5    -M1         A01X+025549Y+018965X0160Y    R180 S1      
327m0619            VIA   -    M      A01X+027484Y+018993X0300Y         S1      
327m0619            U1    -R2         A01X+029076Y+016814X0145Y         S1      
327m0619            R359  -1   M      A12X+030994Y+014945X0198Y0197R090 S2      
327m0619            R334  -2          A12X+030994Y+014150X0198Y0197R270 S2      
317m0619            VIA   -    MD0100PA00X+029226Y+016964X0180Y    R180 S0      
327m0620            U1    -R8         A01X+030966Y+016814X0145Y         S1      
327m0620            R358  -1          A12X+033418Y+017491X0198Y0197R180 S2      
327m0620            R333  -2          A01X+033425Y+017491X0198Y0197R180 S1      
317m0620            VIA   -    MD0100PA00X+033140Y+017491X0200Y         S0      
327m0620            VIA   -    M      A01X+032783Y+017440X0300Y         S1      
317m0620            VIA   -    MD0100PA00X+031116Y+016964X0180Y    R090 S0      
317m0620            VIA   -    MD0100PA00X+026412Y+018810X0180Y         S0      
327m0620            U5    -M2         A01X+025234Y+018965X0160Y    R180 S1      
317m0621            VIA   -    MD0100PA00X+024445Y+018810X0180Y    R180 S0      
327m0621            U5    -M5         A01X+024289Y+018965X0160Y    R180 S1      
327m0621            VIA   -    M      A12X+030082Y+015456X0260Y         S2      
327m0621            U1    -P2         A01X+029076Y+017129X0145Y         S1      
327m0621            R357  -1   M      A12X+030594Y+014945X0198Y0197R090 S2      
327m0621            R332  -2          A12X+030594Y+014150X0198Y0197R270 S2      
317m0621            VIA   -    MD0100PA00X+028925Y+017279X0180Y    R270 S0      
327m0622            U1    -P8  M      A01X+030966Y+017129X0145Y         S1      
327m0622            R356  -1          A12X+033425Y+017891X0198Y0197R180 S2      
327m0622            R331  -2          A01X+033425Y+017991X0198Y0197R180 S1      
317m0622            VIA   -    MD0100PA00X+033140Y+017991X0200Y         S0      
317m0622            VIA   -    MD0100PA00X+030815Y+016979X0180Y    R270 S0      
317m0622            VIA   -    MD0100PA00X+027047Y+018849X0180Y    R180 S0      
327m0622            VIA   -    M      A01X+026720Y+018557X0300Y         S1      
327m0622            U5    -L1         A01X+025549Y+018650X0160Y    R180 S1      
317m0623            VIA   -    MD0100PA00X+025075Y+017865X0180Y    R180 S0      
327m0623            U5    -J3         A01X+024919Y+018020X0160Y    R180 S1      
327m0623            U1    -N3         A01X+029391Y+017444X0145Y         S1      
327m0623            R355  -1   M      A01X+030594Y+014945X0198Y0197R270 S1      
327m0623            R330  -2          A01X+030594Y+014145X0198Y0197R090 S1      
317m0623            VIA   -    M      A01X+029541Y+017294X0180Y    R090 S2      
017m0623            VIA   -    M      A12X+029541Y+017294X0260Y    R090 S2      
017m0623                  -    MD0100PA00X+029541Y+017294                       
327m0624            U1    -N7         A01X+030650Y+017444X0145Y         S1      
327m0624            R354  -1          A12X+032586Y+016741X0198Y0197R180 S2      
327m0624            R329  -2   M      A12X+031783Y+016538X0198Y0197     S2      
317m0624            VIA   -    M      A01X+030500Y+017294X0180Y    R270 S2      
017m0624            VIA   -    M      A12X+030500Y+017294X0260Y    R270 S2      
017m0624                  -    MD0100PA00X+030500Y+017294                       
327m0624            U5    -H3         A01X+024919Y+017705X0160Y    R180 S1      
317m0624            VIA   -    MD0100PA00X+025075Y+017550X0180Y    R180 S0      
327m0625            U5    -F1         A01X+025549Y+017075X0160Y    R180 S1      
327m0625            U1    -R3  M      A01X+029391Y+016814X0145Y         S1      
327m0625            R353  -1   M      A01X+030194Y+014945X0198Y0197R270 S1      
327m0625            R328  -2          A01X+030194Y+014135X0198Y0197R090 S1      
327m0626            U5    -K5         A01X+024289Y+018335X0160Y    R180 S1      
317m0626            VIA   -    MD0100PA00X+024445Y+018180X0180Y    R180 S0      
327m0626            U1    -P7         A01X+030650Y+017129X0145Y         S1      
327m0626            R352  -1          A12X+033425Y+015891X0198Y0197R180 S2      
327m0626            R327  -2          A01X+033425Y+015991X0198Y0197R180 S1      
317m0626            VIA   -    MD0100PA00X+033140Y+015991X0200Y         S0      
317m0626            VIA   -    MD0100PA00X+030500Y+016979X0180Y    R270 S0      
327m0627            U5    -K3         A01X+024919Y+018335X0160Y    R180 S1      
317m0627            VIA   -    MD0100PA00X+025075Y+018180X0180Y         S0      
327m0627            U1    -T8         A01X+030966Y+016499X0145Y         S1      
327m0627            R364  -1          A12X+033425Y+016291X0198Y0197R180 S2      
327m0627            R339  -2          A01X+033425Y+016491X0198Y0197R180 S1      
327m0627            VIA   -    M      A01X+032738Y+016435X0300Y         S1      
317m0627            VIA   -    MD0100PA00X+033140Y+016491X0200Y         S0      
317m0627            VIA   -    MD0100PA00X+031116Y+016349X0180Y         S0      
317m0628            VIA   -    MD0100PA00X+024760Y+018494X0180Y    R180 S0      
327m0628            U5    -L4         A01X+024604Y+018650X0160Y    R180 S1      
327m0628            VIA   -    M      A12X+031060Y+017449X0260Y         S2      
327m0628            U1    -M7         A01X+030650Y+017759X0145Y         S1      
327m0628            R363  -1   M      A12X+032586Y+017541X0198Y0197R180 S2      
327m0628            R338  -2          A12X+032586Y+017941X0198Y0197     S2      
317m0628            VIA   -    MD0100PA00X+030500Y+017608X0180Y    R270 S0      
327m0629            U5    -G1         A01X+025549Y+017390X0160Y    R180 S1      
317m0629            VIA   -    MD0100PA00X+025705Y+017235X0180Y    R180 S0      
327m0629            U1    -T2         A01X+029076Y+016499X0145Y         S1      
327m0629            VIA   -    M      A12X+029257Y+016002X0260Y         S2      
327m0629            R362  -1   M      A12X+030194Y+014945X0198Y0197R090 S2      
327m0629            R337  -2          A12X+030194Y+014150X0198Y0197R270 S2      
317m0629            VIA   -    MD0100PA00X+028911Y+016349X0180Y         S0      
327m0630            R336  -2          A01X+030994Y+014145X0198Y0197R090 S1      
327m0630            R361  -1   M      A01X+030994Y+014945X0198Y0197R270 S1      
327m0630            U1    -M3  M      A01X+029391Y+017759X0145Y         S1      
317m0630            VIA   -    MD0100PA00X+029240Y+017608X0180Y         S0      
327m0630            U5    -F2         A01X+025234Y+017075X0160Y    R180 S1      
317m0630            VIA   -    MD0100PA00X+025390Y+016920X0180Y    R180 S0      
317m0631            VIA   -    MD0100PA00X+025075Y+016920X0180Y    R180 S2      
327m0631            U5    -F3         A01X+024919Y+017075X0160Y    R180 S1      
327m0631            U1    -P3         A01X+029391Y+017129X0145Y         S1      
327m0631            R351  -1   M      A12X+031794Y+014945X0198Y0197R090 S2      
327m0631            R326  -2          A12X+031794Y+014150X0198Y0197R270 S2      
317m0631            VIA   -    MD0100PA00X+029541Y+016979X0180Y    R090 S0      
327m0632            U5    -V2         A01X+025234Y+020855X0160Y    R180 S1      
317m0632            VIA   -    MD0100PA00X+026708Y+021459X0180Y         S0      
317m0632            VIA   -    MD0100PA00X+030500Y+021059X0180Y    R090 S0      
327m0632            U1    -B7         A01X+030650Y+020908X0145Y         S1      
327m0633            U5    -V1         A01X+025549Y+020855X0160Y    R180 S1      
317m0633            VIA   -    MD0100PA00X+026358Y+021459X0180Y         S0      
317m0633            VIA   -    MD0100PA00X+030801Y+021073X0180Y    R270 S0      
327m0633            U1    -A7         A01X+030650Y+021223X0145Y         S1      
327m0634            U1    -G3         A01X+029391Y+019334X0145Y         S1      
317m0634            VIA   -    MD0100PA00X+029541Y+019484X0180Y    R270 S0      
327m0634            U5    -T2         A01X+025234Y+020225X0160Y    R180 S1      
317m0634            VIA   -    MD0100PA00X+026258Y+020726X0180Y         S0      
327m0635            U1    -F3         A01X+029391Y+019649X0145Y         S1      
317m0635            VIA   -    MD0100PA00X+029240Y+019498X0180Y    R090 S0      
327m0635            U5    -T1         A01X+025549Y+020225X0160Y    R180 S1      
317m0635            VIA   -    MD0100PA00X+026608Y+020726X0180Y         S0      
317m0636            VIA   -    M      A01X+031116Y+021059X0180Y         S2      
017m0636            VIA   -    M      A12X+031116Y+021059X0260Y         S2      
017m0636                  -    MD0100PA00X+031116Y+021059                       
327m0636            U1    -B8         A01X+030966Y+020908X0145Y         S1      
327m0636            U5    -V3         A01X+024919Y+020855X0160Y    R180 S1      
317m0636            VIA   -    MD0100PA00X+025075Y+021010X0180Y         S0      
327m0637            U5    -W2         A01X+025234Y+021170X0160Y    R180 S1      
317m0637            VIA   -    MD0100PA00X+025390Y+021325X0180Y         S0      
317m0637            VIA   -    M      A01X+029240Y+021374X0180Y         S2      
017m0637            VIA   -    M      A12X+029240Y+021374X0260Y         S2      
017m0637                  -    MD0100PA00X+029240Y+021374                       
327m0637            U1    -A3         A01X+029391Y+021223X0145Y         S1      
327m0638            U5    -P3         A01X+024919Y+019595X0160Y    R180 S1      
317m0638            VIA   -    MD0100PA00X+025075Y+019751X0180Y         S0      
317m0638            VIA   -    MD0100PA00X+030801Y+018854X0180Y    R090 S0      
327m0638            U1    -J7         A01X+030650Y+018704X0145Y         S1      
327m0639            U5    -P2         A01X+025234Y+019595X0160Y    R180 S1      
317m0639            VIA   -    MD0100PA00X+025390Y+019751X0180Y         S0      
327m0639            U1    -J3         A01X+029391Y+018704X0145Y         S1      
317m0639            VIA   -    MD0100PA00X+029240Y+018553X0180Y         S0      
317m0640            VIA   -    MD0100PA00X+031116Y+019169X0180Y         S0      
327m0640            U1    -H8         A01X+030966Y+019019X0145Y         S1      
317m0640            VIA   -    MD0100PA00X+025705Y+019751X0180Y         S2      
327m0640            U5    -P1         A01X+025549Y+019595X0160Y    R180 S1      
327m0641            U5    -R1         A01X+025549Y+019910X0160Y    R180 S1      
317m0641            VIA   -    MD0100PA00X+025705Y+020066X0180Y         S0      
317m0641            VIA   -    MD0100PA00X+028925Y+019169X0180Y         S0      
327m0641            U1    -H2         A01X+029076Y+019019X0145Y         S1      
327m0642            U5    -R3         A01X+024919Y+019910X0160Y    R180 S1      
317m0642            VIA   -    MD0100PA00X+025075Y+020066X0180Y         S0      
327m0642            U1    -H7         A01X+030650Y+019019X0145Y         S1      
317m0642            VIA   -    MD0100PA00X+030801Y+019169X0180Y    R270 S0      
327m0643            U5    -U1         A01X+025549Y+020540X0160Y    R180 S1      
317m0643            VIA   -    MD0100PA00X+025705Y+020696X0180Y         S0      
327m0643            U1    -H3         A01X+029391Y+019019X0145Y         S1      
317m0643            VIA   -    MD0100PA00X+029240Y+019169X0180Y         S0      
327m0644            U1    -F7         A01X+030650Y+019649X0145Y         S1      
317m0644            VIA   -    M      A01X+029967Y+020133X0180Y         S2      
017m0644            VIA   -    M      A12X+029967Y+020133X0260Y         S2      
017m0644                  -    MD0100PA00X+029967Y+020133                       
317m0644            VIA   -    MD0100PA00X+024760Y+020066X0180Y         S0      
327m0644            U5    -R4         A01X+024604Y+019910X0160Y    R180 S1      
327m0645            U5    -U3         A01X+024919Y+020540X0160Y    R180 S1      
317m0645            VIA   -    MD0100PA00X+025075Y+020696X0180Y         S0      
317m0645            VIA   -    MD0100PA00X+030500Y+020443X0180Y         S0      
327m0645            U1    -D7         A01X+030650Y+020278X0145Y         S1      
327m0646            U5    -V4         A01X+024604Y+020855X0160Y    R180 S1      
317m0646            VIA   -    MD0100PA00X+024760Y+021010X0180Y         S0      
317m0646            VIA   -    M      A01X+029240Y+020128X0180Y    R090 S2      
017m0646            VIA   -    M      A12X+029240Y+020128X0260Y    R090 S2      
017m0646                  -    MD0100PA00X+029240Y+020128                       
327m0646            U1    -D3         A01X+029391Y+020278X0145Y         S1      
317m0647            VIA   -    MD0100PA00X+030815Y+020443X0180Y    R090 S0      
327m0647            U1    -C8         A01X+030966Y+020594X0145Y         S1      
327m0647            U5    -U4         A01X+024604Y+020540X0160Y    R180 S1      
317m0647            VIA   -    MD0100PA00X+024760Y+020696X0180Y         S0      
327m0648            U5    -W4         A01X+024604Y+021170X0160Y    R180 S1      
317m0648            VIA   -    MD0100PA00X+024760Y+021325X0180Y         S0      
317m0648            VIA   -    MD0100PA00X+029240Y+021059X0180Y    R270 S0      
327m0648            U1    -C2         A01X+029076Y+020594X0145Y         S1      
327m0649            U5    -W3         A01X+024919Y+021170X0160Y    R180 S1      
317m0649            VIA   -    MD0100PA00X+025075Y+021325X0180Y         S0      
317m0649            VIA   -    MD0100PA00X+030801Y+020744X0180Y         S0      
327m0649            U1    -C7         A01X+030650Y+020594X0145Y         S1      
317m0650            VIA   -    MD0100PA00X+025705Y+021325X0180Y         S0      
327m0650            U5    -W1         A01X+025549Y+021170X0160Y    R180 S1      
327m0650            U1    -C3         A01X+029391Y+020594X0145Y         S1      
317m0650            VIA   -    M      A01X+029871Y+021048X0180Y    R270 S2      
017m0650            VIA   -    M      A12X+029871Y+021048X0260Y    R270 S2      
017m0650                  -    MD0100PA00X+029871Y+021048                       
317m0651            VIA   -    M      A01X+028925Y+019484X0180Y         S2      
017m0651            VIA   -    M      A12X+028925Y+019484X0260Y         S2      
017m0651                  -    MD0100PA00X+028925Y+019484                       
327m0651            U1    -G2         A01X+029076Y+019334X0145Y         S1      
327m0651            U5    -T3         A01X+024919Y+020225X0160Y    R180 S1      
317m0651            VIA   -    MD0100PA00X+025075Y+020380X0180Y    R180 S0      
327M_BMC_DDR4_BG1   U1    -M9         A01X+031280Y+017759X0145Y         S1      
327M_BMC_DDR4_BG1   R2    -1   M      A12X+031783Y+017738X0198Y0197R180 S2      
327M_BMC_DDR4_BG1   R1    -1          A12X+032900Y+018341X0198Y0197     S2      
317M_BMC_DDR4_BG1   VIA   -    MD0100PA00X+031493Y+017759X0180Y    R045 S0      
327m0652            R9    -1          A12X+032586Y+017141X0198Y0197R180 S2      
317m0652            VIA   -    MD0100PA00X+031493Y+017129X0180Y    R045 S0      
327m0652            U1    -P9         A01X+031280Y+017129X0145Y         S1      
317m0652            VIA   -    MD0100PA00X+024760Y+019124X0180Y         S0      
327m0652            U5    -N4         A01X+024604Y+019280X0160Y    R180 S1      
327JTAG_MB_TRST_N   VIA   -    M      A12X+020406Y+012894X0280Y         S2      
327JTAG_MB_TRST_N   R221  -2          A12X+020290Y+013492X0198Y0197R090 S2      
327JTAG_MB_TRST_N   R229  -2          A12X+020400Y+012308X0198Y0197R270 S2      
327JTAG_MB_TMS      VIA   -    M      A12X+015142Y+043288X0280Y         S2      
327JTAG_MB_TMS      GF1   -A35        A12X+015612Y+046638X0150Y0840R180 S2      
327JTAG_MB_TMS      R223  -2          A12X+020691Y+014411X0198Y0197R090 S2      
327JTAG_MB_TMS      R227  -2   M      A12X+015000Y+042032X0198Y0197R270 S2      
317JTAG_MB_TMS      VIA   -    MD0100PA00X+020560Y+014048X0200Y         S0      
317JTAG_MB_TMS      VIA   -    MD0100PA00X+014806Y+042350X0200Y         S0      
327JTAG_MB_TCK      GF1   -A34        A12X+015848Y+046559X0150Y0680R180 S2      
317JTAG_MB_TCK      VIA   -    MD0100PA00X+015308Y+041200X0200Y         S0      
317JTAG_MB_TCK      VIA   -    MD0100PA00X+006903Y+042265X0200Y         S0      
327JTAG_MB_TCK      R228  -2   M      A12X+015760Y+042038X0198Y0197R270 S2      
317JTAG_MB_TCK      VIA   -    M      A01X+018211Y+012909X0200Y         S2      
017JTAG_MB_TCK      VIA   -    M      A12X+018211Y+012909X0260Y         S2      
017JTAG_MB_TCK            -    MD0100PA00X+018211Y+012909                       
327JTAG_MB_TCK      R222  -2          A12X+018295Y+013479X0198Y0197R090 S2      
327m0653            R131  -1          A12X+025046Y+024258X0198Y0197R270 S2      
327m0653            U5    -AC7        A01X+023659Y+022430X0160Y    R180 S1      
327m0653            VIA   -    M      A12X+024770Y+022940X0260Y         S2      
317m0653            VIA   -    MD0100PA00X+023504Y+022274X0180Y         S0      
327m0654            R130  -1          A12X+023841Y+024196X0198Y0197R270 S2      
327m0654            U5    -AC8        A01X+023344Y+022430X0160Y    R180 S1      
327m0654            VIA   -    M      A12X+023838Y+023247X0260Y         S2      
317m0654            VIA   -    MD0100PA00X+023189Y+022274X0180Y         S0      
327m0655            U5    -AB8        A01X+023344Y+022115X0160Y    R180 S1      
327m0655            VIA   -    M      A12X+026410Y+023550X0260Y         S2      
317m0655            VIA   -    MD0100PA00X+023189Y+021959X0180Y         S0      
327m0655            R129  -1          A12X+026180Y+024262X0198Y0197R270 S2      
327m0656            R128  -1          A12X+025447Y+024267X0198Y0197R270 S2      
327m0656            U5    -AB7        A01X+023659Y+022115X0160Y    R180 S1      
327m0656            VIA   -    M      A12X+025900Y+023760X0260Y         S2      
317m0656            VIA   -    MD0100PA00X+023815Y+022270X0180Y         S0      
327m0657            R221  -1          A12X+020290Y+013808X0198Y0197R090 S2      
327m0657            U5    -D17        A01X+020510Y+016445X0160Y    R180 S1      
327m0657            VIA   -    M      A12X+020225Y+014540X0260Y         S2      
317m0657            VIA   -    MD0100PA00X+020354Y+016290X0180Y         S0      
327m0658            R223  -1          A12X+020691Y+014726X0198Y0197R090 S2      
327m0658            U5    -D16        A01X+020825Y+016445X0160Y    R180 S1      
317m0658            VIA   -    MD0100PA00X+020669Y+016290X0180Y         S2      
327m0659            R639  -1          A01X+020863Y+013794X0198Y0197R270 S1      
327m0659            U5    -A16        A01X+020825Y+015500X0160Y    R180 S1      
317m0659            VIA   -    M      A01X+021149Y+014370X0200Y         S2      
017m0659            VIA   -    M      A12X+021149Y+014370X0260Y         S2      
017m0659                  -    MD0100PA00X+021149Y+014370                       
327m0660            R222  -1          A12X+018295Y+013794X0198Y0197R090 S2      
327m0660            U5    -E17        A01X+020510Y+016760X0160Y    R180 S1      
327m0660            VIA   -    M      A12X+018717Y+014367X0260Y         S2      
317m0660            VIA   -    MD0100PA00X+020354Y+016605X0180Y    R180 S0      
327IRQ_TPM_SPI_N    VIA   -    M      A01X+028820Y+034830X0300Y         S1      
317IRQ_TPM_SPI_N    VIA   -    MD0100PA00X+028130Y+030880X0200Y         S0      
327IRQ_TPM_SPI_N    R113  -1          A01X+028842Y+037270X0198Y0197     S1      
327IRQ_TPM_SPI_N    R59   -2   M      A01X+028448Y+037193X0198Y0197R270 S1      
317IRQ_TPM_SPI_N    VIA   -    MD0100PA00X+016839Y+029849X0200Y         S0      
317IRQ_TPM_SPI_N    VIA   -    MD0100PA00X+020975Y+023540X0180Y    R180 S0      
327IRQ_TPM_SPI_N    U5    -AF15       A01X+021140Y+023374X0160Y    R180 S1      
327m0661            R177  -1          A01X+015888Y+019170X0198Y0197R180 S1      
327m0661            U5    -P24        A01X+018305Y+019595X0160Y    R180 S1      
327m0661            VIA   -    M      A01X+016500Y+019181X0300Y         S1      
317m0662            VIA   -    M      A01X+022721Y+040010X0200Y         S2      
017m0662            VIA   -    M      A12X+022721Y+040010X0260Y         S2      
017m0662                  -    MD0100PA00X+022721Y+040010                       
317m0662            VIA   -    MD0100PA00X+023054Y+024456X0200Y         S0      
327m0662            R37   -1          A12X+023052Y+024198X0198Y0197R090 S2      
327m0662            GF1   -A56        A12X+008955Y+046559X0150Y0680R180 S2      
317m0662            VIA   -    MD0100PA00X+007901Y+044575X0200Y         S0      
317m0662            VIA   -    MD0100PA00X+022400Y+044910X0200Y         S0      
327m0663            R37   -2          A12X+023052Y+023882X0198Y0197R090 S2      
327m0663            U5    -AC9        A01X+023030Y+022430X0160Y    R180 S1      
317m0663            VIA   -    MD0100PA00X+022874Y+022585X0180Y    R270 S0      
327m0664            U5    -AD7        A01X+023659Y+022745X0160Y    R180 S1      
317m0664            VIA   -    MD0100PA00X+023504Y+022589X0180Y         S0      
327m0664            R119  -2          A01X+025050Y+025008X0198Y0197R270 S1      
317m0664            VIA   -    MD0100PA00X+024769Y+024793X0200Y         S0      
327m0665            VIA   -    M      A12X+013343Y+018640X0260Y         S2      
317m0665            VIA   -    MD0100PA00X+010336Y+034642X0180Y         S0      
327m0665            U25   -B3         A01X+010181Y+034798X0160Y    R180 S1      
327m0665            R166  -1          A12X+016365Y+017688X0198Y0197R180 S2      
317m0665            VIA   -    MD0100PA00X+011300Y+016070X0200Y         S0      
327m0666            R166  -2          A12X+016680Y+017688X0198Y0197R180 S2      
327m0666            U5    -J24        A01X+018305Y+018020X0160Y    R180 S1      
327m0666            VIA   -    M      A12X+017160Y+017800X0260Y         S2      
317m0666            VIA   -    MD0100PA00X+018150Y+017865X0180Y    R180 S0      
317m0667            D13   -A    D0320PA00X+011705Y+002476X0480Y0480     S3      
327m0667            R43   -1          A01X+012050Y+003892X0198Y0197R090 S1      
327IBMC_MIOZ        U5    -P5         A01X+024289Y+019595X0160Y    R180 S1      
327IBMC_MIOZ        R127  -2          A12X+025300Y+020310X0198Y0197     S2      
317IBMC_MIOZ        VIA   -    MD0100PA00X+024445Y+019751X0180Y         S0      
327I3C4_SPD_SDA     R201  -2          A01X+016501Y+025259X0198Y0197R090 S1      
317I3C4_SPD_SDA     VIA   -    M      A01X+026380Y+043030X0200Y         S2      
017I3C4_SPD_SDA     VIA   -    M      A12X+026380Y+043030X0260Y         S2      
017I3C4_SPD_SDA           -    MD0100PA00X+026380Y+043030                       
327I3C4_SPD_SDA     GF1   -OA12       A12X+027189Y+046559X0150Y0680R180 S2      
327I3C4_SPD_SDA     R197  -2          A12X+016501Y+025259X0198Y0197R270 S2      
317I3C4_SPD_SDA     VIA   -    MD0100PA00X+026673Y+044318X0200Y         S0      
317I3C4_SPD_SDA     VIA   -    MD0100PA00X+016501Y+025499X0200Y         S0      
327I3C4_SPD_SCL     R200  -2          A01X+015697Y+025259X0198Y0197R090 S1      
317I3C4_SPD_SCL     VIA   -    M      A01X+026710Y+043290X0200Y         S2      
017I3C4_SPD_SCL     VIA   -    M      A12X+026710Y+043290X0260Y         S2      
017I3C4_SPD_SCL           -    MD0100PA00X+026710Y+043290                       
327I3C4_SPD_SCL     GF1   -OA11       A12X+027425Y+046559X0150Y0680R180 S2      
327I3C4_SPD_SCL     R196  -2          A12X+015696Y+025259X0198Y0197R270 S2      
317I3C4_SPD_SCL     VIA   -    MD0100PA00X+027171Y+044984X0200Y         S0      
317I3C4_SPD_SCL     VIA   -    MD0100PA00X+015697Y+025500X0200Y         S0      
327I3C4_SDA_R       R201  -1          A01X+016501Y+024944X0198Y0197R090 S1      
327I3C4_SDA_R       U5    -AF24       A01X+018305Y+023374X0160Y    R180 S1      
327I3C4_SCL_R       R200  -1          A01X+015697Y+024944X0198Y0197R090 S1      
327I3C4_SCL_R       U5    -AE25       A01X+017990Y+023060X0160Y    R180 S1      
327I3C3_SPD_SDA     R199  -2          A01X+015671Y+026060X0198Y0197R090 S1      
327I3C3_SPD_SDA     GF1   -OA10       A12X+027661Y+046638X0150Y0840R180 S2      
327I3C3_SPD_SDA     R189  -2          A12X+015670Y+026055X0198Y0197R270 S2      
317I3C3_SPD_SDA     VIA   -    MD0100PA00X+027514Y+045122X0200Y         S0      
317I3C3_SPD_SDA     VIA   -    MD0100PA00X+015697Y+026325X0200Y         S0      
327I3C3_SPD_SCL     R198  -2          A01X+016071Y+026060X0198Y0197R090 S1      
327I3C3_SPD_SCL     GF1   -OA9        A12X+027898Y+046638X0150Y0840R180 S2      
327I3C3_SPD_SCL     R188  -2          A12X+016076Y+026054X0198Y0197R270 S2      
317I3C3_SPD_SCL     VIA   -    MD0100PA00X+028362Y+044716X0200Y         S0      
317I3C3_SPD_SCL     VIA   -    MD0100PA00X+016059Y+026330X0200Y         S0      
327I3C3_SDA_R       R199  -1          A01X+015671Y+025745X0198Y0197R090 S1      
327I3C3_SDA_R       U5    -AE26       A01X+017675Y+023060X0160Y    R180 S1      
327I3C3_SCL_R       R198  -1          A01X+016071Y+025745X0198Y0197R090 S1      
327I3C3_SCL_R       U5    -AF25       A01X+017990Y+023374X0160Y    R180 S1      
327I3C2_SDA_R       R187  -2          A01X+016997Y+025739X0198Y0197R270 S1      
327I3C2_SDA_R       U5    -AE22       A01X+018935Y+023060X0160Y    R180 S1      
327I3C2_SCL_R       R186  -2          A01X+017399Y+025739X0198Y0197R270 S1      
327I3C2_SCL_R       U5    -AF22       A01X+018935Y+023374X0160Y    R180 S1      
327m0668            U5    -A4         A01X+024604Y+015500X0160Y    R180 S1      
327m0668            R217  -1          A01X+025433Y+011723X0198Y0197R270 S1      
327m0669            U5    -B4         A01X+024604Y+015816X0160Y    R180 S1      
327m0669            R218  -1          A01X+025834Y+011723X0198Y0197R270 S1      
327GND              VIA   -           A12X+000781Y+028840X0260Y    R180 S2      
327GND              VIA   -           A12X+000781Y+027340X0260Y    R180 S2      
327GND              VIA   -           A12X+000781Y+016840X0260Y         S2      
327GND              VIA   -           A12X+000781Y+018340X0260Y         S2      
327GND              VIA   -           A12X+033020Y+028860X0260Y    R090 S2      
327GND              VIA   -           A12X+033020Y+029610X0260Y    R090 S2      
327GND              VIA   -           A12X+033020Y+030360X0260Y    R090 S2      
327GND              VIA   -           A12X+032270Y+030360X0260Y    R180 S2      
327GND              VIA   -           A12X+032270Y+029610X0260Y    R180 S2      
327GND              VIA   -           A12X+000781Y+019840X0260Y         S2      
327GND              VIA   -           A12X+000781Y+021340X0260Y         S2      
327GND              VIA   -           A12X+000781Y+022840X0260Y         S2      
327GND              VIA   -           A12X+000781Y+024340X0260Y         S2      
327GND              VIA   -           A12X+000781Y+025840X0260Y         S2      
327GND              SW6   -1          A01X+002264Y+002752X0590Y0790     S1      
327GND              R855  -2          A12X+028500Y+007592X0198Y0197R090 S2      
327GND              C227  -2          A01X+030808Y+031150X0198Y0197     S1      
317GND              VIA   -    MD0100PA00X+011500Y+036950X0200Y         S0      
327GND              C337  -2          A12X+011802Y+037680X0198Y0197     S2      
317GND              VIA   -    MD0100PA00X+013364Y+039052X0200Y         S0      
327GND              U58   -3          A12X+013409Y+038702X0280Y0400R180 S2      
327GND              SW6   -4          A01X+004803Y+001059X0790Y0790     S1      
327GND              SW6   -3          A01X+001496Y+001059X0790Y0790     S1      
327GND              SW8   -4          A01X+029449Y+001217X0790Y0790     S1      
327GND              SW8   -3          A01X+026142Y+001217X0790Y0790     S1      
327GND              SW8   -1          A01X+026910Y+002910X0590Y0790     S1      
317GND              D21   -C   MD0320PA00X+022114Y+002476X0480Y         S3      
327GND              PU38  -11_1       A01X+002317Y+019785X0315Y1240R180 S1      
327GND              PU38  -6          A01X+003331Y+019835X0070Y0320R270 S1      
327GND              PU38  -4          A01X+003331Y+019520X0070Y0320R270 S1      
327GND              PU38  -2          A01X+003331Y+019205X0070Y0320R270 S1      
317GND              VIA   -    MD0100PA00X+004085Y+044844X0200Y         S0      
317GND              VIA   -    MD0100PA00X+028461Y+038714X0200Y         S0      
317GND              VIA   -    MD0100PA00X+020318Y+041637X0200Y         S0      
317GND              VIA   -    MD0100PA00X+006056Y+031484X0200Y         S0      
317GND              VIA   -    MD0100PA00X+005865Y+029060X0200Y    R084 S0      
317GND              VIA   -    MD0100PA00X+011118Y+029347X0200Y         S0      
317GND              VIA   -    MD0100PA00X+014536Y+042605X0200Y         S0      
317GND              VIA   -    MD0100PA00X+016519Y+042869X0200Y         S0      
317GND              VIA   -    MD0100PA00X+018033Y+011429X0200Y         S0      
327GND              U8    -3          A12X+005344Y+009126X0170Y0240     S2      
327GND              R306  -2   M      A12X+004800Y+009758X0198Y0197R270 S2      
317GND              VIA   -    MD0100PA00X+005327Y+010909X0200Y         S0      
327GND              C274  -2          A12X+006000Y+010658X0198Y0197R270 S2      
327GND              C326  -2          A12X+005950Y+007892X0198Y0197R090 S2      
327GND              R417  -2          A12X+006892Y+007650X0198Y0197     S2      
317GND              VIA   -    MD0100PA00X+006593Y+007650X0200Y         S0      
327GND              R53   -2          A12X+007650Y+006892X0198Y0197R090 S2      
327GND              R419  -2          A12X+009450Y+006942X0198Y0197R090 S2      
317GND              VIA   -    MD0100PA00X+027422Y+005164X0200Y         S0      
327GND              C335  -2          A12X+027158Y+004900X0198Y0197R180 S2      
317GND              VIA   -    MD0100PA00X+026097Y+004244X0200Y         S0      
327GND              U57   -3          A01X+026450Y+004244X0400Y0150     S1      
317GND              VIA   -    MD0100PA00X+027700Y+004198X0200Y         S0      
327GND              C336  -2          A01X+027700Y+004442X0198Y0197R270 S1      
317GND              J2    -G2  MD0910PA00X+019485Y+004480X1310Y    R090 S3      
317GND              J2    -G1  MD0910PA00X+014312Y+004480X1310Y    R090 S3      
317GND              J2    -4   MD0280PA00X+018276Y+005268X0440Y    R090 S3      
317GND              VIA   -    MD0100PA00X+028600Y+006798X0200Y         S0      
327GND              C28   -2          A01X+028600Y+006558X0198Y0197R090 S1      
317GND              VIA   -    MD0100PA00X+028244Y+005194X0200Y         S0      
327GND              U16   -3          A01X+028600Y+005194X0400Y0150     S1      
317GND              VIA   -    MD0100PA00X+030358Y+005452X0200Y         S0      
327GND              C29   -2          A01X+030358Y+005700X0198Y0197     S1      
317GND              VIA   -    MD0100PA00X+029024Y+004698X0200Y         S0      
327GND              C181  -2          A01X+029024Y+004458X0198Y0197R090 S1      
317GND              VIA   -    MD0100PA00X+029540Y+004805X0200Y         S0      
327GND              D10   -C          A01X+029540Y+004522X0220Y0240R270 S1      
317GND              VIA   -    MD0100PA00X+028886Y+001217X0200Y         S0      
317GND              VIA   -    MD0100PA00X+026702Y+001217X0200Y         S0      
317GND              VIA   -    MD0100PA00X+026910Y+003462X0200Y         S0      
327GND              J13   -3          A01X+026491Y+007950X0400Y1090R090 S1      
317GND              H1    -1   M      A01X+010532Y+021334X1780Y         S3      
017GND              H1    -1   M      A12X+010532Y+021334X3150Y         S3      
017GND                    -    MD1500PA00X+010532Y+021334                       
327GND              R387  -1          A12X+025667Y+015875X0198Y0197     S2      
317GND              VIA   -    MD0100PA00X+023300Y+004710X0200Y         S0      
327GND              C27   -2          A01X+023300Y+004458X0198Y0197R090 S1      
317GND              VIA   -    MD0100PA00X+024836Y+004656X0200Y         S0      
327GND              Q13   -1          A01X+024576Y+004656X0170Y0200R090 S1      
317GND              VIA   -    MD0100PA00X+012790Y+004500X0200Y         S0      
327GND              Q9    -1          A01X+012526Y+004446X0170Y0200R090 S1      
327GND              U9    -3          A01X+010878Y+004776X0280Y0400R270 S1      
317GND              VIA   -    MD0100PA00X+011100Y+004460X0200Y         S0      
327GND              C324  -2          A01X+011250Y+004208X0198Y0197R090 S1      
327GND              U15   -3          A01X+016056Y+027371X0130Y0460     S1      
327GND              R642  -1          A12X+015200Y+026308X0198Y0197R090 S2      
317GND              VIA   -    MD0100PA00X+016369Y+026861X0200Y         S0      
327GND              D3    -C          A01X+029138Y+011216X0320Y0320R090 S1      
327GND              D2    -C   M      A01X+029782Y+010806X0320Y0320R270 S1      
327GND              D1    -C   M      A01X+030426Y+011216X0320Y0320R090 S1      
327GND              D0    -C          A01X+031066Y+010806X0320Y0320R270 S1      
317GND              VIA   -    MD0100PA00X+004450Y+035550X0200Y         S0      
317GND              VIA   -    MD0100PA00X+008650Y+007500X0200Y         S0      
317GND              VIA   -    MD0100PA00X+009800Y+007550X0200Y         S0      
317GND              VIA   -    MD0100PA00X+009540Y+006650X0200Y         S0      
317GND              VIA   -    MD0100PA00X+009170Y+006650X0200Y         S0      
317GND              VIA   -    MD0100PA00X+007650Y+006650X0200Y         S0      
317GND              VIA   -    MD0100PA00X+006000Y+007550X0200Y         S0      
327GND              C321  -2          A12X+005950Y+007308X0198Y0197R270 S2      
317GND              VIA   -    MD0100PA00X+005750Y+007550X0200Y         S0      
317GND              VIA   -    MD0100PA00X+004393Y+006225X0200Y         S0      
327GND              Q12   -4          A01X+004194Y+006476X0170Y0200     S1      
317GND              VIA   -    MD0100PA00X+005051Y+005746X0200Y         S0      
327GND              C200  -2          A01X+004516Y+005832X0198Y0197     S1      
317GND              VIA   -    MD0100PA00X+005942Y+005308X0200Y         S0      
317GND              VIA   -    MD0100PA00X+005300Y+004150X0200Y         S0      
327GND              U31   -3          A01X+004804Y+004590X0400Y0150R090 S1      
327GND              C191  -2   M      A01X+005064Y+003850X0198Y0197R180 S1      
317GND              VIA   -    MD0100PA00X+000941Y+001055X0200Y         S0      
317GND              VIA   -    MD0100PA00X+002732Y+002584X0200Y         S0      
317GND              VIA   -    MD0100PA00X+003504Y+003575X0200Y         S0      
327GND              C198  -2          A01X+003692Y+003800X0198Y0197R180 S1      
327GND              R614  -2          A01X+002100Y+031692X0198Y0197R270 S1      
317GND              H4    -1   MD1340PA00X+023622Y+042402X2370Y         S3      
317GND              H3    -1   MD1340PA00X+030118Y+042402X2370Y         S3      
327GND              J40   -10  M      A01X+016801Y+040437X0200Y0590     S1      
327GND              PC267 -2          A12X+009570Y+009824X0440Y0540R090 S2      
327GND              PC270 -2          A12X+008650Y+009824X0440Y0540R090 S2      
327GND              PC269 -2          A12X+007900Y+009824X0440Y0540R090 S2      
327GND              PC268 -2          A12X+007050Y+009824X0440Y0540R090 S2      
317GND              VIA   -    MD0100PA00X+010000Y+009850X0200Y         S0      
327GND              PC266 -2          A01X+010000Y+009608X0198Y0197R090 S1      
317GND              J14   -8   MD0410PA00X+009571Y+005224X0610Y         S3      
327GND              C313  -2          A01X+018912Y+031110X0198Y0197R180 S1      
327GND              C42   -2          A12X+014875Y+022095X0280Y0320R090 S2      
327GND              VIA   -           A12X+013890Y+021950X0260Y         S2      
327GND              VIA   -           A12X+014510Y+020880X0260Y         S2      
317GND              VIA   -    MD0100PA00X+016650Y+009640X0200Y         S0      
327GND              U28   -3          A01X+016188Y+009966X0180Y0520R270 S1      
317GND              VIA   -    MD0100PA00X+015970Y+011200X0200Y         S0      
327GND              C180  -2          A01X+016322Y+011280X0198Y0197R180 S1      
327GND              C26   -2          A01X+015500Y+029258X0198Y0197R090 S1      
327GND              R209  -2          A01X+019392Y+026481X0198Y0197R180 S1      
327GND              R94   -2          A01X+024250Y+034042X0198Y0197R270 S1      
327GND              R865  -2   M      A12X+027700Y+007592X0198Y0197R090 S2      
327GND              R312  -2          A12X+025750Y+027392X0198Y0197R090 S2      
327GND              R857  -2   M      A12X+028100Y+007592X0198Y0197R090 S2      
327GND              C30   -2          A01X+015243Y+015329X0198Y0197R090 S1      
327GND              C36   -2          A12X+019355Y+017160X0198Y0197R090 S2      
327GND              J4    -18         A01X+008563Y+028882X0110Y0630     S1      
327GND              C235  -2          A01X+007450Y+027392X0198Y0197R270 S1      
317GND              VIA   -    MD0100PA00X+018779Y+015975X0180Y    R180 S0      
327GND              C304  -2          A01X+006550Y+018388X0198Y0197R090 S1      
317GND              VIA   -    MD0100PA00X+030400Y+030500X0200Y         S0      
327GND              R677  -2          A01X+030058Y+030700X0198Y0197     S1      
317GND              VIA   -    MD0100PA00X+030950Y+031500X0200Y         S0      
317GND              VIA   -    MD0100PA00X+031100Y+032050X0200Y         S0      
327GND              C226  -2          A01X+031100Y+032342X0198Y0197R270 S1      
317GND              VIA   -    MD0100PA00X+030150Y+032650X0200Y         S0      
327GND              U56   -2          A01X+030150Y+033062X0280Y0400R180 S1      
327GND              R431  -2          A01X+028800Y+029408X0198Y0197R090 S1      
327GND              R164  -2          A01X+023850Y+033192X0198Y0197R270 S1      
327GND              U51   -2          A01X+006330Y+024136X0140Y0440     S1      
327GND              U50   -2          A01X+008750Y+024136X0140Y0440     S1      
327GND              U7    -2          A12X+012200Y+026156X0140Y0440     S2      
327GND              U20   -2          A12X+013450Y+026156X0140Y0440     S2      
327GND              U53   -3          A01X+005944Y+014859X0130Y0460R180 S1      
327GND              U26   -3          A12X+016845Y+001266X0240Y0240R270 S2      
327GND              U33   -3          A12X+014795Y+001266X0240Y0240R270 S2      
327GND              U39   -TH  M      A01X+032535Y+013221X0690Y1050R270 S1      
327GND              D4    -C          A01X+031066Y+012211X0320Y0320R270 S1      
327GND              PU41  -11  M      A01X+032754Y+028516X0100Y0280R270 S1      
327GND              PU41  -4          A01X+031612Y+028713X0100Y0280R270 S1      
327GND              PU41  -2          A01X+031986Y+028831X0100Y0590     S1      
327GND              PU41  -3          A01X+031612Y+028910X0100Y0280R270 S1      
327GND              U41   -TH  M      A01X+014436Y+022022X0690Y1050R180 S1      
327GND              U34   -8   M      A01X+012338Y+010500X0180Y0230R270 S1      
327GND              U34   -3          A01X+012638Y+010500X0180Y0270R270 S1      
327GND              D12   -5          A01X+011656Y+008545X0220Y0320R180 S1      
327GND              D12   -2          A01X+011656Y+009490X0220Y0320R180 S1      
317GND              VIA   -    MD0100PA00X+010458Y+006758X0200Y    R084 S0      
317GND              VIA   -    MD0100PA00X+010458Y+006237X0200Y    R084 S0      
327GND              C44   -2          A12X+028310Y+013740X0280Y0320R270 S2      
327GND              VIA   -           A12X+004940Y+016180X0260Y         S2      
327GND              VIA   -           A12X+002140Y+017810X0260Y         S2      
327GND              VIA   -           A12X+001850Y+016330X0260Y         S2      
327GND              VIA   -           A12X+033770Y+022790X0260Y         S2      
327GND              VIA   -           A12X+001880Y+012210X0260Y         S2      
327GND              VIA   -           A12X+009290Y+034280X0260Y         S2      
317GND              VIA   -    MD0100PA00X+019828Y+010129X0200Y         S0      
317GND              H7    -1   MD1260PA00X+033347Y+004642X2560Y         S3      
317GND              H6    -1   MD1260PA00X+002205Y+004642X2560Y         S3      
327GND              R273  -2          A01X+024370Y+010602X0198Y0197R270 S1      
327GND              C212  -2          A12X+011332Y+010930X0198Y0197     S2      
317GND              VIA   -    MD0100PA00X+011620Y+011510X0200Y         S0      
317GND              VIA   -    MD0100PA00X+014680Y+007900X0200Y         S0      
317GND              VIA   -    MD0100PA00X+024449Y+022900X0180Y    R270 S0      
327GND              U5    -AD4        A01X+024604Y+022745X0160Y    R180 S1      
327GND              C249  -2   M      A12X+033407Y+038664X0198Y0197R180 S2      
327GND              C248  -2          A12X+033407Y+039070X0198Y0197R180 S2      
317GND              VIA   -    MD0100PA00X+033460Y+038330X0200Y         S0      
327GND              J8    -G2         A01X+014626Y+007213X0480Y0710R270 S1      
327GND              R830  -2          A01X+032920Y+014844X0198Y0197     S1      
327GND              C291  -2   M      A01X+033328Y+014844X0198Y0197R090 S1      
327GND              C207  -2          A12X+011560Y+012110X0198Y0197R270 S2      
327GND              C156  -2          A01X+009640Y+013508X0198Y0197R090 S1      
317GND              VIA   -    MD0100PA00X+009640Y+013748X0200Y         S0      
327GND              SW7   -1          A01X+031398Y+002752X0590Y0790     S1      
327GND              C38   -2          A01X+015912Y+011904X0198Y0197R270 S1      
317GND              VIA   -    MD0100PA00X+015842Y+011661X0200Y         S0      
317GND              VIA   -    MD0100PA00X+022880Y+030270X0200Y         S0      
327GND              PC260 -2          A01X+008808Y+012505X0198Y0197R090 S1      
327GND              PU42  -11         A01X+008177Y+012623X0100Y0280R270 S1      
317GND              VIA   -    MD0100PA00X+014795Y+000980X0200Y         S0      
317GND              VIA   -    MD0100PA00X+016570Y+001110X0200Y         S0      
317GND              VIA   -    MD0100PA00X+012450Y+016710X0200Y         S0      
327GND              C154  -2          A01X+015750Y+023208X0198Y0197R090 S1      
317GND              VIA   -    MD0100PA00X+015580Y+023470X0200Y         S0      
327GND              U49   -3          A01X+012638Y+024026X0280Y0400R270 S1      
317GND              VIA   -    MD0100PA00X+011830Y+023750X0200Y         S0      
327GND              C53   -2          A01X+014150Y+014358X0198Y0197R090 S1      
317GND              VIA   -    MD0100PA00X+014200Y+014600X0200Y         S0      
327GND              C228  -2          A01X+014230Y+027562X0198Y0197R270 S1      
327GND              C280  -2          A01X+007550Y+015492X0198Y0197R270 S1      
327GND              C268  -2          A01X+011480Y+026088X0198Y0197R090 S1      
317GND              VIA   -    MD0100PA00X+012172Y+026533X0200Y         S0      
327GND              C298  -2          A01X+013042Y+025370X0198Y0197R180 S1      
327GND              C310  -2          A01X+012650Y+025678X0198Y0197R090 S1      
317GND              VIA   -    MD0100PA00X+012890Y+025590X0200Y         S0      
327GND              C19   -2          A01X+009350Y+026208X0198Y0197R090 S1      
317GND              VIA   -    MD0100PA00X+015240Y+029340X0200Y         S0      
317GND              VIA   -    MD0100PA00X+024445Y+015975X0180Y         S0      
327GND              J4    -23         A01X+009055Y+031854X0110Y0630     S1      
327GND              U5    -A1         A01X+025549Y+015500X0160Y    R180 S1      
317GND              VIA   -    MD0100PA00X+025549Y+015290X0180Y    R180 S0      
317GND              VIA   -    MD0100PA00X+012630Y+017658X0200Y         S0      
327GND              U43   -2          A01X+013350Y+015298X0240Y0420     S1      
317GND              VIA   -    MD0100PA00X+013350Y+014938X0200Y         S0      
327GND              C204  -2          A12X+012993Y+013913X0280Y0320R180 S2      
327GND              C59   -2          A12X+023819Y+017177X0198Y0197R180 S2      
327GND              C68   -2          A12X+024120Y+016848X0198Y0197R270 S2      
327GND              U5    -F8  M      A01X+023344Y+017075X0160Y    R180 S1      
327GND              U5    -H9         A01X+023030Y+017705X0160Y    R180 S1      
327GND              U5    -F6  M      A01X+023974Y+017075X0160Y    R180 S1      
317GND              VIA   -    MD0100PA00X+023815Y+016920X0180Y         S0      
317GND              VIA   -    MD0100PA00X+013122Y+028019X0200Y         S0      
317GND              VIA   -    MD0100PA00X+025575Y+007735X0200Y         S0      
317GND              VIA   -    MD0100PA00X+006749Y+018641X0200Y         S0      
327GND              C141  -2          A12X+007346Y+037318X0164Y0164R180 S2      
327GND              U25   -M12        A01X+007346Y+037948X0160Y    R180 S1      
317GND              VIA   -    MD0100PA00X+007502Y+038103X0180Y         S0      
317GND              VIA   -    MD0100PA00X+013310Y+035890X0200Y         S0      
317GND              VIA   -    MD0100PA00X+007400Y+027080X0200Y         S0      
317GND              VIA   -    MD0100PA00X+007650Y+027070X0200Y         S0      
327GND              R665  -2          A01X+006510Y+027692X0198Y0197R270 S1      
327GND              R664  -2          A01X+006120Y+027682X0198Y0197R270 S1      
327GND              C234  -2          A01X+006975Y+027110X0280Y0320R180 S1      
317GND              VIA   -    MD0100PA00X+006250Y+027250X0200Y         S0      
327GND              C255  -2          A12X+021060Y+030828X0198Y0197R270 S2      
317GND              VIA   -    MD0100PA00X+021361Y+030880X0200Y         S0      
327GND              U5    -C3         A01X+024919Y+016130X0160Y    R180 S1      
317GND              VIA   -    MD0100PA00X+025075Y+015975X0180Y    R270 S0      
327GND              C225  -2          A12X+027600Y+016242X0198Y0197R090 S2      
327GND              C40   -2          A12X+028100Y+016590X0280Y0320     S2      
317GND              VIA   -    MD0100PA00X+010123Y+012701X0200Y         S0      
327GND              J8    -4          A01X+013632Y+011268X0240Y0610R270 S1      
327GND              J8    -6   M      A01X+013632Y+010480X0240Y0610R270 S1      
327GND              J8    -8          A01X+013632Y+009693X0240Y0610R270 S1      
327GND              J8    -10         A01X+013632Y+008906X0240Y0610R270 S1      
317GND              VIA   -    MD0100PA00X+014087Y+011268X0200Y         S0      
317GND              VIA   -    MD0100PA00X+014087Y+010480X0200Y         S0      
317GND              VIA   -    MD0100PA00X+014170Y+009693X0200Y         S0      
317GND              VIA   -    MD0100PA00X+014087Y+008906X0200Y         S0      
327GND              J8    -2   M      A01X+013632Y+012055X0240Y0610R270 S1      
317GND              VIA   -    MD0100PA00X+014087Y+012055X0200Y         S0      
327GND              R89   -2   M      A01X+012658Y+013100X0198Y0197     S1      
317GND              VIA   -    MD0100PA00X+013170Y+013100X0200Y         S0      
327GND              C206  -2   M      A12X+011160Y+012110X0198Y0197R270 S2      
327GND              C208  -2          A12X+012350Y+012492X0198Y0197R090 S2      
327GND              C205  -2          A12X+011250Y+012592X0198Y0197R090 S2      
327GND              R88   -2          A01X+011442Y+012350X0198Y0197R180 S1      
317GND              VIA   -    MD0100PA00X+011200Y+012350X0200Y         S0      
317GND              VIA   -    MD0100PA00X+009090Y+022285X0200Y         S0      
327GND              U54   -4          A01X+021099Y+030464X0200Y0340R090 S1      
317GND              VIA   -    MD0100PA00X+020722Y+030118X0200Y         S0      
317GND              VIA   -    MD0100PA00X+009744Y+028359X0200Y         S0      
327GND              J4    -30         A01X+009744Y+028882X0110Y0630     S1      
317GND              VIA   -    MD0100PA00X+006457Y+030666X0200Y         S0      
317GND              VIA   -    MD0100PA00X+015029Y+031549X0200Y         S0      
327GND              J4    -G2         A01X+014606Y+031549X0490Y1100     S1      
317GND              VIA   -    MD0100PA00X+013546Y+031373X0200Y         S0      
327GND              J4    -69         A01X+013583Y+031854X0110Y0630     S1      
327GND              J4    -63         A01X+012992Y+031854X0110Y0630     S1      
317GND              VIA   -    MD0100PA00X+012402Y+031378X0200Y         S0      
327GND              J4    -57         A01X+012402Y+031854X0110Y0630     S1      
317GND              VIA   -    MD0100PA00X+011801Y+031120X0200Y         S0      
327GND              J4    -39         A01X+010630Y+031854X0110Y0630     S1      
317GND              VIA   -    MD0100PA00X+011801Y+031381X0200Y         S0      
327GND              J4    -51         A01X+011811Y+031854X0110Y0630     S1      
327GND              C500  -2   M      A01X+008650Y+026188X0198Y0197R090 S1      
327GND              J4    -33         A01X+010039Y+031854X0110Y0630     S1      
317GND              VIA   -    MD0100PA00X+009646Y+032319X0200Y         S0      
327GND              J4    -29         A01X+009646Y+031854X0110Y0630     S1      
317GND              VIA   -    MD0100PA00X+007300Y+032340X0200Y         S0      
327GND              PR543 -2          A01X+006340Y+011645X0198Y0197R180 S1      
327GND              C113  -2          A12X+027210Y+022450X0280Y0320R090 S2      
327GND              C132  -2          A12X+033050Y+022830X0280Y0320R180 S2      
327GND              C131  -2          A12X+032200Y+022960X0280Y0320R180 S2      
327GND              C125  -2          A12X+033300Y+012025X0280Y0320R270 S2      
327GND              C120  -2          A12X+032600Y+013190X0280Y0320     S2      
327GND              C329  -2          A12X+032000Y+039600X0400Y0500R270 S2      
327GND              C330  -2          A12X+032700Y+039600X0400Y0500R270 S2      
327GND              C177  -2          A01X+020880Y+008000X0460Y0620R180 S1      
327GND              C327  -2          A01X+020880Y+007100X0460Y0620R180 S1      
327GND              J4    -1          A01X+006890Y+031854X0110Y0630     S1      
327GND              R87   -2          A01X+012658Y+011400X0198Y0197     S1      
317GND              VIA   -    MD0100PA00X+012658Y+011142X0200Y         S0      
317GND              VIA   -    MD0100PA00X+012933Y+012250X0200Y         S0      
317GND              VIA   -    MD0100PA00X+012063Y+012350X0200Y         S0      
317GND              VIA   -    MD0100PA00X+008567Y+028398X0200Y         S0      
317GND              VIA   -    MD0100PA00X+007960Y+031200X0200Y         S0      
317GND              VIA   -    MD0100PA00X+010873Y+009915X0200Y         S0      
317GND              VIA   -    MD0100PA00X+011656Y+008865X0200Y         S0      
317GND              VIA   -    MD0100PA00X+011520Y+009820X0200Y         S0      
327GND              C214  -2          A01X+010792Y+010200X0198Y0197R180 S1      
327GND              C213  -2          A01X+010792Y+010750X0198Y0197R180 S1      
317GND              VIA   -    MD0100PA00X+010592Y+010995X0200Y         S0      
317GND              VIA   -    MD0100PA00X+012073Y+010500X0200Y         S0      
327GND              U38   -1          A01X+012188Y+006104X0280Y0400R090 S1      
317GND              VIA   -    MD0100PA00X+012250Y+005800X0200Y         S0      
327GND              C318  -2          A12X+007888Y+029670X0198Y0197R180 S2      
327GND              OSC2  -2          A12X+008603Y+030839X0340Y0460R090 S2      
317GND              VIA   -    MD0100PA00X+008560Y+033500X0200Y         S0      
327GND              VIA   -           A12X+009300Y+031500X0260Y         S2      
317GND              VIA   -    MD0100PA00X+027616Y+033000X0200Y         S0      
317GND              VIA   -    MD0100PA00X+026592Y+035424X0200Y         S0      
327GND              R744  -2          A12X+025338Y+036310X0198Y0197R180 S2      
327GND              U44   -3          A01X+007137Y+016388X0160Y0360     S1      
317GND              VIA   -    MD0100PA00X+007058Y+016718X0200Y    R090 S0      
317GND              VIA   -    MD0100PA00X+029694Y+032570X0200Y    R270 S0      
317GND              VIA   -    MD0100PA00X+018572Y+030732X0200Y    R180 S0      
327GND              C312  -2          A01X+018452Y+029450X0198Y0197R180 S1      
317GND              VIA   -    MD0100PA00X+018119Y+029407X0200Y    R180 S0      
327GND              U55   -3          A01X+021079Y+031616X0130Y0460R090 S1      
317GND              VIA   -    MD0100PA00X+021560Y+031680X0200Y    R180 S0      
327GND              C501  -2          A01X+006330Y+026088X0198Y0197R090 S1      
317GND              VIA   -    MD0100PA00X+006580Y+026088X0200Y    R090 S0      
327GND              C20   -2          A01X+007250Y+026158X0198Y0197R090 S1      
317GND              VIA   -    MD0100PA00X+008400Y+026138X0200Y    R090 S0      
317GND              VIA   -    M      A01X+008750Y+023730X0200Y    R090 S2      
017GND              VIA   -    M      A12X+008750Y+023730X0260Y    R090 S2      
017GND                    -    MD0100PA00X+008750Y+023730                       
327GND              U2    -4          A01X+010125Y+023998X0110Y0280     S1      
317GND              VIA   -    MD0100PA00X+010350Y+024062X0200Y    R090 S0      
327GND              U47   -2          A01X+011280Y+024206X0170Y0240     S1      
317GND              VIA   -    M      A01X+011359Y+024517X0200Y    R090 S2      
017GND              VIA   -    M      A12X+011359Y+024517X0260Y    R090 S2      
017GND                    -    MD0100PA00X+011359Y+024517                       
327GND              U3    -4          A01X+007935Y+024008X0110Y0280     S1      
317GND              VIA   -    MD0100PA00X+008160Y+024150X0200Y    R090 S0      
317GND              VIA   -    MD0100PA00X+006330Y+023760X0200Y    R090 S0      
327GND              C159  -2          A12X+007430Y+027768X0198Y0197R270 S2      
317GND              VIA   -    MD0100PA00X+007628Y+028047X0200Y         S0      
317GND              VIA   -    MD0100PA00X+006041Y+013020X0200Y    R180 S0      
327GND              C302  -2          A01X+006400Y+013012X0198Y0197R270 S1      
317GND              VIA   -    MD0100PA00X+006713Y+012810X0200Y         S0      
327GND              PU42  -4          A01X+007035Y+012820X0100Y0280R270 S1      
317GND              VIA   -    MD0100PA00X+006011Y+011399X0200Y    R270 S0      
327GND              VIA   -           A01X+006740Y+015560X0300Y    R180 S1      
327GND              PC262 -2          A01X+007241Y+014909X0440Y0540     S1      
317GND              VIA   -    M      A01X+008850Y+012800X0200Y         S2      
017GND              VIA   -    M      A12X+008850Y+012800X0260Y         S2      
017GND                    -    MD0100PA00X+008850Y+012800                       
317GND              VIA   -    MD0100PA00X+006843Y+015215X0200Y         S0      
317GND              VIA   -    MD0100PA00X+006928Y+013232X0200Y         S0      
317GND              VIA   -    MD0100PA00X+006920Y+013580X0200Y         S0      
317GND              VIA   -    MD0100PA00X+007197Y+013589X0200Y         S0      
317GND              VIA   -    MD0100PA00X+007204Y+013231X0200Y         S0      
317GND              VIA   -    MD0100PA00X+006843Y+014951X0200Y         S0      
317GND              VIA   -    MD0100PA00X+006838Y+014410X0200Y    R090 S0      
317GND              VIA   -    MD0100PA00X+006834Y+014137X0200Y         S0      
327GND              PC261 -2          A01X+007241Y+014160X0440Y0540     S1      
327GND              PC263 -2          A01X+007444Y+013587X0198Y0197R180 S1      
327GND              PU42  -2          A01X+007410Y+012938X0100Y0590     S1      
327GND              VIA   -           A12X+007045Y+013861X0260Y    R180 S2      
327GND              VIA   -           A12X+007650Y+013500X0260Y    R180 S2      
317GND              VIA   -    MD0100PA00X+014030Y+039510X0200Y         S0      
317GND              VIA   -    MD0100PA00X+035133Y+043753X0200Y    R090 S0      
317GND              VIA   -    MD0100PA00X+035133Y+041753X0200Y    R090 S0      
317GND              VIA   -    MD0100PA00X+035133Y+039753X0200Y    R090 S0      
317GND              VIA   -    MD0100PA00X+035133Y+037753X0200Y    R090 S0      
317GND              VIA   -    MD0100PA00X+035133Y+035753X0200Y    R090 S0      
317GND              VIA   -    MD0100PA00X+034929Y+033765X0200Y         S0      
317GND              VIA   -    MD0100PA00X+034260Y+031877X0200Y         S0      
317GND              VIA   -    MD0100PA00X+035133Y+030079X0200Y    R090 S0      
317GND              VIA   -    MD0100PA00X+035133Y+028079X0200Y    R090 S0      
317GND              VIA   -    MD0100PA00X+035133Y+026079X0200Y    R090 S0      
317GND              VIA   -    MD0100PA00X+035133Y+024079X0200Y    R090 S0      
317GND              VIA   -    MD0100PA00X+035133Y+022079X0200Y    R090 S0      
317GND              VIA   -    MD0100PA00X+035133Y+020079X0200Y    R090 S0      
317GND              VIA   -    MD0100PA00X+035133Y+018079X0200Y    R090 S0      
317GND              VIA   -    MD0100PA00X+035133Y+016079X0200Y    R090 S0      
317GND              VIA   -    MD0100PA00X+035133Y+014079X0200Y    R090 S0      
317GND              VIA   -    MD0100PA00X+035133Y+012079X0200Y    R090 S0      
317GND              VIA   -    MD0100PA00X+035133Y+010079X0200Y    R090 S0      
317GND              VIA   -    MD0100PA00X+035133Y+008079X0200Y    R090 S0      
317GND              VIA   -    MD0100PA00X+035133Y+006079X0200Y    R090 S0      
317GND              VIA   -    MD0100PA00X+035133Y+004079X0200Y    R090 S0      
317GND              VIA   -    MD0100PA00X+035133Y+002079X0200Y    R090 S0      
317GND              VIA   -    MD0100PA00X+033165Y+046654X0200Y    R090 S0      
317GND              VIA   -    MD0100PA00X+033411Y+044767X0200Y         S0      
317GND              VIA   -    MD0100PA00X+034222Y+000300X0200Y         S0      
317GND              VIA   -    MD0100PA00X+031497Y+045653X0200Y    R270 S0      
317GND              VIA   -    MD0100PA00X+032222Y+000300X0200Y         S0      
317GND              VIA   -    MD0100PA00X+030222Y+000300X0200Y         S0      
317GND              VIA   -    MD0100PA00X+028222Y+000300X0200Y         S0      
317GND              VIA   -    MD0100PA00X+026222Y+000300X0200Y         S0      
317GND              VIA   -    MD0100PA00X+024222Y+000300X0200Y         S0      
317GND              VIA   -    MD0100PA00X+022222Y+000300X0200Y         S0      
317GND              VIA   -    MD0100PA00X+020222Y+000300X0200Y         S0      
317GND              VIA   -    MD0100PA00X+018222Y+000300X0200Y         S0      
317GND              VIA   -    MD0100PA00X+016222Y+000300X0200Y         S0      
317GND              VIA   -    MD0100PA00X+014222Y+000300X0200Y         S0      
317GND              VIA   -    MD0100PA00X+012222Y+000300X0200Y         S0      
317GND              VIA   -    MD0100PA00X+010222Y+000300X0200Y         S0      
317GND              VIA   -    MD0100PA00X+008222Y+000300X0200Y         S0      
317GND              VIA   -    MD0100PA00X+006222Y+000300X0200Y         S0      
317GND              VIA   -    MD0100PA00X+004222Y+000300X0200Y         S0      
317GND              VIA   -    MD0100PA00X+002269Y+046652X0200Y    R090 S0      
317GND              VIA   -    MD0100PA00X+002022Y+044767X0200Y         S0      
317GND              VIA   -    MD0100PA00X+002222Y+000300X0200Y         S0      
317GND              VIA   -    MD0100PA00X+000300Y+044213X0200Y    R270 S0      
317GND              VIA   -    MD0100PA00X+000300Y+042213X0200Y    R270 S0      
317GND              VIA   -    MD0100PA00X+000300Y+040213X0200Y    R270 S0      
317GND              VIA   -    MD0100PA00X+000300Y+038213X0200Y    R270 S0      
317GND              VIA   -    MD0100PA00X+000300Y+036213X0200Y    R270 S0      
317GND              VIA   -    MD0100PA00X+000300Y+034213X0200Y    R270 S0      
317GND              VIA   -    MD0100PA00X+001383Y+032531X0200Y    R270 S0      
317GND              VIA   -    MD0100PA00X+000300Y+030849X0200Y    R270 S0      
317GND              VIA   -    MD0100PA00X+000300Y+028849X0200Y    R270 S0      
317GND              VIA   -    MD0100PA00X+000300Y+026849X0200Y    R270 S0      
317GND              VIA   -    MD0100PA00X+000300Y+024849X0200Y    R270 S0      
317GND              VIA   -    MD0100PA00X+000300Y+022849X0200Y    R270 S0      
317GND              VIA   -    MD0100PA00X+000300Y+020849X0200Y    R270 S0      
317GND              VIA   -    MD0100PA00X+000300Y+018849X0200Y    R270 S0      
317GND              VIA   -    MD0100PA00X+000300Y+016849X0200Y    R270 S0      
317GND              VIA   -    MD0100PA00X+000300Y+014849X0200Y    R270 S0      
317GND              VIA   -    MD0100PA00X+000300Y+012849X0200Y    R270 S0      
317GND              VIA   -    MD0100PA00X+000300Y+010849X0200Y    R270 S0      
317GND              VIA   -    MD0100PA00X+000300Y+008849X0200Y    R270 S0      
317GND              VIA   -    MD0100PA00X+000300Y+006849X0200Y    R270 S0      
317GND              VIA   -    MD0100PA00X+000300Y+004849X0200Y    R270 S0      
317GND              VIA   -    MD0100PA00X+000300Y+002849X0200Y    R270 S0      
317GND              VIA   -    MD0100PA00X+000300Y+000849X0200Y    R270 S0      
327GND              R685  -2   M      A12X+028189Y+028523X0198Y0197R270 S2      
327GND              R684  -2          A12X+028591Y+028523X0198Y0197R270 S2      
317GND              VIA   -    MD0100PA00X+008630Y+039760X0200Y         S0      
317GND              VIA   -    MD0100PA00X+012730Y+039260X0200Y         S0      
317GND              VIA   -    MD0100PA00X+027610Y+038150X0200Y         S0      
317GND              VIA   -    MD0100PA00X+032520Y+038390X0200Y         S0      
317GND              VIA   -    MD0100PA00X+033550Y+036320X0200Y         S0      
317GND              VIA   -    MD0100PA00X+033570Y+037640X0200Y         S0      
317GND              VIA   -    MD0100PA00X+029080Y+043830X0200Y         S0      
317GND              VIA   -    MD0100PA00X+026630Y+043590X0200Y         S0      
317GND              VIA   -    MD0100PA00X+024530Y+044580X0200Y         S0      
317GND              VIA   -    MD0100PA00X+027150Y+044680X0200Y         S0      
317GND              VIA   -    MD0100PA00X+027210Y+039630X0200Y         S0      
317GND              VIA   -    MD0100PA00X+027820Y+040870X0200Y         S0      
317GND              VIA   -    MD0100PA00X+028130Y+041930X0200Y         S0      
317GND              VIA   -    MD0100PA00X+024620Y+029970X0200Y         S0      
317GND              VIA   -    MD0100PA00X+017388Y+031243X0200Y         S0      
317GND              VIA   -    MD0100PA00X+010500Y+031190X0200Y         S0      
317GND              VIA   -    MD0100PA00X+008560Y+029810X0200Y         S0      
317GND              VIA   -    MD0100PA00X+020770Y+005910X0200Y         S0      
317GND              VIA   -    MD0100PA00X+034290Y+006610X0200Y         S0      
317GND              VIA   -    MD0100PA00X+024870Y+007590X0200Y         S0      
317GND              VIA   -    MD0100PA00X+008180Y+018850X0200Y         S0      
317GND              VIA   -    MD0100PA00X+005990Y+019990X0200Y         S0      
317GND              VIA   -    MD0100PA00X+003430Y+037500X0200Y         S0      
317GND              VIA   -    MD0100PA00X+003310Y+039210X0200Y         S0      
317GND              VIA   -    MD0100PA00X+026620Y+030050X0200Y         S0      
317GND              VIA   -    MD0100PA00X+033090Y+031470X0200Y         S0      
327GND              C278  -2          A01X+033090Y+031732X0198Y0197R270 S1      
327GND              C147  -2   M      A01X+006625Y+041818X0198Y0197R270 S1      
317GND              VIA   -    MD0100PA00X+025090Y+009090X0200Y         S0      
317GND              VIA   -    MD0100PA00X+027440Y+009002X0200Y         S0      
317GND              VIA   -    MD0100PA00X+006530Y+018776X0200Y         S0      
327GND              C296  -2   M      A01X+006040Y+018682X0198Y0197R270 S1      
327GND              C305  -2          A01X+005158Y+021120X0198Y0197R180 S1      
317GND              VIA   -    MD0100PA00X+005714Y+020934X0200Y         S0      
327GND              U18   -3          A01X+005714Y+020499X0130Y0460R180 S1      
317GND              VIA   -    MD0100PA00X+030750Y+025650X0200Y         S0      
317GND              VIA   -    MD0100PA00X+005200Y+023040X0200Y         S0      
327GND              U42   -3          A01X+005524Y+022608X0280Y0400     S1      
327GND              C297  -2          A01X+004352Y+024100X0198Y0197R180 S1      
327GND              C153  -2          A01X+032200Y+014808X0198Y0197R090 S1      
327GND              C150  -2          A12X+004450Y+021242X0198Y0197R090 S2      
327GND              C151  -2          A01X+004447Y+026382X0198Y0197R270 S1      
327GND              C155  -2          A01X+033688Y+029590X0198Y0197     S1      
327GND              C252  -2          A01X+027720Y+011592X0198Y0197R270 S1      
327GND              VIA   -           A12X+002750Y+020200X0260Y         S2      
327GND              VIA   -           A12X+003210Y+025280X0260Y         S2      
327GND              VIA   -           A12X+034360Y+013390X0260Y         S2      
327GND              VIA   -           A01X+021590Y+007380X0300Y         S1      
327GND              VIA   -           A12X+008480Y+034410X0260Y         S2      
327GND              VIA   -           A12X+028900Y+024490X0260Y         S2      
327GND              VIA   -           A12X+029220Y+015490X0260Y         S2      
327GND              VIA   -           A12X+022210Y+011210X0260Y         S2      
327GND              VIA   -           A12X+033540Y+013340X0260Y         S2      
317GND              VIA   -    MD0100PA00X+015690Y+038570X0200Y         S0      
317GND              VIA   -    MD0100PA00X+001800Y+023790X0200Y    R090 S0      
317GND              VIA   -    MD0100PA00X+001800Y+024090X0200Y    R090 S0      
317GND              VIA   -    MD0100PA00X+001800Y+024390X0200Y    R090 S0      
317GND              VIA   -    MD0100PA00X+001800Y+024690X0200Y    R090 S0      
317GND              VIA   -    MD0100PA00X+001800Y+024990X0200Y    R090 S0      
327GND              C223  -2          A01X+004108Y+035200X0198Y0197     S1      
317GND              VIA   -    MD0100PA00X+002354Y+032999X0200Y         S0      
327GND              R66   -1          A01X+001998Y+032860X0198Y0197R180 S1      
317GND              VIA   -    MD0100PA00X+003200Y+032630X0200Y         S0      
327GND              U6    -2          A01X+002826Y+032500X0170Y0240R270 S1      
317GND              VIA   -    MD0100PA00X+002581Y+031940X0200Y         S0      
327GND              C34   -2   M      A01X+002512Y+031690X0198Y0197R180 S1      
317GND              VIA   -    MD0100PA00X+003660Y+040860X0200Y         S0      
327GND              C215  -2          A01X+003768Y+041570X0198Y0197     S1      
327GND              C217  -2   M      A01X+003768Y+041190X0198Y0197     S1      
327GND              R823  -1          A01X+026800Y+042372X0198Y0197R090 S1      
327GND              U5    -AA3        A01X+024919Y+021800X0160Y    R180 S1      
317GND              VIA   -    MD0100PA00X+025075Y+021955X0180Y    R180 S0      
317GND              VIA   -    MD0100PA00X+017835Y+020066X0180Y         S0      
327GND              C88   -2   M      A12X+018481Y+019434X0198Y0197     S2      
327GND              C31   -2          A12X+018760Y+019041X0198Y0197R270 S2      
327GND              U5    -R25        A01X+017990Y+019910X0160Y    R180 S1      
327GND              U5    -M4         A01X+024604Y+018965X0160Y    R180 S1      
317GND              VIA   -    MD0100PA00X+024760Y+018810X0180Y    R180 S0      
327GND              U5    -H4         A01X+024604Y+017705X0160Y    R180 S1      
317GND              VIA   -    MD0100PA00X+024760Y+017550X0180Y    R180 S0      
327GND              U5    -K4         A01X+024604Y+018335X0160Y    R180 S1      
317GND              VIA   -    MD0100PA00X+024760Y+018180X0180Y    R180 S0      
327GND              C80   -2          A01X+027204Y+024538X0198Y0197R270 S1      
327GND              C157  -2          A12X+019483Y+008314X0198Y0197R270 S2      
317GND              VIA   -    MD0100PA00X+016672Y+007587X0200Y         S0      
327GND              U27   -8   M      A01X+016672Y+007322X0180Y0230R180 S1      
327GND              U27   -3          A01X+016672Y+007022X0180Y0270R180 S1      
317GND              VIA   -    MD0100PA00X+021860Y+006930X0200Y         S0      
317GND              VIA   -    MD0100PA00X+021580Y+006930X0200Y         S0      
317GND              VIA   -    MD0100PA00X+021960Y+007400X0200Y         S0      
327GND              C171  -2          A01X+022010Y+008086X0440Y0540R090 S1      
327GND              R377  -2          A01X+021750Y+009798X0198Y0197     S1      
317GND              VIA   -    MD0100PA00X+021180Y+009387X0200Y         S0      
317GND              VIA   -    MD0100PA00X+023080Y+005761X0200Y         S0      
327GND              Q6    -S          A12X+022751Y+005761X0320Y0360     S2      
317GND              VIA   -    MD0100PA00X+031398Y+003340X0200Y         S0      
317GND              VIA   -    MD0100PA00X+030060Y+001059X0200Y         S0      
317GND              VIA   -    MD0100PA00X+033738Y+007660X0200Y         S0      
327GND              C199  -2          A01X+033738Y+007400X0198Y0197     S1      
317GND              VIA   -    MD0100PA00X+031918Y+006020X0200Y         S0      
327GND              C201  -2          A01X+031918Y+006270X0198Y0197     S1      
317GND              VIA   -    MD0100PA00X+032260Y+007610X0200Y         S0      
327GND              U32   -3          A01X+032502Y+007306X0140Y0490R270 S1      
317GND              VIA   -    MD0100PA00X+026868Y+007440X0200Y         S0      
317GND              VIA   -    MD0100PA00X+019131Y+008451X0200Y         S0      
327GND              C178  -2          A01X+019131Y+008203X0198Y0197R090 S1      
317GND              VIA   -    MD0100PA00X+018727Y+008447X0200Y         S0      
327GND              C179  -2          A01X+018727Y+008203X0198Y0197R090 S1      
317GND              VIA   -    MD0100PA00X+019020Y+010050X0200Y         S0      
327GND              R296  -2          A12X+018898Y+009654X0198Y0197R270 S2      
327GND              U23   -3   M      A12X+017836Y+008745X0220Y0320R270 S2      
317GND              VIA   -    MD0100PA00X+018292Y+008430X0200Y         S0      
327GND              C269  -2   M      A12X+010496Y+035113X0164Y0164R270 S2      
317GND              VIA   -    MD0100PA00X+012429Y+040626X0200Y         S0      
327GND              C145  -2          A12X+011958Y+039700X0198Y0197R180 S2      
327GND              C194  -2   M      A12X+012090Y+040200X0280Y0320R270 S2      
317GND              VIA   -    MD0100PA00X+021310Y+006930X0200Y         S0      
317GND              VIA   -    MD0100PA00X+024539Y+009959X0200Y         S0      
327GND              C149  -2          A12X+024800Y+009708X0198Y0197R270 S2      
317GND              VIA   -    MD0100PA00X+022900Y+010100X0200Y         S0      
327GND              R219  -2   M      A12X+022750Y+009658X0198Y0197R270 S2      
327GND              C148  -2          A12X+023350Y+009708X0198Y0197R270 S2      
317GND              VIA   -    MD0100PA00X+020950Y+009233X0200Y         S0      
327GND              U10   -2          A01X+020597Y+009233X0240Y0380R270 S1      
317GND              VIA   -    MD0100PA00X+012958Y+005738X0200Y         S0      
327GND              C276  -2          A01X+012958Y+005430X0198Y0197     S1      
317GND              VIA   -    MD0100PA00X+007200Y+023592X0200Y         S0      
327GND              C158  -2          A12X+006950Y+023592X0198Y0197R090 S2      
317GND              VIA   -    MD0100PA00X+006580Y+025314X0200Y         S0      
327GND              U37   -4          A12X+006166Y+024770X0140Y0590     S2      
317GND              VIA   -    MD0100PA00X+004050Y+023690X0200Y         S0      
327GND              C262  -2          A01X+004050Y+023408X0198Y0197R090 S1      
317GND              VIA   -    MD0100PA00X+006260Y+045070X0200Y    R180 S0      
317GND              VIA   -    MD0100PA00X+005648Y+045034X0200Y    R180 S0      
327GND              C283  -2   M      A12X+007346Y+035113X0164Y0164R180 S2      
317GND              VIA   -    MD0100PA00X+018412Y+038740X0200Y         S0      
317GND              VIA   -    MD0100PA00X+017708Y+038740X0200Y         S0      
317GND              VIA   -    MD0100PA00X+025950Y+010110X0200Y         S0      
327GND              R441  -2          A01X+026208Y+011030X0198Y0197     S1      
317GND              VIA   -    MD0100PA00X+025230Y+010766X0200Y         S0      
327GND              R440  -2          A01X+025202Y+011030X0198Y0197R180 S1      
317GND              VIA   -    MD0100PA00X+015728Y+038910X0200Y         S0      
317GND              VIA   -    MD0100PA00X+016432Y+038910X0200Y         S0      
317GND              VIA   -    MD0100PA00X+006906Y+041970X0200Y         S0      
327GND              C188  -2          A12X+009236Y+038263X0164Y0164     S2      
327GND              C152  -2          A12X+010380Y+038458X0198Y0197R270 S2      
327GND              C189  -2          A12X+008390Y+035612X0164Y0164R090 S2      
327GND              C166  -2          A12X+008921Y+035743X0164Y0164R090 S2      
327GND              C167  -2          A12X+007346Y+035743X0164Y0164R180 S2      
327GND              C247  -2          A12X+007346Y+035428X0164Y0164R180 S2      
327GND              C261  -2          A12X+010181Y+035113X0164Y0164R180 S2      
327GND              C164  -2          A12X+007661Y+036688X0164Y0164R270 S2      
327GND              C285  -2          A12X+008921Y+037318X0164Y0164R090 S2      
327GND              C187  -2          A12X+008606Y+037318X0164Y0164R090 S2      
327GND              C245  -2          A12X+008291Y+037318X0164Y0164R090 S2      
317GND              VIA   -    MD0100PA00X+008550Y+032340X0200Y         S0      
327GND              R206  -1          A12X+026186Y+014740X0198Y0197R090 S2      
327GND              C22   -2          A12X+024450Y+020958X0198Y0197R270 S2      
327GND              C293  -2          A01X+013100Y+021026X0440Y0540R090 S1      
327GND              C142  -2          A01X+014426Y+020900X0440Y0540     S1      
327GND              C288  -2          A01X+033524Y+011850X0440Y0540R180 S1      
327GND              C289  -2          A01X+033650Y+013226X0440Y0540R090 S1      
327GND              C294  -2          A01X+015993Y+021257X0198Y0197     S1      
327GND              C287  -2          A01X+033764Y+012550X0198Y0197     S1      
327GND              C292  -2          A01X+013800Y+020792X0198Y0197R270 S1      
327GND              U30   -8          A12X+018118Y+032376X0140Y0590R270 S2      
327GND              U21   -8          A12X+018430Y+039145X0140Y0590R090 S2      
327GND              U5    -K22        A01X+018935Y+018335X0160Y    R180 S1      
317GND              VIA   -    MD0100PA00X+018779Y+018180X0180Y    R180 S0      
327GND              C246  -2          A01X+014790Y+034852X0198Y0197R270 S1      
317GND              VIA   -    MD0100PA00X+016920Y+034940X0200Y         S0      
327GND              R694  -2          A12X+017280Y+034682X0198Y0197R090 S2      
317GND              VIA   -    MD0100PA00X+023935Y+007946X0200Y         S0      
327GND              U36   -3          A12X+024205Y+007946X0240Y0240R270 S2      
317GND              VIA   -    M      A01X+022755Y+007428X0300Y         S1      
017GND              VIA   -    M      A12X+022755Y+007428X0200Y         S1      
017GND                    -    MD0100PA00X+022755Y+007428                       
327GND              C175  -2          A12X+001702Y+010550X0198Y0197     S2      
327GND              U24   -2          A12X+003514Y+010920X0170Y0240R090 S2      
317GND              VIA   -    MD0100PA00X+001290Y+010550X0200Y         S0      
317GND              VIA   -    MD0100PA00X+003830Y+010920X0200Y    R180 S0      
317GND              VIA   -    MD0100PA00X+004528Y+009849X0200Y         S0      
327GND              J6    -2          A01X+005610Y+009900X0400Y1090R090 S1      
317GND              VIA   -    MD0100PA00X+014070Y+037025X0200Y         S0      
327GND              U22   -11         A12X+015484Y+036515X0110Y0260R270 S2      
327GND              C236  -2   M      A12X+014805Y+036478X0198Y0197R270 S2      
317GND              VIA   -    MD0100PA00X+018035Y+036865X0200Y         S0      
327GND              C237  -2   M      A12X+018140Y+036588X0198Y0197R270 S2      
327GND              U22   -20         A12X+017138Y+036515X0110Y0260R270 S2      
327GND              C219  -2   M      A12X+017750Y+036588X0198Y0197R270 S2      
327GND              C190  -2          A12X+006261Y+034991X0198Y0197R225 S2      
327GND              C193  -2          A12X+006010Y+038941X0198Y0197R135 S2      
327GND              C286  -2          A12X+010339Y+039139X0198Y0197R045 S2      
327GND              GF1   -B17        A01X+021207Y+046559X0150Y0680R180 S1      
327GND              GF1   -B10        A01X+022860Y+046559X0150Y0680R180 S1      
317GND              VIA   -    MD0100PA00X+022820Y+045910X0200Y         S0      
317GND              VIA   -    MD0100PA00X+003820Y+036486X0200Y         S0      
327GND              R285  -2          A01X+004050Y+036708X0198Y0197R090 S1      
317GND              VIA   -    MD0100PA00X+016380Y+035680X0200Y         S0      
327GND              U22   -5          A12X+016409Y+035984X0110Y0260     S2      
327GND              C281  -2          A12X+007346Y+037633X0164Y0164R180 S2      
327GND              C165  -2          A12X+007348Y+037948X0164Y0164R090 S2      
327GND              C163  -2          A12X+006405Y+039445X0280Y0320R225 S2      
327GND              C220  -2          A12X+009758Y+036750X0164Y0164R180 S2      
317GND              VIA   -    MD0100PA00X+010608Y+045828X0200Y         S0      
327GND              GF1   -B49        A01X+010608Y+046638X0150Y0840R180 S1      
317GND              VIA   -    MD0100PA00X+009900Y+045828X0200Y         S0      
327GND              GF1   -B52        A01X+009900Y+046638X0150Y0840R180 S1      
317GND              VIA   -    MD0100PA00X+009191Y+045828X0200Y         S0      
327GND              GF1   -B55        A01X+009191Y+046638X0150Y0840R180 S1      
327GND              U5    -AC2        A01X+025234Y+022430X0160Y    R180 S1      
317GND              VIA   -    MD0100PA00X+026013Y+009377X0200Y         S0      
317GND              VIA   -    MD0100PA00X+026717Y+009377X0200Y         S0      
327GND              GF1   -A61        A12X+007774Y+046638X0150Y0840R180 S2      
327GND              GF1   -A58        A12X+008482Y+046638X0150Y0840R180 S2      
317GND              VIA   -    MD0100PA00X+021500Y+045860X0200Y         S0      
327GND              GF1   -A16        A12X+021443Y+046638X0150Y0840R180 S2      
317GND              VIA   -    MD0100PA00X+020930Y+045770X0200Y         S0      
327GND              GF1   -A19        A12X+020734Y+046638X0150Y0840R180 S2      
317GND              VIA   -    MD0100PA00X+020000Y+045580X0200Y         S0      
327GND              GF1   -A22        A12X+020026Y+046638X0150Y0840R180 S2      
327GND              GF1   -A70        A12X+005648Y+046638X0150Y0840R180 S2      
317GND              VIA   -    MD0100PA00X+005648Y+046010X0200Y         S0      
327GND              GF1   -A67        A12X+006356Y+046638X0150Y0840R180 S2      
317GND              VIA   -    MD0100PA00X+006356Y+046010X0200Y         S0      
317GND              VIA   -    MD0100PA00X+015887Y+009398X0200Y         S0      
317GND              VIA   -    MD0100PA00X+016443Y+009399X0200Y         S0      
317GND              VIA   -    MD0100PA00X+016830Y+009398X0200Y         S0      
317GND              VIA   -    MD0100PA00X+017385Y+009399X0200Y         S0      
317GND              VIA   -    MD0100PA00X+007677Y+042654X0200Y    R180 S0      
317GND              VIA   -    MD0100PA00X+007104Y+042654X0200Y    R180 S0      
317GND              VIA   -    MD0100PA00X+005154Y+042654X0200Y    R180 S0      
317GND              VIA   -    MD0100PA00X+005747Y+042654X0200Y    R180 S0      
317GND              VIA   -    MD0100PA00X+022220Y+045870X0200Y         S0      
327GND              GF1   -A13        A12X+022152Y+046638X0150Y0840R180 S2      
317GND              VIA   -    MD0100PA00X+015210Y+042570X0200Y         S0      
317GND              VIA   -    MD0100PA00X+009761Y+033553X0200Y         S0      
327GND              PC225 -2          A01X+004994Y+030887X0198Y0197R090 S1      
327GND              C241  -2          A01X+001800Y+023318X0198Y0197R090 S1      
327GND              R832  -2   M      A01X+016003Y+021664X0198Y0197R270 S1      
317GND              VIA   -    MD0100PA00X+013500Y+020690X0200Y         S0      
317GND              VIA   -    MD0100PA00X+014230Y+021630X0200Y         S0      
317GND              VIA   -    MD0100PA00X+014195Y+022427X0200Y         S0      
317GND              VIA   -    MD0100PA00X+014600Y+021635X0200Y         S0      
317GND              VIA   -    MD0100PA00X+014639Y+022404X0200Y         S0      
327GND              GF1   -B64        A01X+007065Y+046638X0150Y0840R180 S1      
327GND              GF1   -B61        A01X+007774Y+046638X0150Y0840R180 S1      
327GND              GF1   -B58        A01X+008482Y+046638X0150Y0840R180 S1      
327GND              GF1   -B33        A01X+016085Y+046559X0150Y0680R180 S1      
327GND              GF1   -B38        A01X+014904Y+046638X0150Y0840R180 S1      
327GND              GF1   -B26        A01X+019081Y+046559X0150Y0680R180 S1      
327GND              GF1   -OB10       A01X+027661Y+046638X0150Y0840R180 S1      
327GND              GF1   -OB7        A01X+028370Y+046638X0150Y0840R180 S1      
327GND              GF1   -OA13       A12X+026953Y+046638X0150Y0840R180 S2      
327GND              GF1   -A42        A12X+013959Y+046638X0150Y0840R180 S2      
327GND              GF1   -A33        A12X+016085Y+046559X0150Y0680R180 S2      
327GND              GF1   -A64        A12X+007065Y+046638X0150Y0840R180 S2      
327GND              PC217 -2          A01X+004500Y+012160X0440Y0540R090 S1      
327GND              PC215 -2          A01X+001950Y+012160X0440Y0540R090 S1      
327GND              PC213 -2          A01X+002800Y+012160X0440Y0540R090 S1      
327GND              PC214 -2          A01X+003650Y+012160X0440Y0540R090 S1      
327GND              PC206 -2          A01X+002050Y+021800X0400Y0500     S1      
327GND              PC207 -2          A01X+002050Y+021100X0400Y0500     S1      
327GND              C265  -2          A12X+002500Y+024050X0400Y0500R180 S2      
327GND              PC219 -2          A01X+002500Y+023350X0400Y0500     S1      
327GND              PC218 -2          A01X+002500Y+024050X0400Y0500     S1      
327GND              C243  -2          A12X+007974Y+037000X0164Y0164R180 S2      
327GND              C254  -2          A12X+007033Y+038261X0164Y0164R270 S2      
327GND              C216  -2          A12X+009739Y+037830X0164Y0164     S2      
327GND              C260  -2          A12X+009866Y+038578X0164Y0164R270 S2      
327GND              C195  -2          A12X+009758Y+037100X0164Y0164R180 S2      
327GND              C162  -2          A12X+008761Y+036853X0164Y0164     S2      
327GND              C266  -2          A12X+010787Y+039041X0198Y0197R045 S2      
327GND              C263  -2          A12X+009686Y+037453X0164Y0164R180 S2      
327GND              C176  -2          A12X+007985Y+036698X0164Y0164R270 S2      
327GND              C250  -2          A12X+007666Y+037958X0164Y0164R270 S2      
327GND              C242  -2          A12X+008386Y+036548X0164Y0164R270 S2      
327GND              U25   -R15        A01X+006401Y+038892X0160Y    R180 S1      
317GND              VIA   -    MD0100PA00X+006246Y+039048X0180Y         S0      
317GND              VIA   -    MD0100PA00X+006561Y+038733X0180Y         S0      
327GND              U25   -P14        A01X+006716Y+038578X0160Y    R180 S1      
327GND              U25   -B15        A01X+006401Y+034798X0160Y    R180 S1      
327GND              U25   -C14        A01X+006716Y+035113X0160Y    R180 S1      
317GND              VIA   -    MD0100PA00X+006561Y+034957X0180Y         S0      
317GND              VIA   -    MD0100PA00X+006876Y+038418X0180Y         S0      
327GND              U25   -N13        A01X+007031Y+038263X0160Y    R180 S1      
317GND              VIA   -    MD0100PA00X+007506Y+037788X0180Y         S0      
327GND              U25   -L11        A01X+007661Y+037633X0160Y    R180 S1      
317GND              VIA   -    MD0100PA00X+007506Y+035902X0180Y         S0      
327GND              U25   -F11        A01X+007661Y+036058X0160Y    R180 S1      
317GND              VIA   -    MD0100PA00X+007191Y+035587X0180Y         S0      
327GND              U25   -E12        A01X+007346Y+035743X0160Y    R180 S1      
317GND              VIA   -    MD0100PA00X+006876Y+035272X0180Y         S0      
327GND              U25   -D13        A01X+007031Y+035428X0160Y    R180 S1      
327GND              U25   -J8         A01X+008606Y+037003X0160Y    R180 S1      
327GND              U25   -J9         A01X+008291Y+037003X0160Y    R180 S1      
327GND              U25   -H8         A01X+008606Y+036688X0160Y    R180 S1      
327GND              U25   -H9         A01X+008291Y+036688X0160Y    R180 S1      
317GND              VIA   -    MD0100PA00X+008136Y+037158X0180Y         S0      
317GND              VIA   -    MD0100PA00X+008136Y+036532X0180Y         S0      
317GND              VIA   -    MD0100PA00X+008762Y+037158X0180Y         S0      
317GND              VIA   -    MD0100PA00X+008762Y+036532X0180Y         S0      
317GND              VIA   -    MD0100PA00X+006950Y+030870X0200Y         S0      
317GND              VIA   -    MD0100PA00X+008413Y+031179X0200Y         S0      
317GND              VIA   -    MD0100PA00X+008186Y+029790X0200Y         S0      
317GND              VIA   -    MD0100PA00X+008202Y+030335X0200Y         S0      
327GND              U25   -M5         A01X+009551Y+037948X0160Y    R180 S1      
327GND              U25   -L6         A01X+009236Y+037633X0160Y    R180 S1      
327GND              U25   -E5         A01X+009551Y+035743X0160Y    R180 S1      
327GND              U25   -F6         A01X+009236Y+036058X0160Y    R180 S1      
317GND              VIA   -    MD0100PA00X+009707Y+038103X0180Y         S0      
317GND              VIA   -    MD0100PA00X+009392Y+037788X0180Y         S0      
317GND              VIA   -    MD0100PA00X+009707Y+035587X0180Y         S0      
317GND              VIA   -    MD0100PA00X+009392Y+035902X0180Y         S0      
327GND              U25   -C3         A01X+010181Y+035113X0160Y    R180 S1      
327GND              U25   -B2         A01X+010496Y+034798X0160Y    R180 S1      
317GND              VIA   -    MD0100PA00X+010338Y+034956X0180Y         S0      
317GND              VIA   -    MD0100PA00X+010022Y+035272X0180Y         S0      
327GND              U25   -D4         A01X+009866Y+035428X0160Y    R180 S1      
327GND              U25   -R2         A01X+010496Y+038892X0160Y    R180 S1      
327GND              U25   -P3         A01X+010181Y+038578X0160Y    R180 S1      
327GND              U25   -N4         A01X+009866Y+038263X0160Y    R180 S1      
317GND              VIA   -    MD0100PA00X+010022Y+038418X0180Y         S0      
317GND              VIA   -    MD0100PA00X+010338Y+038735X0180Y         S0      
317GND              H9    -1   MD1240PA00X+033032Y+008933X2380Y         S3      
317GND              J7    -7   MD0410PA00X+002382Y+034915X0610Y         S3      
327GND              R770  -1          A12X+018722Y+034908X0198Y0197R090 S2      
327GND              R234  -1   M      A01X+019400Y+026083X0198Y0197     S1      
327GND              R233  -1          A01X+019154Y+025341X0198Y0197R270 S1      
327GND              C224  -2          A01X+025339Y+026840X0198Y0197     S1      
327GND              C143  -2          A01X+029015Y+035851X0198Y0197R180 S1      
327GND              C251  -2          A01X+027705Y+013163X0198Y0197R090 S1      
327GND              C240  -2          A12X+027716Y+012140X0198Y0197R180 S2      
327GND              R228  -1          A12X+015760Y+041722X0198Y0197R270 S2      
327GND              R820  -2   M      A01X+015564Y+017868X0198Y0197R180 S1      
327GND              R819  -2          A12X+016365Y+019072X0198Y0197     S2      
327GND              R818  -2          A12X+016365Y+018595X0198Y0197     S2      
327GND              R817  -2          A01X+015553Y+018264X0198Y0197R180 S1      
327GND              R118  -1          A01X+024220Y+013479X0198Y0197R090 S1      
327GND              R314  -2          A01X+009282Y+041700X0198Y0197     S1      
327GND              C173  -2   M      A01X+009282Y+041250X0198Y0197     S1      
327GND              PR245 -2          A01X+004556Y+021070X0198Y0197     S1      
327GND              PR276 -1          A01X+003957Y+024612X0198Y0197R180 S1      
327GND              R202  -1          A01X+024220Y+011992X0198Y0197R090 S1      
327GND              GF1   -OB4        A01X+029079Y+046638X0150Y0840R180 S1      
327GND              GF1   -OA4        A12X+029079Y+046638X0150Y0840R180 S2      
327GND              GF1   -OA3        A12X+029315Y+046638X0150Y0840R180 S2      
327GND              U5    -AF26       A01X+017675Y+023374X0160Y    R180 S1      
327GND              U5    -AF4        A01X+024604Y+023374X0160Y    R180 S1      
327GND              U5    -AF1        A01X+025549Y+023374X0160Y    R180 S1      
327GND              U5    -AE23       A01X+018620Y+023060X0160Y    R180 S1      
327GND              U5    -AE20       A01X+019565Y+023060X0160Y    R180 S1      
327GND              U5    -AE17       A01X+020510Y+023060X0160Y    R180 S1      
327GND              U5    -AE13       A01X+021770Y+023060X0160Y    R180 S1      
327GND              U5    -AE9        A01X+023030Y+023060X0160Y    R180 S1      
327GND              U5    -AE6        A01X+023974Y+023060X0160Y    R180 S1      
327GND              U5    -AE3        A01X+024919Y+023060X0160Y    R180 S1      
327GND              U5    -AD1 M      A01X+025549Y+022745X0160Y    R180 S1      
327GND              U5    -AC25       A01X+017990Y+022430X0160Y    R180 S1      
327GND              U5    -AC6        A01X+023974Y+022430X0160Y    R180 S1      
327GND              U5    -AA22       A01X+018935Y+021800X0160Y    R180 S1      
327GND              U5    -AA20       A01X+019565Y+021800X0160Y    R180 S1      
327GND              U5    -AA19       A01X+019880Y+021800X0160Y    R180 S1      
327GND              U5    -AA15       A01X+021140Y+021800X0160Y    R180 S1      
327GND              U5    -AA14       A01X+021455Y+021800X0160Y    R180 S1      
327GND              U5    -AA10       A01X+022715Y+021800X0160Y    R180 S1      
327GND              U5    -AA8        A01X+023344Y+021800X0160Y    R180 S1      
327GND              U5    -AA7 M      A01X+023659Y+021800X0160Y    R180 S1      
327GND              U5    -AA6        A01X+023974Y+021800X0160Y    R180 S1      
327GND              U5    -AA1        A01X+025549Y+021800X0160Y    R180 S1      
327GND              U5    -Y22 M      A01X+018935Y+021485X0160Y    R180 S1      
327GND              U5    -Y6  M      A01X+023974Y+021485X0160Y    R180 S1      
327GND              U5    -W25        A01X+017990Y+021170X0160Y    R180 S1      
327GND              U5    -W22        A01X+018935Y+021170X0160Y    R180 S1      
327GND              U5    -W12 M      A01X+022085Y+021170X0160Y    R180 S1      
327GND              U5    -W11        A01X+022400Y+021170X0160Y    R180 S1      
327GND              U5    -W10        A01X+022715Y+021170X0160Y    R180 S1      
327GND              U5    -W9  M      A01X+023030Y+021170X0160Y    R180 S1      
327GND              U5    -W8  M      A01X+023344Y+021170X0160Y    R180 S1      
327GND              U5    -W6  M      A01X+023974Y+021170X0160Y    R180 S1      
327GND              U5    -W5  M      A01X+024289Y+021170X0160Y    R180 S1      
327GND              U5    -V19        A01X+019880Y+020855X0160Y    R180 S1      
327GND              U5    -V18        A01X+020195Y+020855X0160Y    R180 S1      
327GND              U5    -V17        A01X+020510Y+020855X0160Y    R180 S1      
327GND              U5    -V16        A01X+020825Y+020855X0160Y    R180 S1      
327GND              U5    -V15        A01X+021140Y+020855X0160Y    R180 S1      
327GND              U5    -V14        A01X+021455Y+020855X0160Y    R180 S1      
327GND              U5    -V12        A01X+022085Y+020855X0160Y    R180 S1      
327GND              U5    -V11        A01X+022400Y+020855X0160Y    R180 S1      
327GND              U5    -V5         A01X+024289Y+020855X0160Y    R180 S1      
327GND              U5    -U23 M      A01X+018620Y+020540X0160Y    R180 S1      
327GND              U5    -U22        A01X+018935Y+020540X0160Y    R180 S1      
327GND              U5    -U19        A01X+019880Y+020540X0160Y    R180 S1      
327GND              U5    -U14        A01X+021455Y+020540X0160Y    R180 S1      
327GND              U5    -U12        A01X+022085Y+020540X0160Y    R180 S1      
327GND              U5    -U11        A01X+022400Y+020540X0160Y    R180 S1      
327GND              U5    -U10        A01X+022715Y+020540X0160Y    R180 S1      
327GND              U5    -U9  M      A01X+023030Y+020540X0160Y    R180 S1      
327GND              U5    -U8  M      A01X+023344Y+020540X0160Y    R180 S1      
327GND              U5    -U2         A01X+025234Y+020540X0160Y    R180 S1      
327GND              U5    -T19 M      A01X+019880Y+020225X0160Y    R180 S1      
327GND              U5    -T18        A01X+020195Y+020225X0160Y    R180 S1      
327GND              U5    -T17 M      A01X+020510Y+020225X0160Y    R180 S1      
327GND              U5    -T16        A01X+020825Y+020225X0160Y    R180 S1      
327GND              U5    -T15        A01X+021140Y+020225X0160Y    R180 S1      
327GND              U5    -T12        A01X+022085Y+020225X0160Y    R180 S1      
327GND              U5    -T11 M      A01X+022400Y+020225X0160Y    R180 S1      
327GND              U5    -T4         A01X+024604Y+020225X0160Y    R180 S1      
327GND              U5    -R19 M      A01X+019880Y+019910X0160Y    R180 S1      
327GND              U5    -R18        A01X+020195Y+019910X0160Y    R180 S1      
327GND              U5    -R17        A01X+020510Y+019910X0160Y    R180 S1      
327GND              U5    -R16        A01X+020825Y+019910X0160Y    R180 S1      
327GND              U5    -R15        A01X+021140Y+019910X0160Y    R180 S1      
327GND              U5    -R11 M      A01X+022400Y+019910X0160Y    R180 S1      
327GND              U5    -R8  M      A01X+023344Y+019910X0160Y    R180 S1      
327GND              U5    -R2         A01X+025234Y+019910X0160Y    R180 S1      
327GND              U5    -P19 M      A01X+019880Y+019595X0160Y    R180 S1      
327GND              U5    -P18        A01X+020195Y+019595X0160Y    R180 S1      
327GND              U5    -P17 M      A01X+020510Y+019595X0160Y    R180 S1      
327GND              U5    -P16        A01X+020825Y+019595X0160Y    R180 S1      
327GND              U5    -P15 M      A01X+021140Y+019595X0160Y    R180 S1      
327GND              U5    -P10        A01X+022715Y+019595X0160Y    R180 S1      
327GND              U5    -P9  M      A01X+023030Y+019595X0160Y    R180 S1      
327GND              U5    -P4         A01X+024604Y+019595X0160Y    R180 S1      
327GND              U5    -N19        A01X+019880Y+019280X0160Y    R180 S1      
327GND              U5    -N18        A01X+020195Y+019280X0160Y    R180 S1      
327GND              U5    -N17        A01X+020510Y+019280X0160Y    R180 S1      
327GND              U5    -N16        A01X+020825Y+019280X0160Y    R180 S1      
327GND              U5    -N15        A01X+021140Y+019280X0160Y    R180 S1      
327GND              U5    -N10        A01X+022715Y+019280X0160Y    R180 S1      
327GND              U5    -N9         A01X+023030Y+019280X0160Y    R180 S1      
327GND              U5    -N6         A01X+023974Y+019280X0160Y    R180 S1      
327GND              U5    -N2         A01X+025234Y+019280X0160Y    R180 S1      
327GND              U5    -M19 M      A01X+019880Y+018965X0160Y    R180 S1      
327GND              U5    -M18 M      A01X+020195Y+018965X0160Y    R180 S1      
327GND              U5    -M17        A01X+020510Y+018965X0160Y    R180 S1      
327GND              U5    -M16 M      A01X+020825Y+018965X0160Y    R180 S1      
327GND              U5    -M15        A01X+021140Y+018965X0160Y    R180 S1      
327GND              U5    -M12        A01X+022085Y+018965X0160Y    R180 S1      
327GND              U5    -M10        A01X+022715Y+018965X0160Y    R180 S1      
327GND              U5    -M9         A01X+023030Y+018965X0160Y    R180 S1      
327GND              U5    -L25        A01X+017990Y+018650X0160Y    R180 S1      
327GND              U5    -L19        A01X+019880Y+018650X0160Y    R180 S1      
327GND              U5    -L18        A01X+020195Y+018650X0160Y    R180 S1      
327GND              U5    -L17        A01X+020510Y+018650X0160Y    R180 S1      
327GND              U5    -L16 M      A01X+020825Y+018650X0160Y    R180 S1      
327GND              U5    -L15        A01X+021140Y+018650X0160Y    R180 S1      
327GND              U5    -L12        A01X+022085Y+018650X0160Y    R180 S1      
327GND              U5    -L11 M      A01X+022400Y+018650X0160Y    R180 S1      
327GND              U5    -L8         A01X+023344Y+018650X0160Y    R180 S1      
327GND              U5    -L2         A01X+025234Y+018650X0160Y    R180 S1      
327GND              U5    -K15        A01X+021140Y+018335X0160Y    R180 S1      
327GND              U5    -K14        A01X+021455Y+018335X0160Y    R180 S1      
327GND              U5    -K13        A01X+021770Y+018335X0160Y    R180 S1      
327GND              U5    -K9         A01X+023030Y+018335X0160Y    R180 S1      
327GND              U5    -K8  M      A01X+023344Y+018335X0160Y    R180 S1      
327GND              U5    -J19 M      A01X+019880Y+018020X0160Y    R180 S1      
327GND              U5    -J18        A01X+020195Y+018020X0160Y    R180 S1      
327GND              U5    -J17        A01X+020510Y+018020X0160Y    R180 S1      
327GND              U5    -J16        A01X+020825Y+018020X0160Y    R180 S1      
327GND              U5    -J15        A01X+021140Y+018020X0160Y    R180 S1      
327GND              U5    -J14        A01X+021455Y+018020X0160Y    R180 S1      
327GND              U5    -J13 M      A01X+021770Y+018020X0160Y    R180 S1      
327GND              U5    -J11        A01X+022400Y+018020X0160Y    R180 S1      
327GND              U5    -J2         A01X+025234Y+018020X0160Y    R180 S1      
327GND              U5    -H13        A01X+021770Y+017705X0160Y    R180 S1      
327GND              U5    -H11        A01X+022400Y+017705X0160Y    R180 S1      
327GND              U5    -H10        A01X+022715Y+017705X0160Y    R180 S1      
327GND              U5    -G25        A01X+017990Y+017390X0160Y    R180 S1      
327GND              U5    -G2         A01X+025234Y+017390X0160Y    R180 S1      
327GND              U5    -F21        A01X+019250Y+017075X0160Y    R180 S1      
327GND              U5    -F18 M      A01X+020195Y+017075X0160Y    R180 S1      
327GND              U5    -F17        A01X+020510Y+017075X0160Y    R180 S1      
327GND              U5    -F16        A01X+020825Y+017075X0160Y    R180 S1      
327GND              U5    -F14        A01X+021455Y+017075X0160Y    R180 S1      
327GND              U5    -F12        A01X+022085Y+017075X0160Y    R180 S1      
327GND              U5    -F10 M      A01X+022715Y+017075X0160Y    R180 S1      
327GND              U5    -E8         A01X+023344Y+016760X0160Y    R180 S1      
327GND              U5    -D25        A01X+017990Y+016445X0160Y    R180 S1      
327GND              U5    -B23        A01X+018620Y+015816X0160Y    R180 S1      
327GND              U5    -B19        A01X+019880Y+015816X0160Y    R180 S1      
327GND              U5    -B15        A01X+021140Y+015816X0160Y    R180 S1      
327GND              U5    -B11        A01X+022400Y+015816X0160Y    R180 S1      
327GND              U5    -B5  M      A01X+024289Y+015816X0160Y    R180 S1      
327GND              U5    -A26        A01X+017675Y+015500X0160Y    R180 S1      
327GND              U5    -A5         A01X+024289Y+015500X0160Y    R180 S1      
327GND              VIA   -           A12X+002600Y+021650X0260Y         S2      
317GND              VIA   -    MD0100PA00X+003192Y+018661X0200Y         S0      
327GND              PC210 -2          A01X+003300Y+018425X0198Y0197     S1      
327GND              PR526 -2   M      A01X+004239Y+019571X0198Y0197R270 S1      
317GND              VIA   -    MD0100PA00X+033970Y+029590X0200Y         S0      
317GND              VIA   -    MD0100PA00X+018588Y+041505X0200Y         S0      
327GND              C196  -2          A12X+018260Y+041488X0198Y0197R090 S2      
317GND              VIA   -    MD0100PA00X+023110Y+012560X0200Y         S0      
327GND              R210  -1          A12X+025237Y+013479X0198Y0197R270 S2      
317GND              VIA   -    MD0100PA00X+022150Y+012510X0200Y         S0      
317GND              VIA   -    MD0100PA00X+020397Y+012550X0200Y         S0      
317GND              VIA   -    MD0100PA00X+018736Y+013242X0200Y         S0      
317GND              VIA   -    MD0100PA00X+021120Y+014051X0200Y         S0      
317GND              VIA   -    MD0100PA00X+011906Y+019970X0200Y         S0      
327GND              VIA   -           A12X+026073Y+015450X0260Y         S2      
327GND              VIA   -           A12X+026000Y+021090X0260Y         S2      
327GND              VIA   -           A12X+032270Y+028860X0260Y         S2      
327GND              VIA   -           A12X+000820Y+030280X0260Y         S2      
327GND              VIA   -           A12X+002600Y+020950X0260Y         S2      
327GND              VIA   -           A12X+004500Y+012250X0260Y         S2      
327GND              VIA   -           A12X+001800Y+023450X0260Y         S2      
327GND              VIA   -           A12X+002800Y+022350X0260Y         S2      
327GND              VIA   -           A12X+002990Y+023140X0260Y         S2      
327GND              VIA   -           A01X+034360Y+011890X0300Y         S1      
327GND              VIA   -           A01X+001000Y+012350X0300Y         S1      
327GND              VIA   -           A01X+000780Y+019440X0300Y         S1      
327GND              VIA   -           A01X+001050Y+024540X0300Y         S1      
327GND              VIA   -           A01X+001080Y+023420X0300Y         S1      
327GND              VIA   -           A01X+000659Y+026452X0300Y         S1      
327GND              VIA   -           A01X+001550Y+025200X0300Y         S1      
327GND              VIA   -           A12X+025980Y+022260X0260Y         S2      
327GND              OSC1  -2   M      A01X+022883Y+010724X0340Y0460R090 S1      
327GND              PR525 -2   M      A01X+004729Y+018752X0198Y0197     S1      
327GND              C174  -2          A01X+012930Y+042592X0198Y0197R270 S1      
317GND              VIA   -    MD0100PA00X+012990Y+041558X0200Y         S0      
317GND              VIA   -    MD0100PA00X+014250Y+034580X0200Y    R180 S0      
327GND              C270  -2          A12X+031508Y+036900X0198Y0197R180 S2      
317GND              VIA   -    MD0100PA00X+031508Y+036650X0200Y         S0      
327GND              R229  -1          A12X+020400Y+011992X0198Y0197R270 S2      
317GND              VIA   -    MD0100PA00X+020360Y+011700X0200Y         S0      
327GND              R776  -2          A12X+018995Y+029117X0198Y0197R180 S2      
327GND              R778  -2   M      A12X+018998Y+028316X0198Y0197R180 S2      
327GND              PR522 -2          A01X+004228Y+020633X0198Y0197R090 S1      
317GND              VIA   -    MD0100PA00X+024140Y+032810X0200Y         S0      
327GND              C300  -2          A12X+022003Y+037213X0198Y0197R180 S2      
327GND              R743  -2          A12X+023698Y+037410X0198Y0197R180 S2      
327GND              R745  -2          A12X+025338Y+035120X0198Y0197R180 S2      
327GND              R64   -2          A01X+018140Y+042962X0198Y0197R270 S1      
317GND              VIA   -    MD0100PA00X+018275Y+042675X0200Y         S0      
327GND              Q8    -S          A12X+023006Y+039374X0320Y0360R270 S2      
317GND              VIA   -    MD0100PA00X+022823Y+039039X0200Y         S0      
317GND              VIA   -    MD0100PA00X+022316Y+036260X0200Y         S0      
327GND              J10   -11         A01X+030351Y+038132X0240Y0650R090 S1      
327GND              J10   -G2  M      A01X+031182Y+039006X0560Y2310R090 S1      
327GND              J5    -G2         A01X+024686Y+039006X0560Y2310R090 S1      
327GND              J10   -G1         A01X+031182Y+035684X0560Y2310R270 S1      
327GND              J5    -G1         A01X+024686Y+035684X0560Y2310R270 S1      
327GND              J5    -11         A01X+023855Y+038132X0240Y0650R090 S1      
317GND              VIA   -    MD0100PA00X+028772Y+036347X0200Y    R180 S0      
327GND              C144  -2   M      A01X+029015Y+036301X0198Y0197R180 S1      
327GND              C112  -2          A12X+020356Y+020351X0198Y0197R180 S2      
317GND              VIA   -    MD0100PA00X+019092Y+035099X0200Y         S0      
317GND              VIA   -    MD0100PA00X+023360Y+037150X0200Y         S0      
317GND              VIA   -    MD0100PA00X+025942Y+034593X0200Y         S0      
327GND              U40   -12         A12X+023842Y+033916X0140Y0590R090 S2      
317GND              VIA   -    MD0100PA00X+023347Y+034105X0200Y         S0      
317GND              VIA   -    MD0100PA00X+030115Y+010865X0200Y         S0      
327GND              D5    -C          A01X+030426Y+012621X0320Y0320R090 S1      
317GND              VIA   -    MD0100PA00X+030750Y+012564X0200Y         S0      
327GND              D6    -C          A01X+029782Y+012211X0320Y0320R270 S1      
327GND              D7    -C   M      A01X+029138Y+012621X0320Y0320R090 S1      
317GND              VIA   -    MD0100PA00X+029420Y+012880X0200Y         S0      
327GND              R40   -1          A12X+009281Y+041776X0198Y0197R270 S2      
317GND              VIA   -    MD0100PA00X+018237Y+032596X0200Y         S0      
327GND              C192  -2   M      A12X+027823Y+011739X0198Y0197     S2      
317GND              VIA   -    MD0100PA00X+027920Y+011410X0200Y         S0      
317GND              VIA   -    MD0100PA00X+005910Y+043350X0200Y         S0      
317GND              VIA   -    MD0100PA00X+006630Y+043300X0200Y         S0      
327GND              R63   -2          A01X+015042Y+042900X0198Y0197R180 S1      
317GND              VIA   -    MD0100PA00X+024341Y+038132X0200Y         S0      
327GND              R487  -2          A01X+016503Y+034362X0198Y0197R270 S1      
317GND              VIA   -    MD0100PA00X+016479Y+034110X0200Y         S0      
327GND              C146  -2          A12X+014568Y+040800X0198Y0197     S2      
327GND              R411  -2          A12X+032946Y+011271X0198Y0197R180 S2      
327GND              R493  -2          A12X+027038Y+038410X0198Y0197R180 S2      
317GND              VIA   -    MD0100PA00X+021808Y+044452X0200Y         S0      
317GND              VIA   -    MD0100PA00X+021186Y+044452X0200Y         S0      
317GND              VIA   -    MD0100PA00X+021672Y+040765X0200Y         S0      
317GND              VIA   -    MD0100PA00X+022222Y+040765X0200Y         S0      
317GND              VIA   -    MD0100PA00X+007530Y+030515X0200Y         S0      
317GND              VIA   -    MD0100PA00X+008220Y+030870X0200Y         S0      
317GND              VIA   -    MD0100PA00X+027610Y+037590X0200Y         S0      
327GND              Q3    -E          A01X+020775Y+036110X0400Y0500     S1      
317GND              VIA   -    MD0100PA00X+020775Y+036650X0200Y         S0      
327GND              Q1    -E          A01X+020760Y+037815X0400Y0500     S1      
317GND              VIA   -    M      A01X+020836Y+038489X0200Y         S2      
017GND              VIA   -    M      A12X+020836Y+038489X0260Y         S2      
017GND                    -    MD0100PA00X+020836Y+038489                       
317GND              VIA   -    MD0100PA00X+023380Y+039012X0200Y         S0      
317GND              VIA   -    MD0100PA00X+023330Y+035689X0200Y         S0      
317GND              VIA   -    MD0100PA00X+017255Y+039869X0200Y    R090 S0      
327GND              R866  -2          A12X+019762Y+041025X0198Y0197R180 S2      
317GND              VIA   -    M      A01X+020027Y+041096X0300Y    R090 S1      
017GND              VIA   -    M      A12X+020027Y+041096X0200Y    R090 S1      
017GND                    -    MD0100PA00X+020027Y+041096                       
317GND              VIA   -    MD0100PA00X+016967Y+039942X0200Y    R180 S0      
317GND              VIA   -    MD0100PA00X+014660Y+041060X0200Y    R090 S0      
327GND              R467  -2          A12X+014568Y+039750X0198Y0197     S2      
317GND              VIA   -    MD0100PA00X+014330Y+039640X0200Y    R090 S0      
317GND              VIA   -    MD0100PA00X+015400Y+041475X0200Y         S0      
317GND              VIA   -    MD0100PA00X+009528Y+041250X0200Y         S0      
327GND              R313  -2          A01X+009868Y+042852X0198Y0197R090 S1      
317GND              VIA   -    MD0100PA00X+010340Y+042000X0200Y         S0      
327GND              U12   -S          A01X+008308Y+042104X0400Y0560R090 S1      
317GND              VIA   -    MD0100PA00X+007880Y+042380X0200Y         S0      
317GND              VIA   -    MD0100PA00X+026293Y+032530X0200Y         S0      
317GND              VIA   -    MD0100PA00X+015313Y+017857X0200Y         S0      
317GND              VIA   -    MD0100PA00X+018960Y+045980X0200Y         S0      
317GND              VIA   -    MD0100PA00X+000830Y+031470X0200Y         S0      
317GND              VIA   -    MD0100PA00X+013850Y+045725X0200Y         S0      
317GND              VIA   -    MD0100PA00X+008482Y+046010X0200Y         S0      
317GND              VIA   -    MD0100PA00X+007750Y+046010X0200Y         S0      
317GND              VIA   -    MD0100PA00X+007065Y+046010X0200Y         S0      
327GND              C90   -2          A12X+029736Y+023314X0198Y0197R090 S2      
317GND              VIA   -    MD0100PA00X+028325Y+014205X0200Y    R180 S0      
317GND              VIA   -    MD0100PA00X+028074Y+014207X0200Y    R180 S0      
317GND              VIA   -    MD0100PA00X+026303Y+015085X0200Y    R180 S0      
317GND              VIA   -    MD0100PA00X+026329Y+015337X0200Y    R180 S0      
327GND              PC212 -2          A01X+005206Y+012362X0198Y0197R270 S1      
317GND              VIA   -    MD0100PA00X+002469Y+024927X0200Y    R090 S0      
317GND              VIA   -    MD0100PA00X+002104Y+024994X0200Y    R090 S0      
317GND              VIA   -    MD0100PA00X+002114Y+024684X0200Y    R090 S0      
317GND              VIA   -    MD0100PA00X+002469Y+025197X0200Y    R090 S0      
317GND              VIA   -    MD0100PA00X+002469Y+024647X0200Y    R090 S0      
317GND              VIA   -    MD0100PA00X+002114Y+024374X0200Y    R090 S0      
317GND              VIA   -    MD0100PA00X+002114Y+024067X0200Y    R090 S0      
317GND              VIA   -    MD0100PA00X+002120Y+023277X0200Y    R090 S0      
317GND              VIA   -    MD0100PA00X+002114Y+023659X0200Y    R090 S0      
327GND              PU1   -1          A01X+002677Y+025133X0098Y0276     S1      
327GND              PU1   -14         A01X+002500Y+025408X0098Y0276R270 S1      
327GND              PC221 -2          A01X+002020Y+025256X0198Y0197R270 S1      
327GND              PC223 -2          A01X+002709Y+024611X0198Y0197R180 S1      
327GND              PC273 -2          A01X+004448Y+025964X0198Y0197     S1      
327GND              PR530 -1          A01X+004438Y+025568X0198Y0197R270 S1      
327GND              PU1   -7          A01X+003641Y+025605X0098Y0276R090 S1      
317GND              VIA   -    MD0100PA00X+004157Y+025594X0200Y         S0      
317GND              VIA   -    M      A01X+003957Y+024313X0200Y         S2      
017GND              VIA   -    M      A12X+003957Y+024313X0260Y         S2      
017GND                    -    MD0100PA00X+003957Y+024313                       
327GND              PR532 -1          A01X+001815Y+025978X0198Y0197     S1      
317GND              VIA   -    MD0100PA00X+001569Y+025906X0200Y    R090 S0      
327GND              C97   -2          A12X+022963Y+020704X0198Y0197     S2      
327GND              PC253 -2          A01X+032008Y+029482X0198Y0197R180 S1      
317GND              VIA   -    MD0100PA00X+033631Y+028635X0200Y         S0      
327GND              PC250 -2   M      A01X+033383Y+028635X0198Y0197R090 S1      
327GND              PC251 -2          A01X+031813Y+030768X0440Y0540     S1      
327GND              PC252 -2          A01X+031813Y+030023X0440Y0540     S1      
327GND              C135  -1          A12X+020299Y+024509X0198Y0197R090 S2      
327GND              C133  -1   M      A12X+019899Y+024509X0198Y0197R090 S2      
327GND              PC208 -2          A01X+001661Y+019051X0198Y0197R090 S1      
327GND              C126  -2          A12X+027773Y+014298X0280Y0320R180 S2      
327GND              C77   -2          A12X+019237Y+021721X0198Y0197R180 S2      
327GND              C115  -2          A12X+019622Y+021721X0198Y0197     S2      
327GND              C51   -2          A12X+019658Y+021320X0198Y0197R180 S2      
317GND              VIA   -    MD0100PA00X+008528Y+044555X0200Y         S0      
317GND              VIA   -    MD0100PA00X+008226Y+044558X0200Y         S0      
327GND              U1    -A2         A01X+029076Y+021223X0145Y         S1      
327GND              U1    -A8         A01X+030966Y+021223X0145Y         S1      
327GND              U1    -B2         A01X+029076Y+020908X0145Y         S1      
327GND              U1    -C9         A01X+031280Y+020594X0145Y         S1      
327GND              U1    -D2         A01X+029076Y+020278X0145Y         S1      
327GND              U1    -D8         A01X+030966Y+020278X0145Y         S1      
327GND              U1    -E1         A01X+028761Y+019964X0145Y         S1      
327GND              U1    -E3         A01X+029391Y+019964X0145Y         S1      
327GND              U1    -E8         A01X+030966Y+019964X0145Y         S1      
327GND              U1    -F1         A01X+028761Y+019649X0145Y         S1      
327GND              U1    -G8         A01X+030966Y+019334X0145Y         S1      
327GND              U1    -H1         A01X+028761Y+019019X0145Y         S1      
327GND              U1    -H9         A01X+031280Y+019019X0145Y         S1      
327GND              U1    -K1         A01X+028761Y+018389X0145Y         S1      
327GND              U1    -K9         A01X+031280Y+018389X0145Y         S1      
327GND              U1    -N1         A01X+028761Y+017444X0145Y         S1      
327GND              U1    -T1         A01X+028761Y+016499X0145Y         S1      
327GND              U1    -T7         A01X+030650Y+016499X0145Y         S1      
327GND              Q10   -S          A12X+031223Y+038630X0320Y0360R180 S2      
327GND              C70   -2          A12X+019457Y+019767X0198Y0197R270 S2      
327GND              C122  -2          A12X+020348Y+018904X0198Y0197R270 S2      
327GND              C76   -2          A12X+023883Y+018278X0198Y0197     S2      
327GND              C72   -2          A12X+019372Y+018926X0198Y0197R270 S2      
327GND              C98   -2          A12X+019946Y+018908X0198Y0197R270 S2      
327GND              C32   -2          A12X+020043Y+018197X0198Y0197R180 S2      
327GND              C101  -2          A12X+020141Y+017230X0198Y0197     S2      
327GND              C39   -2          A12X+020337Y+017797X0198Y0197R180 S2      
327GND              C84   -2          A12X+021779Y+019392X0198Y0197R180 S2      
327GND              C89   -2          A12X+021626Y+017982X0198Y0197R090 S2      
327GND              C129  -2          A01X+028298Y+013840X0198Y0197R180 S1      
327GND              C116  -2          A12X+021686Y+018999X0198Y0197R270 S2      
327GND              C60   -2          A12X+020918Y+017827X0198Y0197     S2      
327GND              C91   -2          A12X+020749Y+018904X0198Y0197R270 S2      
327GND              C104  -2          A12X+022852Y+018894X0198Y0197     S2      
327GND              C85   -2          A12X+022020Y+018189X0198Y0197     S2      
327GND              C99   -2          A12X+022219Y+018585X0198Y0197R090 S2      
327GND              C119  -2          A01X+027270Y+014040X0198Y0197R090 S1      
327GND              C41   -2          A12X+023142Y+018494X0198Y0197R180 S2      
327GND              C45   -2          A12X+023403Y+018087X0198Y0197R180 S2      
327GND              C64   -2   M      A12X+022706Y+017643X0198Y0197R270 S2      
327GND              C95   -2          A12X+021991Y+017635X0198Y0197     S2      
327GND              C108  -2          A12X+028661Y+021653X0198Y0197R090 S2      
327GND              C105  -2          A12X+023795Y+017886X0198Y0197R270 S2      
327GND              C73   -2          A12X+025012Y+019477X0198Y0197R180 S2      
327GND              C127  -2          A12X+028244Y+014831X0198Y0197R270 S2      
327GND              C67   -2          A12X+026390Y+015936X0198Y0197R090 S2      
327GND              C37   -2   M      A01X+021078Y+010877X0198Y0197R270 S1      
327GND              C10   -2          A12X+028056Y+017564X0198Y0197     S2      
327GND              C16   -2          A12X+028786Y+018791X0198Y0197     S2      
327GND              C13   -2          A12X+033425Y+018696X0198Y0197     S2      
327GND              C56   -2          A01X+027568Y+014523X0198Y0197R270 S1      
327GND              C58   -2          A12X+029049Y+014831X0198Y0197R270 S2      
327GND              C62   -2          A12X+028645Y+014831X0198Y0197R270 S2      
327GND              C66   -2   M      A12X+020667Y+021246X0198Y0197R270 S2      
327GND              C93   -2          A12X+022871Y+019664X0198Y0197R270 S2      
327GND              C109  -2          A12X+022164Y+019388X0198Y0197     S2      
327GND              C114  -2          A01X+027803Y+014039X0198Y0197R090 S1      
327GND              C63   -2          A12X+026890Y+015936X0198Y0197R090 S2      
327GND              C71   -2          A12X+023802Y+018679X0198Y0197R090 S2      
327GND              C54   -2          A12X+023111Y+017640X0198Y0197R270 S2      
327GND              C52   -2          A01X+027167Y+014523X0198Y0197R270 S1      
327GND              C49   -2          A12X+023988Y+019415X0198Y0197     S2      
327GND              C46   -2          A12X+026587Y+014732X0198Y0197R270 S2      
327GND              C100  -2          A12X+021991Y+017234X0198Y0197     S2      
327GND              C12   -2          A12X+030151Y+019304X0198Y0197R270 S2      
327GND              C14   -2          A12X+033740Y+016691X0198Y0197R180 S2      
327GND              C8    -2          A12X+032098Y+016938X0198Y0197R180 S2      
327GND              C18   -2          A01X+031794Y+014945X0198Y0197R090 S1      
327GND              C35   -2          A12X+015652Y+015328X0198Y0197R270 S2      
327GND              C33   -2          A12X+019334Y+017841X0198Y0197R090 S2      
327GND              C57   -2   M      A12X+019746Y+017206X0198Y0197R270 S2      
327GND              C65   -2          A12X+021550Y+016913X0198Y0197R090 S2      
327GND              PC271 -2   M      A01X+004546Y+019154X0198Y0197     S1      
327GND              PC205 -2   M      A01X+004631Y+020633X0198Y0197R090 S1      
327GND              C110  -2          A12X+021157Y+017229X0198Y0197R180 S2      
327GND              C168  -2          A12X+033264Y+020629X0198Y0197R180 S2      
327GND              C4    -2          A12X+030143Y+020585X0198Y0197R180 S2      
327GND              C3    -2          A12X+027809Y+021353X0198Y0197     S2      
327GND              C2    -2          A12X+031698Y+019237X0198Y0197R090 S2      
327GND              C5    -2   M      A12X+028219Y+020170X0198Y0197R090 S2      
327GND              C170  -2          A12X+033264Y+020229X0198Y0197R180 S2      
327GND              PC255 -2          A01X+033722Y+023048X0198Y0197R270 S1      
327GND              C273  -2          A12X+030268Y+039738X0198Y0197     S2      
327GND              C17   -2          A01X+029468Y+014291X0198Y0197R180 S1      
327GND              C15   -2          A12X+032842Y+015014X0198Y0197R180 S2      
327GND              C6    -2   M      A12X+027809Y+020951X0198Y0197     S2      
327GND              C79   -2          A12X+023271Y+019808X0198Y0197R090 S2      
327GND              C78   -2          A12X+028358Y+024110X0198Y0197R270 S2      
327GND              C21   -2          A12X+023906Y+021234X0198Y0197R270 S2      
327GND              C130  -2          A12X+023506Y+021581X0198Y0197R270 S2      
327GND              C128  -2          A12X+028338Y+024558X0198Y0197R090 S2      
327GND              C61   -2   M      A01X+027958Y+024558X0198Y0197R270 S1      
327GND              C267  -2          A12X+029329Y+039736X0198Y0197R180 S2      
327GND              C23   -2          A12X+023726Y+020526X0198Y0197     S2      
327GND              C96   -2          A12X+021033Y+021863X0198Y0197R270 S2      
327GND              C47   -2          A12X+027147Y+021635X0198Y0197R090 S2      
327GND              C50   -2   M      A12X+022264Y+020456X0198Y0197     S2      
327GND              C69   -2          A12X+023102Y+021581X0198Y0197R270 S2      
327GND              C81   -2          A12X+022277Y+021014X0198Y0197     S2      
327GND              C284  -2          A12X+019448Y+023861X0198Y0197R270 S2      
327GND              C282  -2          A12X+022544Y+027978X0198Y0197R180 S2      
327GND              C314  -2          A12X+023028Y+027985X0198Y0197     S2      
327GND              C309  -2          A12X+022115Y+029072X0198Y0197R090 S2      
327GND              C295  -2          A12X+022640Y+028994X0198Y0197     S2      
327GND              C74   -2   M      A12X+023834Y+019808X0198Y0197R090 S2      
327GND              C107  -2          A12X+021149Y+018706X0198Y0197R090 S2      
327GND              C87   -2          A12X+024450Y+021658X0198Y0197R270 S2      
327GND              C94   -2          A12X+020640Y+021627X0198Y0197R180 S2      
327GND              C299  -2          A12X+020581Y+027479X0198Y0197R270 S2      
327GND              C303  -2          A12X+020981Y+027479X0198Y0197R270 S2      
327GND              C279  -2          A12X+020624Y+023517X0198Y0197R090 S2      
327GND              C277  -2          A12X+020666Y+027874X0198Y0197     S2      
327GND              C102  -2          A12X+022561Y+021614X0198Y0197R180 S2      
327GND              C106  -2          A12X+021545Y+021603X0198Y0197     S2      
327GND              C86   -2   M      A12X+023288Y+019415X0198Y0197     S2      
327GND              C275  -2   M      A12X+018998Y+028722X0198Y0197R180 S2      
327GND              C140  -2          A12X+019648Y+020620X0198Y0197R180 S2      
327GND              C82   -2          A12X+020726Y+020353X0198Y0197     S2      
327GND              C311  -2          A12X+019410Y+026110X0198Y0197R090 S2      
327GND              C307  -2          A12X+020181Y+028277X0198Y0197R180 S2      
327GND              C83   -2          A12X+018154Y+021321X0198Y0197R270 S2      
327GND              C136  -1   M      A12X+018489Y+024559X0198Y0197R090 S2      
327GND              C134  -1          A12X+018130Y+024558X0198Y0197R090 S2      
327GND              C43   -2          A12X+015916Y+022376X0198Y0197R270 S2      
327GND              C75   -2          A12X+016652Y+022840X0198Y0197     S2      
327GND              C117  -2          A12X+020711Y+019445X0198Y0197     S2      
327GND              C111  -2          A12X+021596Y+020100X0198Y0197R270 S2      
327GND              C92   -2          A12X+022302Y+020056X0198Y0197     S2      
327GND              C103  -2          A12X+020226Y+019442X0198Y0197R180 S2      
327GND              C7    -2          A12X+028224Y+019783X0198Y0197R270 S2      
327GND              C9    -2          A12X+031711Y+020843X0198Y0197R090 S2      
327GND              C139  -2          A12X+019648Y+020970X0198Y0197R180 S2      
327GND              C48   -2          A12X+016886Y+021203X0198Y0197     S2      
327GND              C222  -2          A12X+031346Y+018837X0198Y0197     S2      
327GND              C221  -2          A12X+031173Y+021614X0198Y0197     S2      
327GND              R15   -2          A12X+026844Y+011737X0198Y0197     S2      
327GND              R412  -2          A12X+032946Y+010869X0198Y0197R180 S2      
327GND              R413  -2          A12X+032946Y+010468X0198Y0197R180 S2      
327GND              R349  -1          A12X+027887Y+018703X0198Y0197R090 S2      
327GND              R4    -2   M      A12X+028547Y+016580X0198Y0197     S2      
327GND              R337  -1          A12X+030194Y+013835X0198Y0197R270 S2      
327GND              R332  -1          A12X+030594Y+013835X0198Y0197R270 S2      
327GND              R330  -1   M      A01X+030594Y+013830X0198Y0197R090 S1      
327GND              R328  -1   M      A01X+030194Y+013820X0198Y0197R090 S1      
327GND              R2    -2          A12X+032098Y+017738X0198Y0197R180 S2      
327GND              R5    -2          A12X+032098Y+017338X0198Y0197R180 S2      
327GND              R345  -1          A12X+032098Y+015738X0198Y0197     S2      
327GND              R326  -1          A12X+031794Y+013835X0198Y0197R270 S2      
327GND              R334  -1          A12X+030994Y+013835X0198Y0197R270 S2      
327GND              R346  -1          A12X+031394Y+013835X0198Y0197R270 S2      
327GND              R336  -1   M      A01X+030994Y+013830X0198Y0197R090 S1      
327GND              R348  -1          A01X+031394Y+013830X0198Y0197R090 S1      
327GND              R342  -1          A12X+032900Y+019141X0198Y0197     S2      
327GND              R341  -1          A01X+033740Y+018991X0198Y0197R180 S1      
327GND              R350  -1          A12X+032900Y+018741X0198Y0197     S2      
327GND              R338  -1          A12X+032900Y+017941X0198Y0197     S2      
327GND              R347  -1          A01X+033740Y+018393X0198Y0197R180 S1      
327GND              R333  -1          A01X+033740Y+017491X0198Y0197R180 S1      
327GND              R331  -1          A01X+033740Y+017991X0198Y0197R180 S1      
327GND              R329  -1          A12X+032098Y+016538X0198Y0197     S2      
327GND              R344  -1          A12X+032098Y+016138X0198Y0197     S2      
327GND              R340  -1          A12X+032900Y+015941X0198Y0197     S2      
327GND              R327  -1          A01X+033740Y+015991X0198Y0197R180 S1      
327GND              R335  -1          A01X+033740Y+016991X0198Y0197R180 S1      
327GND              R339  -1          A01X+033740Y+016491X0198Y0197R180 S1      
327GND              R343  -1          A01X+033740Y+015491X0198Y0197R180 S1      
327GND              R325  -2          A12X+033264Y+021029X0198Y0197R180 S2      
327GND              PR496 -2          A01X+030531Y+027326X0198Y0197R180 S1      
327GND              R127  -1          A12X+025615Y+020310X0198Y0197     S2      
327GND              R798  -2          A12X+023028Y+027584X0198Y0197     S2      
327GND              R788  -2          A12X+022632Y+028591X0198Y0197     S2      
327GND              R792  -2          A12X+021383Y+026752X0198Y0197R090 S2      
327GND              R790  -2          A12X+020179Y+027479X0198Y0197R270 S2      
327GND              R794  -2          A12X+020181Y+027874X0198Y0197R180 S2      
327GND              R22   -2          A12X+017360Y+024568X0198Y0197R270 S2      
327GND              R23   -2          A01X+017741Y+024944X0198Y0197R270 S1      
327GND              R235  -1          A12X+016970Y+024638X0198Y0197R090 S2      
327GND              R25   -2          A01X+018341Y+025014X0198Y0197R270 S1      
327GND              R3    -2          A12X+030876Y+020079X0198Y0197R180 S2      
327GND              R6    -2          A12X+031712Y+020252X0198Y0197R270 S2      
327GND              U19   -4          A12X+030994Y+010309X0170Y0700R090 S2      
327GND              C118  -2          A12X+029453Y+022706X0280Y0320     S2      
327GND              C123  -2          A12X+030016Y+022296X0280Y0320     S2      
327GND              C55   -2          A12X+029729Y+013787X0280Y0320R270 S2      
327GND              C124  -2   M      A01X+029718Y+013830X0280Y0320R270 S1      
327GND              C121  -2          A12X+021607Y+020552X0280Y0320R180 S2      
327GND              C1    -2          A12X+032941Y+019649X0280Y0320R270 S2      
327GND              PC256 -2          A01X+033052Y+022873X0440Y0540R090 S1      
327GND              PC257 -2          A01X+032212Y+022876X0440Y0540R090 S1      
327GND              PC258 -2          A01X+031372Y+022878X0440Y0540R090 S1      
327GND              PC259 -2          A01X+030532Y+022880X0440Y0540R090 S1      
327GND              PC227 -2          A01X+002644Y+031158X0440Y0540R270 S1      
327GND              PC228 -2          A01X+003484Y+031155X0440Y0540R270 S1      
327GND              PC229 -2          A01X+004324Y+031176X0440Y0540R270 S1      
327GND              PC226 -2          A01X+001804Y+031160X0440Y0540R270 S1      
317GND              H5    -1   MD1240PA00X+002402Y+008933X2380Y         S3      
327GND              U14   -2          A01X+026733Y+012752X0220Y0320R180 S1      
317GND              VIA   -    MD0100PA00X+032338Y+016138X0200Y         S0      
317GND              VIA   -    MD0100PA00X+032338Y+016538X0200Y         S0      
317GND              VIA   -    MD0100PA00X+032024Y+015108X0200Y         S0      
317GND              VIA   -    MD0100PA00X+019683Y+024035X0200Y         S0      
317GND              VIA   -    MD0100PA00X+033708Y+019700X0200Y         S0      
317GND              VIA   -    MD0100PA00X+022555Y+019754X0180Y    R090 S0      
317GND              VIA   -    MD0100PA00X+022870Y+016920X0180Y    R180 S0      
317GND              VIA   -    MD0100PA00X+022240Y+016920X0180Y    R270 S0      
317GND              VIA   -    MD0100PA00X+022874Y+021325X0180Y    R270 S0      
317GND              VIA   -    MD0100PA00X+023728Y+010751X0200Y         S0      
317GND              VIA   -    MD0100PA00X+026844Y+012148X0200Y         S0      
317GND              VIA   -    MD0100PA00X+026510Y+042400X0200Y         S0      
317GND              VIA   -    MD0100PA00X+025111Y+010292X0200Y         S0      
317GND              VIA   -    MD0100PA00X+024499Y+010353X0200Y         S0      
317GND              VIA   -    MD0100PA00X+022496Y+010724X0200Y         S0      
317GND              VIA   -    MD0100PA00X+025440Y+010370X0200Y         S0      
317GND              VIA   -    MD0100PA00X+025976Y+010365X0200Y         S0      
317GND              VIA   -    MD0100PA00X+020982Y+010612X0200Y         S0      
317GND              VIA   -    MD0100PA00X+025237Y+013216X0200Y         S0      
317GND              VIA   -    MD0100PA00X+024280Y+013220X0200Y         S0      
317GND              VIA   -    MD0100PA00X+024281Y+011750X0200Y         S0      
317GND              VIA   -    MD0100PA00X+029236Y+019797X0180Y    R090 S0      
317GND              VIA   -    MD0100PA00X+010022Y+044313X0200Y         S0      
317GND              VIA   -    MD0100PA00X+009456Y+044329X0200Y         S0      
317GND              VIA   -    MD0100PA00X+009716Y+045044X0200Y         S0      
317GND              VIA   -    MD0100PA00X+009200Y+045040X0200Y         S0      
317GND              VIA   -    MD0100PA00X+020984Y+019751X0180Y    R180 S0      
317GND              VIA   -    MD0100PA00X+020984Y+020066X0180Y    R180 S0      
317GND              VIA   -    MD0100PA00X+020354Y+019751X0180Y    R180 S0      
317GND              VIA   -    MD0100PA00X+020354Y+020066X0180Y    R180 S0      
317GND              VIA   -    MD0100PA00X+019724Y+019751X0180Y    R180 S0      
317GND              VIA   -    MD0100PA00X+019724Y+020066X0180Y    R180 S0      
317GND              VIA   -    MD0100PA00X+016636Y+020979X0200Y         S0      
317GND              VIA   -    MD0100PA00X+031960Y+020114X0200Y         S0      
317GND              VIA   -    M      A01X+031116Y+019484X0180Y         S2      
017GND              VIA   -    M      A12X+031116Y+019484X0260Y         S2      
017GND                    -    MD0100PA00X+031116Y+019484                       
317GND              VIA   -    MD0100PA00X+031116Y+020114X0180Y         S0      
317GND              VIA   -    MD0100PA00X+029737Y+019662X0180Y    R180 S0      
317GND              VIA   -    MD0100PA00X+030151Y+019544X0200Y         S0      
317GND              VIA   -    MD0100PA00X+028610Y+019799X0180Y         S0      
317GND              VIA   -    MD0100PA00X+028610Y+020114X0180Y         S0      
317GND              VIA   -    MD0100PA00X+025390Y+020066X0180Y    R180 S0      
317GND              VIA   -    MD0100PA00X+024760Y+019751X0180Y    R180 S0      
317GND              VIA   -    MD0100PA00X+003064Y+030907X0200Y    R090 S0      
317GND              VIA   -    M      A01X+003064Y+031196X0200Y    R090 S2      
017GND              VIA   -    M      A12X+003064Y+031196X0260Y    R090 S2      
017GND                    -    MD0100PA00X+003064Y+031196                       
317GND              VIA   -    MD0100PA00X+002224Y+030859X0200Y    R090 S0      
317GND              VIA   -    MD0100PA00X+002224Y+031148X0200Y    R090 S0      
317GND              VIA   -    MD0100PA00X+000620Y+031290X0200Y    R270 S0      
317GND              VIA   -    MD0100PA00X+004744Y+031208X0200Y    R090 S0      
317GND              VIA   -    M      A01X+003904Y+031193X0200Y    R090 S2      
017GND              VIA   -    M      A12X+003904Y+031193X0260Y    R090 S2      
017GND                    -    MD0100PA00X+003904Y+031193                       
317GND              VIA   -    MD0100PA00X+003904Y+030904X0200Y    R090 S0      
317GND              VIA   -    MD0100PA00X+004744Y+030869X0200Y    R090 S0      
317GND              VIA   -    MD0100PA00X+014278Y+026683X0200Y    R180 S0      
317GND              VIA   -    MD0100PA00X+016631Y+022519X0200Y         S0      
317GND              VIA   -    MD0100PA00X+014904Y+045875X0200Y         S0      
317GND              VIA   -    MD0100PA00X+017835Y+022585X0180Y         S0      
317GND              VIA   -    MD0100PA00X+018464Y+020696X0180Y    R180 S0      
317GND              VIA   -    MD0100PA00X+017835Y+021325X0180Y         S0      
317GND              VIA   -    MD0100PA00X+016085Y+046012X0200Y         S0      
317GND              VIA   -    MD0100PA00X+019724Y+020380X0180Y    R180 S0      
317GND              VIA   -    MD0100PA00X+020039Y+021010X0180Y    R180 S0      
317GND              VIA   -    MD0100PA00X+018779Y+021325X0180Y         S0      
317GND              VIA   -    MD0100PA00X+017440Y+024914X0200Y         S0      
317GND              VIA   -    MD0100PA00X+018464Y+023215X0180Y    R180 S0      
317GND              VIA   -    MD0100PA00X+017408Y+023460X0180Y         S0      
317GND              VIA   -    MD0100PA00X+018923Y+028066X0200Y         S0      
317GND              VIA   -    MD0100PA00X+019158Y+026136X0200Y         S0      
317GND              VIA   -    MD0100PA00X+019409Y+023215X0180Y    R180 S0      
317GND              VIA   -    MD0100PA00X+019899Y+024781X0200Y         S0      
317GND              VIA   -    MD0100PA00X+019724Y+021955X0180Y    R180 S0      
317GND              VIA   -    MD0100PA00X+020354Y+023215X0180Y         S0      
317GND              VIA   -    MD0100PA00X+021299Y+021955X0180Y    R180 S0      
317GND              VIA   -    MD0100PA00X+020984Y+021010X0180Y    R180 S0      
317GND              VIA   -    MD0100PA00X+021299Y+021010X0180Y    R180 S0      
317GND              VIA   -    MD0100PA00X+021299Y+020696X0180Y    R180 S0      
317GND              VIA   -    MD0100PA00X+020354Y+021010X0180Y    R180 S0      
317GND              VIA   -    MD0100PA00X+022240Y+020696X0180Y         S0      
317GND              VIA   -    MD0100PA00X+022240Y+021325X0180Y         S0      
317GND              VIA   -    M      A01X+020421Y+027820X0300Y    R180 S1      
017GND              VIA   -    M      A12X+020421Y+027820X0200Y    R180 S1      
017GND                    -    MD0100PA00X+020421Y+027820                       
317GND              VIA   -    MD0100PA00X+020513Y+028200X0200Y    R180 S0      
317GND              VIA   -    MD0100PA00X+021126Y+026730X0200Y         S0      
317GND              VIA   -    MD0100PA00X+022544Y+028227X0200Y    R090 S0      
317GND              VIA   -    MD0100PA00X+022367Y+029074X0200Y         S0      
317GND              VIA   -    MD0100PA00X+021925Y+023215X0180Y    R180 S0      
317GND              VIA   -    MD0100PA00X+022870Y+021955X0180Y    R180 S0      
317GND              VIA   -    MD0100PA00X+023819Y+022585X0180Y    R270 S0      
317GND              VIA   -    MD0100PA00X+023815Y+021955X0180Y    R180 S0      
317GND              VIA   -    MD0100PA00X+024130Y+021325X0180Y    R180 S0      
317GND              VIA   -    MD0100PA00X+023500Y+021955X0180Y    R180 S0      
317GND              VIA   -    MD0100PA00X+023500Y+020696X0180Y    R180 S0      
317GND              VIA   -    MD0100PA00X+023277Y+026953X0200Y         S0      
317GND              VIA   -    MD0100PA00X+024130Y+023215X0180Y    R180 S0      
317GND              VIA   -    MD0100PA00X+023185Y+023215X0180Y    R180 S0      
317GND              VIA   -    MD0100PA00X+024402Y+023552X0180Y    R270 S0      
317GND              VIA   -    MD0100PA00X+023863Y+023565X0180Y    R180 S0      
317GND              VIA   -    MD0100PA00X+025339Y+027366X0200Y         S0      
317GND              VIA   -    MD0100PA00X+025705Y+023530X0180Y    R180 S0      
317GND              VIA   -    MD0100PA00X+025075Y+023215X0180Y    R180 S0      
317GND              VIA   -    MD0100PA00X+025705Y+021955X0180Y    R180 S0      
317GND              VIA   -    MD0100PA00X+025705Y+022589X0180Y    R090 S0      
317GND              VIA   -    MD0100PA00X+026027Y+020736X0180Y         S0      
317GND              VIA   -    MD0100PA00X+025390Y+020696X0180Y    R180 S0      
317GND              VIA   -    MD0100PA00X+024760Y+020380X0180Y    R180 S0      
317GND              VIA   -    MD0100PA00X+028600Y+024210X0200Y         S0      
317GND              VIA   -    MD0100PA00X+028925Y+021059X0180Y         S0      
317GND              VIA   -    MD0100PA00X+028925Y+021374X0180Y         S0      
317GND              VIA   -    MD0100PA00X+028909Y+020433X0180Y         S0      
317GND              VIA   -    MD0100PA00X+026953Y+045906X0200Y         S0      
317GND              VIA   -    MD0100PA00X+026839Y+020726X0180Y    R180 S0      
317GND              VIA   -    MD0100PA00X+026127Y+021466X0180Y         S0      
317GND              VIA   -    MD0100PA00X+026939Y+021459X0180Y    R180 S0      
317GND              VIA   -    MD0100PA00X+030269Y+027550X0200Y    R270 S0      
317GND              VIA   -    MD0100PA00X+030112Y+022642X0200Y    R270 S0      
317GND              VIA   -    MD0100PA00X+030112Y+022981X0200Y    R270 S0      
317GND              VIA   -    MD0100PA00X+030394Y+021266X0180Y         S0      
317GND              VIA   -    MD0100PA00X+028371Y+045940X0200Y         S0      
317GND              VIA   -    MD0100PA00X+027756Y+046003X0200Y         S0      
317GND              VIA   -    M      A01X+028189Y+028764X0300Y         S1      
017GND              VIA   -    M      A12X+028189Y+028764X0200Y         S1      
017GND                    -    MD0100PA00X+028189Y+028764                       
317GND              VIA   -    M      A01X+030952Y+022640X0200Y    R270 S2      
017GND              VIA   -    M      A12X+030952Y+022640X0260Y    R270 S2      
017GND                    -    MD0100PA00X+030952Y+022640                       
317GND              VIA   -    MD0100PA00X+030952Y+022979X0200Y    R270 S0      
317GND              VIA   -    MD0100PA00X+031792Y+022637X0200Y    R270 S0      
317GND              VIA   -    MD0100PA00X+031792Y+022976X0200Y    R270 S0      
317GND              VIA   -    MD0100PA00X+031431Y+020744X0180Y         S0      
317GND              VIA   -    MD0100PA00X+031116Y+021374X0180Y         S0      
317GND              VIA   -    MD0100PA00X+031116Y+020429X0180Y         S0      
317GND              VIA   -    MD0100PA00X+030846Y+021418X0180Y    R315 S0      
317GND              VIA   -    MD0100PA00X+029169Y+045991X0200Y         S0      
317GND              VIA   -    MD0100PA00X+029169Y+045691X0200Y         S0      
317GND              VIA   -    MD0100PA00X+029169Y+045391X0200Y         S0      
317GND              VIA   -    MD0100PA00X+029740Y+039738X0200Y         S0      
317GND              VIA   -    MD0100PA00X+029875Y+039012X0200Y         S0      
317GND              VIA   -    MD0100PA00X+030308Y+029752X0200Y         S0      
317GND              VIA   -    M      A01X+033700Y+021011X0300Y    R180 S1      
017GND              VIA   -    M      A12X+033700Y+021011X0200Y    R180 S1      
017GND                    -    MD0100PA00X+033700Y+021011                       
317GND              VIA   -    MD0100PA00X+033700Y+020611X0200Y    R180 S0      
317GND              VIA   -    M      A01X+033700Y+020211X0300Y    R180 S1      
017GND              VIA   -    M      A12X+033700Y+020211X0200Y    R180 S1      
017GND                    -    MD0100PA00X+033700Y+020211                       
317GND              VIA   -    MD0100PA00X+033247Y+039409X0200Y    R090 S0      
317GND              VIA   -    MD0100PA00X+033247Y+039709X0200Y    R090 S0      
317GND              VIA   -    MD0100PA00X+031498Y+039464X0200Y    R090 S0      
317GND              VIA   -    MD0100PA00X+031498Y+039764X0200Y    R090 S0      
317GND              VIA   -    MD0100PA00X+032532Y+039012X0200Y         S0      
317GND              VIA   -    MD0100PA00X+030850Y+038210X0200Y    R180 S0      
317GND              VIA   -    MD0100PA00X+032504Y+035689X0200Y         S0      
317GND              VIA   -    MD0100PA00X+032632Y+022635X0200Y    R270 S0      
317GND              VIA   -    MD0100PA00X+032632Y+022974X0200Y    R270 S0      
317GND              VIA   -    MD0100PA00X+033472Y+022974X0200Y    R090 S0      
317GND              VIA   -    MD0100PA00X+033472Y+022635X0200Y    R090 S0      
317GND              VIA   -    MD0100PA00X+031223Y+038277X0200Y         S0      
317GND              VIA   -    MD0100PA00X+031417Y+030702X0200Y         S0      
317GND              VIA   -    MD0100PA00X+031413Y+031018X0200Y         S0      
317GND              VIA   -    MD0100PA00X+031418Y+029944X0200Y         S0      
317GND              VIA   -    MD0100PA00X+031420Y+030236X0200Y         S0      
317GND              VIA   -    MD0100PA00X+031482Y+029613X0200Y         S0      
317GND              VIA   -    MD0100PA00X+031743Y+029566X0200Y         S0      
317GND              VIA   -    MD0100PA00X+031232Y+029321X0200Y         S0      
317GND              VIA   -    MD0100PA00X+031581Y+029345X0200Y         S0      
317GND              VIA   -    MD0100PA00X+031767Y+029143X0200Y         S0      
317GND              VIA   -    M      A01X+031211Y+028844X0200Y         S2      
017GND              VIA   -    M      A12X+031211Y+028844X0260Y         S2      
017GND                    -    MD0100PA00X+031211Y+028844                       
317GND              VIA   -    MD0100PA00X+030086Y+010406X0200Y         S0      
317GND              VIA   -    MD0100PA00X+002125Y+020622X0200Y    R270 S0      
317GND              VIA   -    MD0100PA00X+033188Y+010458X0200Y         S0      
317GND              VIA   -    MD0100PA00X+033188Y+010859X0200Y         S0      
317GND              VIA   -    MD0100PA00X+033188Y+011261X0200Y         S0      
317GND              VIA   -    MD0100PA00X+027960Y+013140X0200Y         S0      
317GND              VIA   -    MD0100PA00X+032135Y+013004X0200Y    R270 S0      
317GND              VIA   -    MD0100PA00X+032128Y+013453X0200Y    R270 S0      
317GND              VIA   -    MD0100PA00X+032930Y+012989X0200Y    R270 S0      
317GND              VIA   -    MD0100PA00X+032930Y+013459X0200Y    R270 S0      
317GND              VIA   -    MD0100PA00X+019724Y+017865X0180Y    R180 S0      
317GND              VIA   -    MD0100PA00X+020039Y+016920X0180Y         S0      
317GND              VIA   -    MD0100PA00X+019724Y+015660X0180Y    R180 S0      
317GND              VIA   -    MD0100PA00X+019724Y+019124X0180Y    R180 S0      
317GND              VIA   -    MD0100PA00X+020039Y+019124X0180Y    R180 S0      
317GND              VIA   -    MD0100PA00X+020984Y+018494X0180Y    R180 S0      
317GND              VIA   -    MD0100PA00X+020984Y+018180X0180Y    R180 S0      
317GND              VIA   -    MD0100PA00X+020669Y+017865X0180Y    R180 S0      
317GND              VIA   -    MD0100PA00X+021299Y+018180X0180Y    R180 S0      
317GND              VIA   -    MD0100PA00X+020669Y+016920X0180Y    R180 S0      
317GND              VIA   -    MD0100PA00X+021299Y+016920X0180Y    R180 S0      
317GND              VIA   -    MD0100PA00X+020354Y+016920X0180Y    R180 S0      
317GND              VIA   -    MD0100PA00X+020984Y+015660X0180Y    R180 S0      
317GND              VIA   -    MD0100PA00X+020669Y+019124X0180Y    R180 S0      
317GND              VIA   -    MD0100PA00X+020354Y+019124X0180Y    R180 S0      
317GND              VIA   -    MD0100PA00X+022555Y+017865X0180Y    R180 S0      
317GND              VIA   -    MD0100PA00X+022555Y+018494X0180Y    R180 S0      
317GND              VIA   -    MD0100PA00X+021925Y+017865X0180Y    R180 S0      
317GND              VIA   -    MD0100PA00X+021770Y+017485X0180Y         S0      
317GND              VIA   -    MD0100PA00X+022555Y+015660X0180Y    R180 S0      
317GND              VIA   -    MD0100PA00X+022870Y+019124X0180Y    R180 S0      
317GND              VIA   -    MD0100PA00X+021929Y+019121X0180Y         S0      
317GND              VIA   -    MD0100PA00X+023500Y+018494X0180Y    R180 S0      
317GND              VIA   -    MD0100PA00X+023500Y+016605X0180Y         S0      
317GND              VIA   -    MD0100PA00X+024445Y+015660X0180Y    R180 S0      
317GND              VIA   -    MD0100PA00X+024130Y+019124X0180Y    R180 S0      
317GND              VIA   -    MD0100PA00X+023185Y+019124X0180Y    R180 S0      
317GND              VIA   -    MD0100PA00X+025390Y+017865X0180Y    R180 S0      
317GND              VIA   -    MD0100PA00X+025390Y+018494X0180Y    R180 S0      
317GND              VIA   -    MD0100PA00X+025390Y+017235X0180Y    R180 S0      
317GND              VIA   -    MD0100PA00X+025390Y+019124X0180Y    R180 S0      
317GND              VIA   -    MD0100PA00X+026288Y+017898X0180Y    R315 S0      
317GND              VIA   -    MD0100PA00X+027450Y+013163X0200Y         S0      
317GND              VIA   -    MD0100PA00X+029089Y+015232X0200Y    R180 S0      
317GND              VIA   -    MD0100PA00X+026851Y+017909X0180Y    R270 S0      
317GND              VIA   -    MD0100PA00X+028548Y+019019X0180Y    R045 S0      
317GND              VIA   -    MD0100PA00X+028610Y+018238X0180Y         S0      
317GND              VIA   -    MD0100PA00X+028610Y+017294X0180Y         S0      
317GND              VIA   -    MD0100PA00X+027816Y+017608X0200Y         S0      
317GND              VIA   -    MD0100PA00X+028598Y+016349X0180Y         S0      
317GND              VIA   -    MD0100PA00X+029369Y+015223X0200Y    R180 S0      
317GND              VIA   -    MD0100PA00X+030444Y+013590X0200Y         S0      
317GND              VIA   -    MD0100PA00X+030194Y+013580X0200Y         S0      
317GND              VIA   -    MD0100PA00X+031431Y+019169X0180Y         S0      
317GND              VIA   -    MD0100PA00X+031130Y+018238X0180Y    R270 S0      
317GND              VIA   -    MD0100PA00X+031116Y+018553X0180Y         S0      
317GND              VIA   -    MD0100PA00X+030801Y+016349X0180Y         S0      
317GND              VIA   -    MD0100PA00X+033140Y+019241X0200Y         S0      
317GND              VIA   -    MD0100PA00X+033140Y+018741X0200Y         S0      
317GND              VIA   -    MD0100PA00X+033140Y+017741X0200Y         S0      
317GND              VIA   -    MD0100PA00X+032338Y+017738X0200Y         S0      
317GND              VIA   -    MD0100PA00X+032338Y+017338X0200Y         S0      
317GND              VIA   -    MD0100PA00X+033140Y+015741X0200Y         S0      
317GND              VIA   -    MD0100PA00X+032338Y+016938X0200Y         S0      
317GND              VIA   -    MD0100PA00X+032338Y+015738X0200Y         S0      
317GND              VIA   -    MD0100PA00X+033328Y+015113X0200Y         S0      
317GND              VIA   -    MD0100PA00X+033980Y+018991X0200Y    R180 S0      
317GND              VIA   -    MD0100PA00X+033980Y+017991X0200Y    R180 S0      
317GND              VIA   -    MD0100PA00X+033980Y+018591X0200Y    R180 S0      
317GND              VIA   -    MD0100PA00X+033980Y+017691X0200Y    R180 S0      
317GND              VIA   -    MD0100PA00X+033980Y+016591X0200Y    R180 S0      
317GND              VIA   -    MD0100PA00X+033980Y+016991X0200Y    R180 S0      
317GND              VIA   -    MD0100PA00X+033980Y+015991X0200Y    R180 S0      
317GND              VIA   -    MD0100PA00X+033980Y+015491X0200Y    R180 S0      
317GND              VIA   -    M      A01X+033784Y+012853X0200Y    R090 S2      
017GND              VIA   -    M      A12X+033784Y+012853X0260Y    R090 S2      
017GND                    -    MD0100PA00X+033784Y+012853                       
317GND              VIA   -    MD0100PA00X+033910Y+012113X0200Y    R090 S0      
317GND              VIA   -    M      A01X+033910Y+011733X0200Y    R090 S2      
017GND              VIA   -    M      A12X+033910Y+011733X0260Y    R090 S2      
017GND                    -    MD0100PA00X+033910Y+011733                       
317GND              VIA   -    MD0100PA00X+001700Y+021929X0200Y         S0      
317GND              VIA   -    MD0100PA00X+001700Y+021571X0200Y         S0      
317GND              VIA   -    M      A01X+004729Y+018449X0200Y         S2      
017GND              VIA   -    M      A12X+004729Y+018449X0260Y         S2      
017GND                    -    MD0100PA00X+004729Y+018449                       
317GND              VIA   -    MD0100PA00X+014840Y+015576X0200Y         S0      
317GND              VIA   -    MD0100PA00X+016124Y+019048X0200Y         S0      
317GND              VIA   -    MD0100PA00X+016124Y+018582X0200Y         S0      
317GND              VIA   -    MD0100PA00X+004922Y+012129X0200Y    R180 S0      
317GND              VIA   -    MD0100PA00X+004922Y+012379X0200Y    R180 S0      
317GND              VIA   -    MD0100PA00X+005216Y+012122X0200Y    R270 S0      
317GND              VIA   -    MD0100PA00X+004072Y+012079X0200Y    R180 S0      
317GND              VIA   -    MD0100PA00X+004072Y+012379X0200Y    R180 S0      
317GND              VIA   -    MD0100PA00X+003222Y+012079X0200Y    R180 S0      
317GND              VIA   -    MD0100PA00X+003222Y+012379X0200Y    R180 S0      
317GND              VIA   -    MD0100PA00X+002372Y+012079X0200Y    R180 S0      
317GND              VIA   -    MD0100PA00X+002372Y+012379X0200Y    R180 S0      
317GND              VIA   -    M      A01X+004894Y+020487X0200Y    R270 S2      
017GND              VIA   -    M      A12X+004894Y+020487X0260Y    R270 S2      
017GND                    -    MD0100PA00X+004894Y+020487                       
317GND              VIA   -    MD0100PA00X+004771Y+021223X0200Y    R270 S0      
317GND              VIA   -    M      A01X+004804Y+019154X0200Y    R270 S2      
017GND              VIA   -    M      A12X+004804Y+019154X0260Y    R270 S2      
017GND                    -    MD0100PA00X+004804Y+019154                       
317GND              VIA   -    MD0100PA00X+003782Y+019835X0200Y    R270 S0      
317GND              VIA   -    MD0100PA00X+003736Y+019405X0200Y    R270 S0      
317GND              VIA   -    MD0100PA00X+003660Y+018902X0200Y    R270 S0      
317GND              VIA   -    MD0100PA00X+001663Y+019305X0200Y    R270 S0      
317GND              VIA   -    MD0100PA00X+001913Y+019305X0200Y    R270 S0      
317GND              VIA   -    MD0100PA00X+001663Y+020425X0200Y    R270 S0      
317GND              VIA   -    MD0100PA00X+001913Y+020145X0200Y    R270 S0      
317GND              VIA   -    MD0100PA00X+001913Y+019585X0200Y    R270 S0      
317GND              VIA   -    MD0100PA00X+001913Y+019865X0200Y    R270 S0      
317GND              VIA   -    MD0100PA00X+001663Y+020145X0200Y    R270 S0      
317GND              VIA   -    MD0100PA00X+001663Y+019585X0200Y    R270 S0      
317GND              VIA   -    MD0100PA00X+001663Y+019865X0200Y    R270 S0      
317GND              VIA   -    MD0100PA00X+001700Y+021154X0200Y         S0      
317GND              VIA   -    MD0100PA00X+001700Y+020802X0200Y    R270 S0      
317GND              VIA   -    MD0100PA00X+001913Y+020425X0200Y    R270 S0      
317GND              VIA   -    MD0100PA00X+017835Y+018494X0180Y    R180 S0      
317GND              VIA   -    MD0100PA00X+017835Y+016290X0180Y    R180 S0      
317GND              VIA   -    MD0100PA00X+017835Y+017235X0180Y    R180 S0      
317GND              VIA   -    MD0100PA00X+017536Y+015329X0180Y    R180 S0      
317GND              VIA   -    MD0100PA00X+018590Y+024994X0200Y         S0      
317GND              VIA   -    MD0100PA00X+023500Y+020066X0180Y    R180 S0      
327GND              R620  -2          A01X+030308Y+029479X0198Y0197R090 S1      
327GND              C244  -2   M      A01X+014394Y+034857X0198Y0197R270 S1      
327GND              U29   -3          A12X+022755Y+007946X0240Y0240R270 S2      
327GND              C218  -2   M      A12X+010496Y+035428X0164Y0164R180 S2      
327GND              C160  -2          A12X+010658Y+035750X0164Y0164R180 S2      
327GND              R378  -2          A01X+018292Y+008800X0198Y0197R180 S1      
327GND              C172  -2   M      A01X+021450Y+009408X0198Y0197R090 S1      
327GND              R205  -2          A12X+016900Y+007808X0198Y0197R270 S2      
327GND              U13   -3          A01X+005182Y+041610X0160Y0200R090 S1      
327GND              GF1   -B70        A01X+005648Y+046638X0150Y0840R180 S1      
327GND              GF1   -B67        A01X+006356Y+046638X0150Y0840R180 S1      
327GND              C301  -2   M      A12X+031438Y+026030X0198Y0197R180 S2      
327GND              U52   -3          A12X+031666Y+027409X0130Y0460R180 S2      
327GND              U35   -8   M      A01X+012338Y+012250X0180Y0230R270 S1      
327GND              U35   -3   M      A01X+012638Y+012250X0180Y0270R270 S1      
327GND              J4    -G1         A01X+006457Y+031549X0490Y1100     S1      
327GND              J4    -7          A01X+007480Y+031854X0110Y0630     S1      
327GND              J4    -45         A01X+011220Y+031854X0110Y0630     S1      
327GND              J4    -75         A01X+014173Y+031854X0110Y0630     S1      
327GND              J4    -24         A01X+009154Y+028882X0110Y0630     S1      
327GND              J4    -36         A01X+010335Y+028882X0110Y0630     S1      
327GND              C210  -2          A12X+012950Y+011958X0198Y0197R270 S2      
327GND              J8    -G1  M      A01X+014626Y+012961X0480Y0710R270 S1      
327GND              C256  -2   M      A12X+013058Y+035750X0198Y0197R180 S2      
327GND              C257  -2          A12X+013058Y+035350X0198Y0197R180 S2      
327GND              C11   -2          A12X+012558Y+027700X0198Y0197R180 S2      
327GND              C231  -2   M      A12X+013092Y+027700X0198Y0197     S2      
327GND              C264  -2          A01X+013300Y+017658X0198Y0197R090 S1      
327GND              C253  -2   M      A01X+012900Y+017658X0198Y0197R090 S1      
327GND              C202  -2          A12X+012025Y+016462X0198Y0197R270 S2      
327GND              C203  -2   M      A12X+012450Y+016462X0198Y0197R270 S2      
327GND              R786  -2          A12X+012422Y+023480X0198Y0197     S2      
327GND              C290  -2   M      A12X+012422Y+023830X0198Y0197     S2      
327GND              R545  -1          A01X+022608Y+029660X0198Y0197R180 S1      
327GND              R182  -1   M      A01X+022608Y+030060X0198Y0197R180 S1      
327GND              U17   -10  M      A01X+016801Y+040575X0170Y0670     S1      
327GND              SW7   -4          A01X+033937Y+001059X0790Y0790     S1      
327GND              SW7   -3   M      A01X+030630Y+001059X0790Y0790     S1      
327GND              C209  -2          A12X+012550Y+012108X0198Y0197R270 S2      
327GND              C211  -2          A12X+014288Y+007870X0198Y0197R180 S2      
327GND              R507  -2          A01X+025058Y+032200X0198Y0197     S1      
327GND              R506  -2   M      A01X+025058Y+031350X0198Y0197     S1      
327GND              C197  -2          A12X+009050Y+007508X0198Y0197R270 S2      
327GND              R839  -2   M      A01X+005250Y+006992X0198Y0197R270 S1      
327GND              Q12   -1          A01X+004706Y+007224X0170Y0200     S1      
327GND              R619  -2          A01X+005250Y+006608X0198Y0197R090 S1      
317FRU_E2           VIA   -    M      A01X+032250Y+010290X0300Y         S1      
017FRU_E2           VIA   -    M      A12X+032250Y+010290X0200Y         S1      
017FRU_E2                 -    MD0100PA00X+032250Y+010290                       
327FRU_E2           R14   -2          A12X+033434Y+010468X0198Y0197     S2      
327FRU_E2           R413  -1   M      A12X+032631Y+010468X0198Y0197R180 S2      
327FRU_E2           U19   -3          A12X+030994Y+010565X0170Y0700R090 S2      
327FRU_E1           R13   -2          A12X+033434Y+010869X0198Y0197     S2      
327FRU_E1           R412  -1   M      A12X+032631Y+010869X0198Y0197R180 S2      
327FRU_E1           U19   -2          A12X+030994Y+010821X0170Y0700R090 S2      
327FRU_E1           VIA   -    M      A12X+032180Y+010900X0260Y         S2      
327FRU_E0           R12   -2          A12X+033434Y+011271X0198Y0197     S2      
327FRU_E0           R411  -1   M      A12X+032631Y+011271X0198Y0197R180 S2      
327FRU_E0           U19   -1          A12X+030994Y+011077X0170Y0700R090 S2      
327FRU_E0           VIA   -    M      A12X+031700Y+011150X0260Y         S2      
327REAR_PWR_BTN_N   SW6   -2          A01X+004035Y+002752X0590Y0790     S1      
327REAR_PWR_BTN_N   U31   -2          A01X+004548Y+004590X0400Y0150R090 S1      
327REAR_PWR_BTN_N   R734  -1   M      A01X+005064Y+003487X0198Y0197     S1      
327REAR_PWR_BTN_N   R768  -2          A01X+004708Y+003800X0198Y0197     S1      
327REAR_PWR_BTN_N   C198  -1   M      A01X+004008Y+003800X0198Y0197R180 S1      
327FM_THROTTLE_N    R769  -1   M      A01X+011910Y+039938X0198Y0197R270 S1      
317FM_THROTTLE_N    VIA   -    MD0100PA00X+012517Y+039392X0200Y         S0      
327FM_THROTTLE_N    R45   -2          A01X+011650Y+040302X0198Y0197R270 S1      
317FM_THROTTLE_N    VIA   -    M      A01X+014189Y+031057X0200Y         S2      
017FM_THROTTLE_N    VIA   -    M      A12X+014189Y+031057X0260Y         S2      
017FM_THROTTLE_N          -    MD0100PA00X+014189Y+031057                       
317FM_THROTTLE_N    VIA   -    MD0100PA00X+020669Y+015660X0180Y    R180 S0      
327FM_THROTTLE_N    U5    -B16        A01X+020825Y+015816X0160Y    R180 S1      
327FM_SLPS3_GF_N    R773  -1          A12X+011768Y+036660X0198Y0197     S2      
327FM_SLPS3_GF_N    R774  -2          A01X+019968Y+026870X0198Y0197     S1      
327FM_SLPS3_GF_N    VIA   -    M      A01X+020644Y+026117X0300Y         S1      
327FM_SLPS3_GF_N    R722  -2          A12X+021210Y+025038X0198Y0197R270 S2      
317FM_SLPS3_GF_N    VIA   -    MD0100PA00X+020620Y+025538X0200Y         S0      
327FM_SLPS3_GF_N    R721  -1          A12X+020018Y+035625X0198Y0197R180 S2      
317FM_SLPS3_GF_N    VIA   -    MD0100PA00X+019745Y+035656X0200Y         S0      
317FM_SLPS3_GF_N    VIA   -    MD0100PA00X+012978Y+037450X0200Y         S0      
327m0670            U5    -C26        A01X+017675Y+016130X0160Y    R180 S1      
317m0670            VIA   -    MD0100PA00X+017520Y+015975X0180Y    R180 S0      
317m0670            VIA   -    MD0100PA00X+018400Y+014050X0200Y         S0      
327m0670            R763  -2          A01X+018400Y+013798X0198Y0197R090 S1      
317m0671            VIA   -    MD0100PA00X+013440Y+012765X0200Y         S0      
327m0671            R763  -1          A01X+018400Y+013482X0198Y0197R090 S1      
317m0671            VIA   -    MD0100PA00X+018210Y+013229X0200Y         S0      
327m0671            R62   -2          A01X+017263Y+012310X0198Y0197R090 S1      
317m0671            VIA   -    MD0100PA00X+008762Y+035272X0180Y         S2      
327m0671            U25   -D8         A01X+008606Y+035428X0160Y    R180 S1      
327m0672            U5    -F15        A01X+021140Y+017075X0160Y    R180 S1      
317m0672            VIA   -    MD0100PA00X+020984Y+016920X0180Y    R180 S0      
327m0672            R159  -2          A12X+013950Y+014408X0198Y0197R270 S2      
317m0672            VIA   -    MD0100PA00X+013846Y+014646X0200Y         S0      
327m0673            R881  -2          A01X+029900Y+029142X0198Y0197R270 S1      
327m0673            R616  -1          A01X+030709Y+029164X0198Y0197R090 S1      
327m0673            VIA   -    M      A01X+029810Y+028390X0300Y         S1      
317m0674            VIA   -    MD0100PA00X+013550Y+013500X0200Y         S0      
327m0674            R159  -1          A12X+013950Y+014092X0198Y0197R270 S2      
327m0674            U25   -T8         A01X+008606Y+039208X0160Y    R180 S1      
327m0674            R616  -2   M      A01X+030709Y+029479X0198Y0197R090 S1      
327m0674            R620  -1          A01X+030308Y+029164X0198Y0197R090 S1      
317m0674            VIA   -    MD0100PA00X+029130Y+031590X0200Y         S0      
317m0674            VIA   -    MD0100PA00X+030970Y+029479X0200Y         S0      
317m0674            VIA   -    MD0100PA00X+009999Y+031120X0200Y         S0      
317m0674            VIA   -    MD0100PA00X+004842Y+032162X0200Y         S0      
317m0674            VIA   -    M      A01X+008432Y+043051X0200Y         S2      
017m0674            VIA   -    M      A12X+008432Y+043051X0260Y         S2      
017m0674                  -    MD0100PA00X+008432Y+043051                       
327m0675            R70   -2          A01X+013290Y+018112X0198Y0197R270 S1      
317m0675            VIA   -    M      A01X+008150Y+017652X0200Y         S2      
017m0675            VIA   -    M      A12X+008150Y+017652X0260Y         S2      
017m0675                  -    MD0100PA00X+008150Y+017652                       
317m0675            VIA   -    M      A01X+010050Y+032855X0200Y    R090 S2      
017m0675            VIA   -    M      A12X+010050Y+032855X0260Y    R090 S2      
017m0675                  -    MD0100PA00X+010050Y+032855                       
327m0675            U25   -B4         A01X+009866Y+034798X0160Y    R180 S1      
327m0675            R169  -2   M      A01X+010310Y+033128X0198Y0197R090 S1      
327m0676            R121  -1          A12X+013550Y+014408X0198Y0197R090 S2      
317m0676            VIA   -    MD0100PA00X+013350Y+014680X0200Y         S0      
317m0676            VIA   -    MD0100PA00X+018779Y+017865X0180Y         S0      
327m0676            U5    -J22        A01X+018935Y+018020X0160Y    R180 S1      
327m0677            R270  -2          A12X+006606Y+033522X0198Y0197     S2      
327m0677            R121  -2          A12X+013550Y+014092X0198Y0197R090 S2      
327m0677            VIA   -    M      A12X+005550Y+031500X0260Y         S2      
317m0677            VIA   -    MD0100PA00X+005466Y+031166X0200Y         S0      
327m0677            R163  -2   M      A12X+006410Y+033108X0198Y0197R270 S2      
327m0677            R720  -1          A12X+020018Y+035275X0198Y0197R180 S2      
317m0677            VIA   -    MD0100PA00X+016140Y+030760X0200Y         S0      
317m0677            VIA   -    MD0100PA00X+019141Y+035745X0200Y         S0      
317m0677            VIA   -    MD0100PA00X+013550Y+013800X0200Y         S0      
317m0677            VIA   -    MD0100PA00X+010070Y+029360X0200Y         S0      
327m0678            U5    -D7         A01X+023659Y+016445X0160Y    R180 S1      
327m0678            VIA   -    M      A12X+024899Y+015700X0260Y         S2      
327m0678            R211  -2          A12X+026035Y+012260X0198Y0197R270 S2      
317m0678            VIA   -    MD0100PA00X+023815Y+016290X0180Y    R180 S0      
327FM_BMC_DISABLE   R431  -1   M      A01X+028800Y+029092X0198Y0197R090 S1      
327FM_BMC_DISABLE   R615  -2          A01X+029200Y+029092X0198Y0197R270 S1      
327FM_BMC_DISABLE   VIA   -    M      A12X+018757Y+033759X0260Y         S2      
317FM_BMC_DISABLE   VIA   -    MD0100PA00X+027750Y+034847X0200Y         S0      
317FM_BMC_DISABLE   VIA   -    MD0100PA00X+028776Y+028754X0200Y         S0      
317FM_BMC_DISABLE   VIA   -    MD0100PA00X+019046Y+034443X0200Y         S0      
327FM_BMC_DISABLE   U11   -3          A12X+016608Y+032764X0400Y0500R180 S2      
327m0679            R750  -1          A12X+008650Y+040308X0198Y0197R090 S2      
327m0679            R506  -1          A01X+024742Y+031350X0198Y0197     S1      
317m0679            VIA   -    MD0100PA00X+008949Y+040844X0200Y         S0      
327m0679            U5    -R26        A01X+017675Y+019910X0160Y    R180 S1      
317m0679            VIA   -    MD0100PA00X+012312Y+021309X0200Y         S0      
317m0679            VIA   -    MD0100PA00X+017520Y+020066X0180Y         S2      
327m0679            R624  -2          A01X+024358Y+031351X0198Y0197     S1      
317m0679            VIA   -    MD0100PA00X+024270Y+030680X0200Y    R270 S0      
327m0680            VIA   -    M      A01X+018160Y+014290X0300Y         S1      
327m0680            R705  -2          A01X+018000Y+013788X0198Y0197R090 S1      
327m0680            U5    -B21        A01X+019250Y+015816X0160Y    R180 S1      
327m0681            U5    -AB2        A01X+025234Y+022115X0160Y    R180 S1      
317m0681            VIA   -     D0100PA00X+025390Y+022270X0180Y         S0      
327m0682            U5    -AA2        A01X+025234Y+021800X0160Y    R180 S1      
317m0682            VIA   -     D0100PA00X+025390Y+021955X0180Y         S0      
327m0683            U5    -AC1        A01X+025549Y+022430X0160Y    R180 S1      
327m0684            U5    -AB1        A01X+025549Y+022115X0160Y    R180 S1      
327m0685            U5    -AC3        A01X+024919Y+022430X0160Y    R180 S1      
317m0685            VIA   -     D0100PA00X+025075Y+022585X0180Y         S0      
327m0686            U5    -AB3        A01X+024919Y+022115X0160Y    R180 S1      
317m0686            VIA   -     D0100PA00X+025075Y+022270X0180Y         S0      
327m0687            R158  -2          A12X+020700Y+013798X0198Y0197R270 S2      
327m0687            U5    -C15        A01X+021140Y+016130X0160Y    R180 S1      
317m0687            VIA   -    MD0100PA00X+020984Y+015975X0180Y         S2      
327CRT_VCC5         VIA   -           A12X+012680Y+013290X0260Y         S2      
317CRT_VCC5         VIA   -    MD0100PA00X+011780Y+014720X0200Y    R090 S0      
317CRT_VCC5         VIA   -    MD0100PA00X+012080Y+014720X0200Y    R090 S0      
327CRT_VCC5         VIA   -           A12X+012030Y+013480X0260Y         S2      
327CRT_VCC5         D11   -C          A12X+012216Y+014134X0390Y0480R090 S2      
327CRT_VCC5         D9    -C          A12X+011300Y+014150X0390Y0480R090 S2      
327CRT_VCC5         R27   -2          A12X+012980Y+015015X0280Y0320R180 S2      
327CRT_VCC5         C204  -1          A12X+012993Y+014493X0280Y0320R180 S2      
327CRT_VCC5         R16   -2          A01X+011502Y+010200X0198Y0197R180 S1      
327CRT_VCC5         R17   -2          A01X+011502Y+010760X0198Y0197R180 S1      
317CRT_VCC5         VIA   -    MD0100PA00X+011502Y+010480X0200Y         S0      
327CRT_VCC5         D12   -6          A01X+012030Y+008545X0220Y0320R180 S1      
327CRT_VCC5         D12   -4          A01X+011282Y+008545X0220Y0320R180 S1      
327CRT_VCC5         D12   -3          A01X+011282Y+009490X0220Y0320R180 S1      
327CRT_VCC5         D12   -1          A01X+012030Y+009490X0220Y0320R180 S1      
317CRT_VCC5         VIA   -    MD0100PA00X+010880Y+009190X0200Y         S0      
317CRT_VCC5         VIA   -    MD0100PA00X+011970Y+008920X0200Y         S0      
327CRT_VCC5         R91   -1          A01X+010680Y+008808X0198Y0197R270 S1      
327CRT_VCC5         R30   -1          A12X+016340Y+001578X0198Y0197R090 S2      
327CRT_VCC5         VIA   -    M      A12X+014300Y+001731X0260Y         S2      
327CRT_VCC5         R92   -1   M      A12X+013548Y+008430X0198Y0197     S2      
327m0688            D8    -A          A01X+017105Y+026680X0320Y0320     S1      
327m0688            R167  -2          A01X+017132Y+027280X0198Y0197R180 S1      
317m0689            VIA   -    MD0100PA00X+016450Y+026600X0200Y         S0      
317m0689            VIA   -    MD0100PA00X+018779Y+021955X0180Y         S0      
327m0689            U5    -Y23        A01X+018620Y+021485X0160Y    R180 S1      
327m0689            D8    -C          A01X+017695Y+026680X0320Y0320     S1      
327m0689            R805  -2   M      A01X+018098Y+027280X0198Y0197     S1      
327m0690            U26   -5   M      A12X+017435Y+001974X0240Y0240R270 S2      
327m0690            U33   -5          A12X+015385Y+001974X0240Y0240R270 S2      
327m0690            VIA   -    M      A12X+015895Y+002020X0260Y         S2      
327m0690            R18   -2          A12X+017940Y+001778X0198Y0197R270 S2      
327BMC_DDC_BUF_EN   U26   -1          A12X+017435Y+001266X0240Y0240R270 S2      
327BMC_DDC_BUF_EN   U33   -1          A12X+015385Y+001266X0240Y0240R270 S2      
327BMC_DDC_BUF_EN   VIA   -    M      A12X+015873Y+001262X0260Y         S2      
327BMC_DDC_BUF_EN   R30   -2   M      A12X+016340Y+001262X0198Y0197R090 S2      
327BMC_CLK_25M_R    R215  -1          A01X+023460Y+011108X0198Y0197R270 S1      
317BMC_CLK_25M_R    VIA   -    M      A01X+023159Y+011050X0200Y         S2      
017BMC_CLK_25M_R    VIA   -    M      A12X+023159Y+011050X0260Y         S2      
017BMC_CLK_25M_R          -    MD0100PA00X+023159Y+011050                       
327BMC_CLK_25M_R    OSC1  -3          A01X+022883Y+011373X0340Y0460R090 S1      
327BMC_CLK_25M      R215  -2          A01X+023460Y+010792X0198Y0197R270 S1      
327BMC_CLK_25M      U5    -D10        A01X+022715Y+016445X0160Y    R180 S1      
317BMC_CLK_25M      VIA   -    M      A01X+023563Y+010499X0200Y         S2      
017BMC_CLK_25M      VIA   -    M      A12X+023563Y+010499X0260Y         S2      
017BMC_CLK_25M            -    MD0100PA00X+023563Y+010499                       
317BMC_CLK_25M      VIA   -    MD0100PA00X+022870Y+016290X0180Y    R180 S0      
327A_BMC_DACREST    U5    -AC21       A01X+019250Y+022430X0160Y    R180 S1      
327A_BMC_DACREST    R235  -2          A12X+016970Y+024322X0198Y0197R090 S2      
317A_BMC_DACREST    VIA   -    MD0100PA00X+018779Y+022585X0180Y         S2      
327m0691            U5    -AD17       A01X+020510Y+022745X0160Y    R180 S1      
327m0691            C135  -2          A12X+020299Y+024194X0198Y0197R090 S2      
327m0691            C137  -2   M      A12X+020199Y+023726X0198Y0197R180 S2      
317m0691            VIA   -    MD0100PA00X+020354Y+022900X0180Y    R180 S0      
327m0692            U5    -AC20       A01X+019565Y+022430X0160Y    R180 S1      
327m0692            C136  -2          A12X+018489Y+024244X0198Y0197R090 S2      
327m0692            C138  -2   M      A12X+018495Y+023844X0198Y0197R180 S2      
317m0692            VIA   -    MD0100PA00X+019409Y+022585X0180Y    R180 S0      
327m0693            U5    -AD18       A01X+020195Y+022745X0160Y    R180 S1      
327m0693            C133  -2          A12X+019899Y+024194X0198Y0197R090 S2      
327m0693            C137  -1   M      A12X+019884Y+023726X0198Y0197R180 S2      
317m0693            VIA   -    MD0100PA00X+020039Y+022900X0180Y    R180 S2      
327m0694            U5    -AB20       A01X+019565Y+022115X0160Y    R180 S1      
327m0694            C134  -2          A12X+018130Y+024242X0198Y0197R090 S2      
327m0694            C138  -1   M      A12X+018180Y+023844X0198Y0197R180 S2      
317m0694            VIA   -    MD0100PA00X+019409Y+022270X0180Y    R180 S2      
327A_BMC_ADCREXT1   R234  -2          A01X+019714Y+026083X0198Y0197     S1      
327A_BMC_ADCREXT1   U5    -AF18       A01X+020195Y+023374X0160Y    R180 S1      
327A_BMC_ADCREXT1   VIA   -    M      A01X+019617Y+024555X0300Y         S1      
327A_BMC_ADCREXT0   R233  -2          A01X+019154Y+025026X0198Y0197R270 S1      
327A_BMC_ADCREXT0   U5    -AF20       A01X+019565Y+023374X0160Y    R180 S1      
327A_BMC_ADCREXT0   VIA   -    M      A01X+019071Y+024554X0300Y         S1      
327A_BMC_ADCAV33    VIA   -           A12X+017000Y+022350X0260Y         S2      
327A_BMC_ADCAV33    U5    -AA21M      A01X+019250Y+021800X0160Y    R180 S1      
327A_BMC_ADCAV33    U5    -Y21        A01X+019250Y+021485X0160Y    R180 S1      
327A_BMC_ADCAV33    C77   -1          A12X+018922Y+021721X0198Y0197R180 S2      
327A_BMC_ADCAV33    C75   -1          A12X+016968Y+022840X0198Y0197     S2      
327A_BMC_ADCAV33    L12   -2          A12X+017010Y+023310X0280Y0320R270 S2      
317A_BMC_ADCAV33    VIA   -    MD0100PA00X+019094Y+021955X0180Y    R180 S0      
C                                                                               
C  ****************************************                                     
C      DUMMY NET PINS & VIAS ON THE BOARD                                       
C  ****************************************                                     
C                                                                               
327N/C              U25   -D10        A01X+007976Y+035428X0160Y    R180 S1      
327N/C              DM1   -1          A01X-001674Y+053629X0300Y         S1      
327N/C              DM2   -1          A01X-002374Y+054329X0300Y         S1      
327N/C              Q13   -3          A01X+024576Y+004144X0170Y0200R090 S1      
327N/C              Q13   -5          A01X+025324Y+004400X0170Y0200R090 S1      
327N/C              Q13   -4          A01X+025324Y+004144X0170Y0200R090 S1      
327N/C              U5    -AD22       A01X+018935Y+022745X0160Y    R180 S1      
327N/C              U5    -A2         A01X+025234Y+015500X0160Y    R180 S1      
327N/C              U5    -B3         A01X+024919Y+015816X0160Y    R180 S1      
327N/C              U25   -J11        A01X+007661Y+037003X0160Y    R180 S1      
327N/C              U5    -C1         A01X+025549Y+016130X0160Y    R180 S1      
327N/C              U5    -A3         A01X+024919Y+015500X0160Y    R180 S1      
327N/C              U5    -D5         A01X+024289Y+016445X0160Y    R180 S1      
327N/C              U5    -D6         A01X+023974Y+016445X0160Y    R180 S1      
327N/C              U25   -T4         A01X+009866Y+039208X0160Y    R180 S1      
327N/C              U5    -E2         A01X+025234Y+016760X0160Y    R180 S1      
327N/C              U5    -F4         A01X+024604Y+017075X0160Y    R180 S1      
327N/C              U5    -D1         A01X+025549Y+016445X0160Y    R180 S1      
327N/C              U5    -E3         A01X+024919Y+016760X0160Y    R180 S1      
327N/C              U5    -D2         A01X+025234Y+016445X0160Y    R180 S1      
327N/C              U5    -E5         A01X+024289Y+016760X0160Y    R180 S1      
327N/C              U5    -C4         A01X+024604Y+016130X0160Y    R180 S1      
327N/C              U5    -B1         A01X+025549Y+015816X0160Y    R180 S1      
327N/C              U5    -B2         A01X+025234Y+015816X0160Y    R180 S1      
327N/C              U5    -Y4         A01X+024604Y+021485X0160Y    R180 S1      
327N/C              U5    -Y3         A01X+024919Y+021485X0160Y    R180 S1      
327N/C              U5    -Y2         A01X+025234Y+021485X0160Y    R180 S1      
327N/C              U5    -Y1         A01X+025549Y+021485X0160Y    R180 S1      
327N/C              U5    -AB6        A01X+023974Y+022115X0160Y    R180 S1      
327N/C              U5    -AC5        A01X+024289Y+022430X0160Y    R180 S1      
327N/C              U5    -AB5        A01X+024289Y+022115X0160Y    R180 S1      
327N/C              U5    -Y5         A01X+024289Y+021485X0160Y    R180 S1      
327N/C              U5    -AA5        A01X+024289Y+021800X0160Y    R180 S1      
327N/C              U5    -AC4        A01X+024604Y+022430X0160Y    R180 S1      
327N/C              U5    -AA4        A01X+024604Y+021800X0160Y    R180 S1      
327N/C              U5    -AB4        A01X+024604Y+022115X0160Y    R180 S1      
327N/C              U25   -G15        A01X+006401Y+036373X0160Y    R180 S1      
327N/C              U25   -G14        A01X+006716Y+036373X0160Y    R180 S1      
327N/C              U25   -H14        A01X+006716Y+036688X0160Y    R180 S1      
327N/C              U25   -H16        A01X+006086Y+036688X0160Y    R180 S1      
327N/C              U25   -P16        A01X+006086Y+038578X0160Y    R180 S1      
327N/C              U25   -P15        A01X+006401Y+038578X0160Y    R180 S1      
327N/C              U25   -A10        A01X+007976Y+034483X0160Y    R180 S1      
327N/C              U25   -F9         A01X+008291Y+036058X0160Y    R180 S1      
327N/C              U25   -F16        A01X+006086Y+036058X0160Y    R180 S1      
327N/C              U25   -L15        A01X+006401Y+037633X0160Y    R180 S1      
327N/C              U25   -M16        A01X+006086Y+037948X0160Y    R180 S1      
327N/C                    -           A12X+027010Y+019800X0390Y         S2      
327N/C                    -           A12X+003086Y+001433X0390Y         S2      
327N/C                    -           A12X+020590Y+009950X0390Y         S2      
327N/C              U5    -C2         A01X+025234Y+016130X0160Y    R180 S1      
327N/C              U5    -D4         A01X+024604Y+016445X0160Y    R180 S1      
327N/C              U5    -E1         A01X+025549Y+016760X0160Y    R180 S1      
327N/C              U5    -E6         A01X+023974Y+016760X0160Y    R180 S1      
327N/C              U5    -C5         A01X+024289Y+016130X0160Y    R180 S1      
327N/C              U23   -1          A12X+017836Y+007997X0220Y0320R270 S2      
327N/C              U25   -D9         A01X+008291Y+035428X0160Y    R180 S1      
327N/C              U25   -K16        A01X+006086Y+037318X0160Y    R180 S1      
327N/C              U25   -R9         A01X+008291Y+038892X0160Y    R180 S1      
327N/C              U25   -T10        A01X+007976Y+039208X0160Y    R180 S1      
327N/C              U25   -P10        A01X+007976Y+038578X0160Y    R180 S1      
327N/C              U25   -R10        A01X+007976Y+038892X0160Y    R180 S1      
327N/C              U25   -N10        A01X+007976Y+038263X0160Y    R180 S1      
327N/C              U25   -M11        A01X+007661Y+037948X0160Y    R180 S1      
327N/C              U25   -T11        A01X+007661Y+039208X0160Y    R180 S1      
327N/C              U25   -P11        A01X+007661Y+038578X0160Y    R180 S1      
327N/C              U25   -N11        A01X+007661Y+038263X0160Y    R180 S1      
327N/C              U25   -R11        A01X+007661Y+038892X0160Y    R180 S1      
327N/C              U25   -T12        A01X+007346Y+039208X0160Y    R180 S1      
327N/C              U25   -R13        A01X+007031Y+038892X0160Y    R180 S1      
327N/C              U25   -T14        A01X+006716Y+039208X0160Y    R180 S1      
327N/C              U25   -P12        A01X+007346Y+038578X0160Y    R180 S1      
327N/C              U25   -T13        A01X+007031Y+039208X0160Y    R180 S1      
327N/C              U25   -P13        A01X+007031Y+038578X0160Y    R180 S1      
327N/C              U25   -L1         A01X+010811Y+037633X0160Y    R180 S1      
327N/C              U25   -L3         A01X+010181Y+037633X0160Y    R180 S1      
327N/C              U25   -K4         A01X+009866Y+037318X0160Y    R180 S1      
327N/C              U25   -L5         A01X+009551Y+037633X0160Y    R180 S1      
327N/C              U25   -L2         A01X+010496Y+037633X0160Y    R180 S1      
327N/C              U25   -M1         A01X+010811Y+037948X0160Y    R180 S1      
327N/C              U25   -K5         A01X+009551Y+037318X0160Y    R180 S1      
327N/C              U25   -L4         A01X+009866Y+037633X0160Y    R180 S1      
327N/C              U25   -M3         A01X+010181Y+037948X0160Y    R180 S1      
327N/C              U25   -N1         A01X+010811Y+038263X0160Y    R180 S1      
327N/C              U25   -N2         A01X+010496Y+038263X0160Y    R180 S1      
327N/C              U25   -P1         A01X+010811Y+038578X0160Y    R180 S1      
327N/C              U25   -M2         A01X+010496Y+037948X0160Y    R180 S1      
327N/C              U25   -N3         A01X+010181Y+038263X0160Y    R180 S1      
327N/C              U25   -R1         A01X+010811Y+038892X0160Y    R180 S1      
327N/C              U25   -P2         A01X+010496Y+038578X0160Y    R180 S1      
327N/C              U25   -K3         A01X+010181Y+037318X0160Y    R180 S1      
327N/C              U25   -K2         A01X+010496Y+037318X0160Y    R180 S1      
327N/C              U25   -J5         A01X+009551Y+037003X0160Y    R180 S1      
327N/C              U25   -K6         A01X+009236Y+037318X0160Y    R180 S1      
327N/C              U25   -G1         A01X+010811Y+036373X0160Y    R180 S1      
327N/C              U25   -H2         A01X+010496Y+036688X0160Y    R180 S1      
327N/C              U25   -H4         A01X+009866Y+036688X0160Y    R180 S1      
327N/C              U25   -J6         A01X+009236Y+037003X0160Y    R180 S1      
327N/C              U25   -H3         A01X+010181Y+036688X0160Y    R180 S1      
327N/C              U25   -H1         A01X+010811Y+036688X0160Y    R180 S1      
327N/C              U25   -J1         A01X+010811Y+037003X0160Y    R180 S1      
327N/C              U25   -J3         A01X+010181Y+037003X0160Y    R180 S1      
327N/C              U25   -J2         A01X+010496Y+037003X0160Y    R180 S1      
327N/C              U25   -K1         A01X+010811Y+037318X0160Y    R180 S1      
327N/C              U25   -H5         A01X+009551Y+036688X0160Y    R180 S1      
327N/C              U25   -J4         A01X+009866Y+037003X0160Y    R180 S1      
327N/C              U25   -D3         A01X+010181Y+035428X0160Y    R180 S1      
327N/C              U25   -D1         A01X+010811Y+035428X0160Y    R180 S1      
327N/C              U25   -B1         A01X+010811Y+034798X0160Y    R180 S1      
327N/C              U25   -C2         A01X+010496Y+035113X0160Y    R180 S1      
327N/C              U25   -E2         A01X+010496Y+035743X0160Y    R180 S1      
327N/C              U25   -E3         A01X+010181Y+035743X0160Y    R180 S1      
327N/C              U25   -C1         A01X+010811Y+035113X0160Y    R180 S1      
327N/C              U25   -D2         A01X+010496Y+035428X0160Y    R180 S1      
327N/C              U25   -E1         A01X+010811Y+035743X0160Y    R180 S1      
327N/C              U25   -F2         A01X+010496Y+036058X0160Y    R180 S1      
327N/C              U25   -F4         A01X+009866Y+036058X0160Y    R180 S1      
327N/C              U25   -G6         A01X+009236Y+036373X0160Y    R180 S1      
327N/C              U25   -F3         A01X+010181Y+036058X0160Y    R180 S1      
327N/C              U25   -F1         A01X+010811Y+036058X0160Y    R180 S1      
327N/C              U25   -G5         A01X+009551Y+036373X0160Y    R180 S1      
327N/C              U25   -G4         A01X+009866Y+036373X0160Y    R180 S1      
327N/C              U25   -G2         A01X+010496Y+036373X0160Y    R180 S1      
327N/C              U25   -G3         A01X+010181Y+036373X0160Y    R180 S1      
327N/C              U25   -F5         A01X+009551Y+036058X0160Y    R180 S1      
327N/C              U25   -H6         A01X+009236Y+036688X0160Y    R180 S1      
327N/C              U25   -A2         A01X+010496Y+034483X0160Y    R180 S1      
327N/C              U13   -1          A01X+005182Y+042121X0160Y0200R090 S1      
327N/C              Q9    -3          A01X+012526Y+003934X0170Y0200R090 S1      
327N/C              Q9    -5          A01X+013274Y+004190X0170Y0200R090 S1      
327N/C              Q9    -4          A01X+013274Y+003934X0170Y0200R090 S1      
327N/C              U22   -TH         A12X+016311Y+036417X0360Y1150R270 S2      
327N/C                    -           A01X+001210Y+043879X0390Y         S1      
327N/C                    -           A01X+031080Y+004200X0390Y         S1      
327N/C                    -           A01X+010400Y+015760X0390Y         S1      
327N/C                    -           A01X+026960Y+033770X0390Y         S1      
327N/C                    -           A12X+013740Y+032380X0390Y         S2      
327N/C                    -           A01X+001047Y+007150X0390Y         S1      
327N/C                    -           A01X+032320Y+045150X0390Y         S1      
327N/C                    -           A12X+003150Y+044350X0390Y         S2      
327N/C                    -           A12X+029700Y+027050X0390Y         S2      
317N/C              H2B1  -1    D1250UA00X+034064Y+043281X1250Y    R090 S3      
317N/C              H2B2  -1    D1250UA00X+002730Y+006820X1250Y    R090 S3      
327N/C              U44   -1          A01X+006625Y+016388X0160Y0360     S1      
327N/C              DM3   -1          A01X-001650Y+054450X0300Y         S1      
317N/C              SW7   -H1   D0360UA00X+030906Y+001846X0360Y         S3      
317N/C              SW7   -H2   D0360UA00X+033662Y+001846X0360Y         S3      
327N/C              J4    -73         A01X+013976Y+031854X0110Y0630     S1      
327N/C              J4    -70         A01X+013681Y+028882X0110Y0630     S1      
327N/C              J4    -68         A01X+013484Y+028882X0110Y0630     S1      
327N/C              J4    -64         A01X+013091Y+028882X0110Y0630     S1      
327N/C              J4    -62         A01X+012894Y+028882X0110Y0630     S1      
327N/C              J4    -60         A01X+012697Y+028882X0110Y0630     S1      
327N/C              J4    -6          A01X+007382Y+028882X0110Y0630     S1      
327N/C              J4    -53         A01X+012008Y+031854X0110Y0630     S1      
327N/C              J4    -50         A01X+011713Y+028882X0110Y0630     S1      
327N/C              J4    -49         A01X+011614Y+031854X0110Y0630     S1      
327N/C              J4    -48         A01X+011516Y+028882X0110Y0630     S1      
327N/C              J4    -47         A01X+011417Y+031854X0110Y0630     S1      
327N/C              J4    -44         A01X+011122Y+028882X0110Y0630     S1      
327N/C              J4    -43         A01X+011024Y+031854X0110Y0630     S1      
327N/C              J4    -41         A01X+010827Y+031854X0110Y0630     S1      
327N/C              J4    -38         A01X+010532Y+028882X0110Y0630     S1      
327N/C              J4    -34         A01X+010138Y+028882X0110Y0630     S1      
327N/C              J4    -32         A01X+009941Y+028882X0110Y0630     S1      
327N/C              J4    -22         A01X+008957Y+028882X0110Y0630     S1      
327N/C              J4    -20         A01X+008760Y+028882X0110Y0630     S1      
327N/C              J4    -17         A01X+008465Y+031854X0110Y0630     S1      
317N/C              J4    -H1   D0480UA00X+006594Y+029778X0480Y    R090 S3      
317N/C              J4    -H2   D0670UA00X+014468Y+029778X0670Y    R090 S3      
317N/C              H2    -1    D1260UA00X+010532Y+018657X2520Y3150     S3      
317N/C              SW8   -H1   D0360UA00X+026417Y+002004X0360Y         S3      
317N/C              SW8   -H2   D0360UA00X+029173Y+002004X0360Y         S3      
317N/C              SW6   -H1   D0360UA00X+001772Y+001846X0360Y         S3      
317N/C              SW6   -H2   D0360UA00X+004528Y+001846X0360Y         S3      
C                                                                               
C  ****************************************                                     
C      TOOLING HOLE PINS ON THE BOARD                                           
C  ****************************************                                     
C                                                                               
367                       -     D0410UA00X+038266Y+037375X0410Y    R180 S3      
367                       -     D0410UA00X+037266Y+037375X0410Y    R180 S3      
367                       -     D0410UA00X+038266Y+039875X0410Y    R180 S3      
367                       -     D0410UA00X+037266Y+039875X0410Y    R180 S3      
367                       -     D0410UA00X+039375Y+027205X0410Y         S3      
367                       -     D0410UA00X+040375Y+027205X0410Y         S3      
367                       -     D0410UA00X+039375Y+024705X0410Y         S3      
367                       -     D0410UA00X+040375Y+024705X0410Y         S3      
367                       -     D0410UA00X+039375Y+020054X0410Y    R180 S3      
367                       -     D0410UA00X+040375Y+020054X0410Y    R180 S3      
367                       -     D0410UA00X+039375Y+022554X0410Y    R180 S3      
367                       -     D0410UA00X+040375Y+022554X0410Y    R180 S3      
367                       -     D0410UA00X+040369Y-045638X0410Y         S3      
367                       -     D0410UA00X+039369Y-045638X0410Y         S3      
367                       -     D0410UA00X+040369Y-048138X0410Y         S3      
367                       -     D0410UA00X+039369Y-048138X0410Y         S3      
367                       -     D0410UA00X+038260Y-043031X0410Y         S3      
367                       -     D0410UA00X+037260Y-043031X0410Y         S3      
367                       -     D0410UA00X+038260Y-045531X0410Y         S3      
367                       -     D0410UA00X+037260Y-045531X0410Y         S3      
367                       -     D0410UA00X+039378Y-012885X0410Y    R180 S3      
367                       -     D0410UA00X+040378Y-012885X0410Y    R180 S3      
367                       -     D0410UA00X+039378Y-010385X0410Y    R180 S3      
367                       -     D0410UA00X+040378Y-010385X0410Y    R180 S3      
367                       -     D0410UA00X+040375Y-005722X0410Y         S3      
367                       -     D0410UA00X+039375Y-005722X0410Y         S3      
367                       -     D0410UA00X+040375Y-008222X0410Y         S3      
367                       -     D0410UA00X+039375Y-008222X0410Y         S3      
367                       -     D0410UA00X+037260Y+007623X0410Y         S3      
367                       -     D0410UA00X+038260Y+007623X0410Y         S3      
367                       -     D0410UA00X+037260Y+005123X0410Y         S3      
367                       -     D0410UA00X+038260Y+005123X0410Y         S3      
367                       -     D0410UA00X+040375Y-005722X0410Y         S3      
367                       -     D0410UA00X+041375Y-005722X0410Y         S3      
367                       -     D0410UA00X+040375Y-008222X0410Y         S3      
367                       -     D0410UA00X+041375Y-008222X0410Y         S3      
367                       -     D0410UA00X+038266Y+000448X0410Y    R180 S3      
367                       -     D0410UA00X+037266Y+000448X0410Y    R180 S3      
367                       -     D0410UA00X+038266Y+002948X0410Y    R180 S3      
367                       -     D0410UA00X+037266Y+002948X0410Y    R180 S3      
367                       -     D0410UA00X+040375Y+039881X0410Y    R180 S3      
367                       -     D0410UA00X+041375Y+039881X0410Y    R180 S3      
367                       -     D0410UA00X+040375Y+042381X0410Y    R180 S3      
367                       -     D0410UA00X+041375Y+042381X0410Y    R180 S3      
367                       -     D0410UA00X+041375Y+020054X0410Y    R180 S3      
367                       -     D0410UA00X+040375Y+020054X0410Y    R180 S3      
367                       -     D0410UA00X+041375Y+022554X0410Y    R180 S3      
367                       -     D0410UA00X+040375Y+022554X0410Y    R180 S3      
367                       -     D0410UA00X+041375Y+027205X0410Y         S3      
367                       -     D0410UA00X+040375Y+027205X0410Y         S3      
367                       -     D0410UA00X+041375Y+024705X0410Y         S3      
367                       -     D0410UA00X+040375Y+024705X0410Y         S3      
367                       -     D0410UA00X+037266Y-022379X0410Y    R180 S3      
367                       -     D0410UA00X+038266Y-022379X0410Y    R180 S3      
367                       -     D0410UA00X+037266Y-019879X0410Y    R180 S3      
367                       -     D0410UA00X+038266Y-019879X0410Y    R180 S3      
367                       -     D0410UA00X+040375Y+039881X0410Y    R180 S3      
367                       -     D0410UA00X+039375Y+039881X0410Y    R180 S3      
367                       -     D0410UA00X+040375Y+042381X0410Y    R180 S3      
367                       -     D0410UA00X+039375Y+042381X0410Y    R180 S3      
367                       -     D0410UA00X+037258Y-015204X0410Y         S3      
367                       -     D0410UA00X+038258Y-015204X0410Y         S3      
367                       -     D0410UA00X+037258Y-017704X0410Y         S3      
367                       -     D0410UA00X+038258Y-017704X0410Y         S3      
C                                                                               
C  End-of-Job                                                                   
C                                                                               
999                                                                             
